(kicad_pcb
	(version 20241229)
	(generator "pcbnew")
	(generator_version "9.0")
	(general
		(thickness 1.62)
		(legacy_teardrops no)
	)
	(paper "A4")
	(title_block
		(title "OCuLink to 10GbE adapter")
		(date "2026-02-23")
		(rev "1.1.0")
		(company "Antmicro Ltd")
		(comment 1 "www.antmicro.com")
	)
	(layers
		(0 "F.Cu" signal)
		(4 "In1.Cu" signal)
		(6 "In2.Cu" signal)
		(8 "In3.Cu" signal)
		(10 "In4.Cu" signal)
		(12 "In5.Cu" signal)
		(14 "In6.Cu" signal)
		(2 "B.Cu" signal)
		(9 "F.Adhes" user "F.Adhesive")
		(11 "B.Adhes" user "B.Adhesive")
		(13 "F.Paste" user)
		(15 "B.Paste" user)
		(5 "F.SilkS" user "F.Silkscreen")
		(7 "B.SilkS" user "B.Silkscreen")
		(1 "F.Mask" user)
		(3 "B.Mask" user)
		(17 "Dwgs.User" user "User.Drawings")
		(19 "Cmts.User" user "User.Comments")
		(21 "Eco1.User" user "User.Eco1")
		(23 "Eco2.User" user "User.Eco2")
		(25 "Edge.Cuts" user)
		(27 "Margin" user)
		(31 "F.CrtYd" user "F.Courtyard")
		(29 "B.CrtYd" user "B.Courtyard")
		(35 "F.Fab" user)
		(33 "B.Fab" user)
	)
	(setup
		(stackup
			(layer "F.SilkS"
				(type "Top Silk Screen")
				(color "White")
			)
			(layer "F.Paste"
				(type "Top Solder Paste")
			)
			(layer "F.Mask"
				(type "Top Solder Mask")
				(color "Black")
				(thickness 0.01)
			)
			(layer "F.Cu"
				(type "copper")
				(thickness 0.035)
			)
			(layer "dielectric 1"
				(type "prepreg")
				(thickness 0.12)
				(material "PR2116")
				(epsilon_r 4.2)
				(loss_tangent 0.02)
			)
			(layer "In1.Cu"
				(type "copper")
				(thickness 0.035)
			)
			(layer "dielectric 2"
				(type "core")
				(thickness 0.2)
				(material "FR4-Improved")
				(epsilon_r 4.3)
				(loss_tangent 0.02)
			)
			(layer "In2.Cu"
				(type "copper")
				(thickness 0.035)
			)
			(layer "dielectric 3"
				(type "prepreg")
				(thickness 0.12)
				(material "PR2116")
				(epsilon_r 4.2)
				(loss_tangent 0.02) addsublayer
				(thickness 0.12)
				(material "PR2116")
				(epsilon_r 4.2)
				(loss_tangent 0.02)
			)
			(layer "In3.Cu"
				(type "copper")
				(thickness 0.035)
			)
			(layer "dielectric 4"
				(type "core")
				(thickness 0.2)
				(material "FR4-Improved")
				(epsilon_r 4.3)
				(loss_tangent 0.02)
			)
			(layer "In4.Cu"
				(type "copper")
				(thickness 0.035)
			)
			(layer "dielectric 5"
				(type "prepreg")
				(thickness 0.12)
				(material "PR2116")
				(epsilon_r 4.2)
				(loss_tangent 0.02) addsublayer
				(thickness 0.12)
				(material "PR2116")
				(epsilon_r 4.2)
				(loss_tangent 0.02)
			)
			(layer "In5.Cu"
				(type "copper")
				(thickness 0.035)
			)
			(layer "dielectric 6"
				(type "core")
				(thickness 0.2)
				(material "FR4-Improved")
				(epsilon_r 4.3)
				(loss_tangent 0.02)
			)
			(layer "In6.Cu"
				(type "copper")
				(thickness 0.035)
			)
			(layer "dielectric 7"
				(type "prepreg")
				(thickness 0.12)
				(material "PR2116")
				(epsilon_r 4.2)
				(loss_tangent 0.02)
			)
			(layer "B.Cu"
				(type "copper")
				(thickness 0.035)
			)
			(layer "B.Mask"
				(type "Bottom Solder Mask")
				(color "Black")
				(thickness 0.01)
			)
			(layer "B.Paste"
				(type "Bottom Solder Paste")
			)
			(layer "B.SilkS"
				(type "Bottom Silk Screen")
				(color "White")
			)
			(copper_finish "None")
			(dielectric_constraints yes)
		)
		(pad_to_mask_clearance 0)
		(allow_soldermask_bridges_in_footprints no)
		(tenting front back)
		(aux_axis_origin 50 150)
		(grid_origin 50 150)
		(pcbplotparams
			(layerselection 0x00000000_00000000_55555555_5755f5ff)
			(plot_on_all_layers_selection 0x00000000_00000000_00000000_00000000)
			(disableapertmacros no)
			(usegerberextensions no)
			(usegerberattributes yes)
			(usegerberadvancedattributes yes)
			(creategerberjobfile yes)
			(dashed_line_dash_ratio 12.000000)
			(dashed_line_gap_ratio 3.000000)
			(svgprecision 4)
			(plotframeref no)
			(mode 1)
			(useauxorigin no)
			(hpglpennumber 1)
			(hpglpenspeed 20)
			(hpglpendiameter 15.000000)
			(pdf_front_fp_property_popups yes)
			(pdf_back_fp_property_popups yes)
			(pdf_metadata yes)
			(pdf_single_document no)
			(dxfpolygonmode yes)
			(dxfimperialunits yes)
			(dxfusepcbnewfont yes)
			(psnegative no)
			(psa4output no)
			(plot_black_and_white yes)
			(sketchpadsonfab no)
			(plotpadnumbers no)
			(hidednponfab no)
			(sketchdnponfab yes)
			(crossoutdnponfab yes)
			(subtractmaskfromsilk no)
			(outputformat 1)
			(mirror no)
			(drillshape 1)
			(scaleselection 1)
			(outputdirectory "")
		)
	)
	(net 0 "")
	(net 1 "VCCA")
	(net 2 "/X710-AT2 PCIe/RSENSE")
	(net 3 "/X710-AT2 PCIe/RBIAS")
	(net 4 "/X710-AT2 PCIe/PCIe_JTAG.JTMS")
	(net 5 "P0_AVDDL")
	(net 6 "DVDD")
	(net 7 "+3V3")
	(net 8 "/X710-AT2 PCIe/PCIe_JTAG.JTDO")
	(net 9 "VCCD")
	(net 10 "AVDDH")
	(net 11 "/X710-AT2 PCIe/PCIe_JTAG.JTDI")
	(net 12 "XFI_VDD")
	(net 13 "/OCuLink/PCIe_{x4}.TX0+")
	(net 14 "P1_AVDDL")
	(net 15 "/X710-AT2 PCIe/PCIe_JTAG.~{JRST}")
	(net 16 "/X710-AT2 PCIe/PCIe_JTAG.JTCK")
	(net 17 "/OCuLink/PCIe_{x4}.TX0-")
	(net 18 "+1V88")
	(net 19 "/OCuLink/PCIe_{x4}.TX1+")
	(net 20 "/OCuLink/PCIe_{x4}.TX1-")
	(net 21 "/OCuLink/PCIe_{x4}.TX2+")
	(net 22 "/OCuLink/PCIe_{x4}.TX2-")
	(net 23 "XGB_AVDDH")
	(net 24 "XFI_PVDD")
	(net 25 "/OCuLink/PCIe_{x4}.TX3+")
	(net 26 "/OCuLink/PCIe_{x4}.TX3-")
	(net 27 "PLL_VDD")
	(net 28 "GND")
	(net 29 "/X710-AT2 10GbE/25MHZ_OSC.+")
	(net 30 "/X710-AT2 10GbE/25MHZ_OSC_AC.+")
	(net 31 "/X710-AT2 10GbE/25MHZ_OSC.-")
	(net 32 "/X710-AT2 PCIe/PCIe_{x4}_AC.TX0+")
	(net 33 "/X710-AT2 PCIe/PCIe_{x4}_AC.TX0-")
	(net 34 "/OCuLink/PCIe_{x4}.RX1-")
	(net 35 "/X710-AT2 PCIe/PCIe_{x4}_AC.TX1+")
	(net 36 "/OCuLink/PCIe_{x4}.RX0-")
	(net 37 "/OCuLink/PCIe_{x4}.RX1+")
	(net 38 "/X710-AT2 PCIe/PCIe_{x4}_AC.TX1-")
	(net 39 "/OCuLink/PCIe_{x4}.RX0+")
	(net 40 "/X710-AT2 PCIe/PCIe_{x4}_AC.TX2+")
	(net 41 "/X710-AT2 PCIe/PCIe_{x4}_AC.TX2-")
	(net 42 "/OCuLink/REFCLK.+")
	(net 43 "Net-(C37-Pad2)")
	(net 44 "/X710-AT2 PCIe/PCIe_{x4}_AC.TX3+")
	(net 45 "/OCuLink/REFCLK.-")
	(net 46 "/X710-AT2 PCIe/PCIe_{x4}_AC.TX3-")
	(net 47 "/X710-AT2 Misc/POR_BYPASS")
	(net 48 "/2xRJ45/Ethernet_P0.D2-")
	(net 49 "/2xRJ45/Ethernet_P0.D1-")
	(net 50 "/2xRJ45/Ethernet_P0.D3-")
	(net 51 "/2xRJ45/Ethernet_P0.D2+")
	(net 52 "Net-(J3-LED_YG_Y-)")
	(net 53 "Net-(J3-LED_YG_G-)")
	(net 54 "Net-(J3-LED_GRN-)")
	(net 55 "/2xRJ45/Ethernet_P0.D4+")
	(net 56 "/2xRJ45/Ethernet_P0.D1+")
	(net 57 "/2xRJ45/Ethernet_P0.D4-")
	(net 58 "/2xRJ45/Ethernet_P0.D3+")
	(net 59 "/2xRJ45/Ethernet_P1.D1-")
	(net 60 "/2xRJ45/Ethernet_P1.D2-")
	(net 61 "Net-(J6-LED_YG_Y-)")
	(net 62 "/2xRJ45/Ethernet_P1.D2+")
	(net 63 "/2xRJ45/Ethernet_P1.D3+")
	(net 64 "Net-(J6-LED_YG_G-)")
	(net 65 "/2xRJ45/Ethernet_P1.D3-")
	(net 66 "Net-(J6-LED_GRN-)")
	(net 67 "/2xRJ45/Ethernet_P1.D4+")
	(net 68 "/2xRJ45/Ethernet_P1.D4-")
	(net 69 "/2xRJ45/Ethernet_P1.D1+")
	(net 70 "Net-(D2-A)")
	(net 71 "/Flash memory/~{HOLD}")
	(net 72 "/Flash memory/~{WP}")
	(net 73 "/X710-AT2 10GbE/25MHZ_OSC_AC.-")
	(net 74 "/X710-AT2 10GbE/3V3_OSC")
	(net 75 "Net-(D3-A)")
	(net 76 "/X710-AT2 Misc/50MHZ_XTAL_R.+")
	(net 77 "/X710-AT2 Misc/50MHZ_XTAL_R.-")
	(net 78 "Net-(U10-VCC)")
	(net 79 "Net-(D11-A)")
	(net 80 "/OCuLink/PCIe_{x4}.RX2+")
	(net 81 "/2xRJ45/~{P0_LED_LINK_10G}")
	(net 82 "/2xRJ45/~{P0_LED_ACT}")
	(net 83 "/X710-AT2 10GbE/RESCAL_RES_P")
	(net 84 "/X710-AT2 10GbE/BIAS_RDAC")
	(net 85 "/X710-AT2 10GbE/OSC_SEL")
	(net 86 "/2xRJ45/~{P1_LINK_LESS_THAN_10G}")
	(net 87 "/2xRJ45/~{P1_LED_LINK_10G}")
	(net 88 "/2xRJ45/~{P1_LED_ACT}")
	(net 89 "Net-(D11-C)")
	(net 90 "+3V3_AUX")
	(net 91 "unconnected-(J10-Pad7)")
	(net 92 "unconnected-(J2-D_{B}--PadB7)")
	(net 93 "unconnected-(J2-SBU_{1}-PadA8)")
	(net 94 "/X710-AT2 10GbE/MDC3_SCL3")
	(net 95 "/X710-AT2 10GbE/MDIO3_SDA3")
	(net 96 "/X710-AT2 10GbE/MDC2_SCL2")
	(net 97 "/X710-AT2 Misc/~{SMBALRT}")
	(net 98 "/OCuLink/PCIe_{x4}.RX3+")
	(net 99 "/X710-AT2 Misc/LAN_PWR_GOOD")
	(net 100 "/X710-AT2 Misc/AUX_PWR")
	(net 101 "/X710-AT2 10GbE/MDIO2_SDA2")
	(net 102 "/X710-AT2 10GbE/MDC1_SCL1")
	(net 103 "/X710-AT2 10GbE/MDIO1_SDA1")
	(net 104 "/OCuLink/PCIe_{x4}.RX2-")
	(net 105 "/Flash memory/FLASH.~{CE}")
	(net 106 "/Flash memory/FLASH.CLK")
	(net 107 "/X710-AT2 Misc/FLSH_SCK")
	(net 108 "/X710-AT2 Misc/GPIO5_POR_BYPASS")
	(net 109 "/OCuLink/PCIe_{x4}.RX3-")
	(net 110 "/Flash memory/+3V3_FLASH")
	(net 111 "unconnected-(J10-Pad10)")
	(net 112 "/X710-AT2 Misc/RSVDL33")
	(net 113 "/X710-AT2 Misc/RSVDK40_1P88V")
	(net 114 "/X710-AT2 RSVD/DEBUG_EN")
	(net 115 "/X710-AT2 Misc/RSVD_J11_VSS")
	(net 116 "/X710-AT2 Misc/~{PHY_TRST}")
	(net 117 "unconnected-(D6-Pad1)")
	(net 118 "unconnected-(D6-Pad1)_1")
	(net 119 "/X710-AT2 RSVD/DEBUG_Y20")
	(net 120 "/X710-AT2 RSVD/DEBUG_W7")
	(net 121 "/X710-AT2 RSVD/DEBUG_Y16")
	(net 122 "/X710-AT2 RSVD/RSVDY24_VSS")
	(net 123 "/X710-AT2 RSVD/RSVDY22_VSS")
	(net 124 "/X710-AT2 RSVD/RSVDW5_VSS")
	(net 125 "/X710-AT2 RSVD/RSVDN9_VSS")
	(net 126 "/X710-AT2 RSVD/RSVDW1_VSS")
	(net 127 "/X710-AT2 RSVD/RSVDP22_VSS")
	(net 128 "/X710-AT2 RSVD/RSVDY18_VSS")
	(net 129 "/X710-AT2 RSVD/RSVDP8_VSS")
	(net 130 "/X710-AT2 10GbE/MDC0_SCL0")
	(net 131 "/X710-AT2 RSVD/RSVDD8_1P88V")
	(net 132 "/X710-AT2 10GbE/MDIO0_SDA0")
	(net 133 "/X710-AT2 Misc/MAIN_PWR_OK")
	(net 134 "/X710-AT2 Misc/PHY_TCK")
	(net 135 "/X710-AT2 Misc/PHY_TMS")
	(net 136 "/X710-AT2 Misc/PHY_TDI")
	(net 137 "/X710-AT2 Misc/PHY_TDO")
	(net 138 "unconnected-(J2-D_{B}+-PadB6)")
	(net 139 "/Flash memory/FLASH.MOSI")
	(net 140 "/Flash memory/FLASH.MISO")
	(net 141 "/X710-AT2 10GbE/~{PHY_RESET_3V3_R}")
	(net 142 "/X710-AT2 10GbE/~{P0_INT}")
	(net 143 "/X710-AT2 10GbE/25MHZ_OSC_R.+")
	(net 144 "unconnected-(J2-D_{A}--PadA7)")
	(net 145 "unconnected-(J2-SBU_{2}-PadB8)")
	(net 146 "unconnected-(J2-D_{A}+-PadA6)")
	(net 147 "unconnected-(J7-Pad1)")
	(net 148 "unconnected-(J7-Pad7)")
	(net 149 "/X710-AT2 10GbE/EN_OSC")
	(net 150 "/X710-AT2 10GbE/25MHZ_OSC_R.-")
	(net 151 "unconnected-(J9-NC-PadB9)")
	(net 152 "unconnected-(J9-5V-PadA21)")
	(net 153 "/X710-AT2 Misc/50MHZ_XTAL.+")
	(net 154 "unconnected-(J9-5V-PadA21)_1")
	(net 155 "Net-(U9H-SVR_IND)")
	(net 156 "Net-(Q3-G)")
	(net 157 "Net-(U7-A_{2})")
	(net 158 "Net-(U7-B_{2})")
	(net 159 "Net-(U9D-NCSI_ARB_OUT)")
	(net 160 "Net-(U9D-NCSI_CRS_DV)")
	(net 161 "Net-(U9D-NCSI_RXD_0)")
	(net 162 "Net-(U9D-NCSI_RXD_1)")
	(net 163 "unconnected-(U9E-RSVDT28_NC-PadT28)")
	(net 164 "unconnected-(U9A-PET_7_N-PadAD40)")
	(net 165 "unconnected-(U9C-SDP3_1-PadN7)")
	(net 166 "unconnected-(U9F-P0_PTP_SYNC0-PadN39)")
	(net 167 "unconnected-(U9G-RSVDU35_NC-PadU35)")
	(net 168 "unconnected-(U9F-RSVDL35_NC-PadL35)")
	(net 169 "unconnected-(U9G-RSVDL29_NC-PadL29)")
	(net 170 "unconnected-(U9B-SER0_RX_P-PadB14)")
	(net 171 "unconnected-(U9E-RSVDT22_NC-PadT22)")
	(net 172 "unconnected-(U9C-SDP3_0-PadN5)")
	(net 173 "unconnected-(U9G-RSVDU31_NC-PadU31)")
	(net 174 "unconnected-(U9C-SDP2_1-PadJ7)")
	(net 175 "unconnected-(U9G-RSVDA41_NC-PadA41)")
	(net 176 "unconnected-(U9C-SDP3_2-PadM6)")
	(net 177 "unconnected-(U9F-XTAL_PTP_XTAL_P-PadJ41)")
	(net 178 "unconnected-(U9B-SER0_RX_N-PadA13)")
	(net 179 "unconnected-(U9E-RSVDW27_NC-PadW27)")
	(net 180 "unconnected-(U9E-RSVDR9_NC-PadR9)")
	(net 181 "unconnected-(U9E-RSVDV22_NC-PadV22)")
	(net 182 "unconnected-(U9F-P0_PTP_SYNC1-PadN41)")
	(net 183 "unconnected-(U9G-RSVDV32_NC-PadV32)")
	(net 184 "unconnected-(U9E-RSVDU29_NC-PadU29)")
	(net 185 "unconnected-(U9F-SYNCE_LOCK_2-PadE11)")
	(net 186 "unconnected-(U9E-RSVDR27_NC-PadR27)")
	(net 187 "unconnected-(U9F-RSVDR37_NC-PadR37)")
	(net 188 "unconnected-(U9E-RSVDK24_NC-PadK24)")
	(net 189 "unconnected-(U9F-P1_PTP_SYNC0-PadH10)")
	(net 190 "unconnected-(U9G-RSVDT30_NC-PadT30)")
	(net 191 "/X710-AT2 Misc/50MHZ_XTAL.-")
	(net 192 "unconnected-(U9B-SER0_TX_P-PadA17)")
	(net 193 "unconnected-(U9E-RSVDU9_NC-PadU9)")
	(net 194 "unconnected-(U9E-RSVDW25_NC-PadW25)")
	(net 195 "unconnected-(U9G-RSVDC21_NC-PadC21)")
	(net 196 "unconnected-(U9F-RSVDM36_NC-PadM36)")
	(net 197 "unconnected-(U9D-GPIO_1-PadW41)")
	(net 198 "/X710-AT2 10GbE/~{P0_INT_R}")
	(net 199 "unconnected-(U9C-SDP3_3-PadM8)")
	(net 200 "unconnected-(U9G-RSVDK34_NC-PadK34)")
	(net 201 "unconnected-(U9E-RSVDT26_NC-PadT26)")
	(net 202 "unconnected-(U9A-PER_7_N-PadAA39)")
	(net 203 "unconnected-(U9F-RSVDN35_NC-PadN35)")
	(net 204 "unconnected-(U9E-RSVDT24_NC-PadT24)")
	(net 205 "unconnected-(U9E-RSVDL23_NC-PadL23)")
	(net 206 "unconnected-(U9E-RSVDW23_NC-PadW23)")
	(net 207 "unconnected-(U9F-SYNCE_CLKOUT_0-PadG9)")
	(net 208 "unconnected-(U9F-RSVDM34_NC-PadM34)")
	(net 209 "unconnected-(U9F-SYNCE_CLKOUT_3-PadE13)")
	(net 210 "unconnected-(U9H-RSVDV8_NC-PadV8)")
	(net 211 "unconnected-(U9C-SDP2_0-PadF6)")
	(net 212 "unconnected-(U9D-GPIO_4-PadH8)")
	(net 213 "unconnected-(U9C-SDP0_3-PadL5)")
	(net 214 "unconnected-(U9A-PET_4_P-PadAD26)")
	(net 215 "/X710-AT2 10GbE/MDIO0_I2C0.MDIO")
	(net 216 "unconnected-(U9E-RSVDP26_NC-PadP26)")
	(net 217 "unconnected-(U9E-RSVDV28_NC-PadV28)")
	(net 218 "unconnected-(U9F-SYNCE_LOCK_3-PadF12)")
	(net 219 "unconnected-(U9G-RSVDM32_NC-PadM32)")
	(net 220 "unconnected-(U9F-RSVDR33_NC-PadR33)")
	(net 221 "unconnected-(U9E-RSVDL25_NC-PadL25)")
	(net 222 "unconnected-(U9E-RSVDU23_NC-PadU23)")
	(net 223 "unconnected-(U9F-RSVDG13_NC-PadG13)")
	(net 224 "unconnected-(U9F-RSVDG15_NC-PadG15)")
	(net 225 "unconnected-(U9C-SDP1_2-PadP6)")
	(net 226 "/OCuLink/SDA")
	(net 227 "unconnected-(U9F-RSVDH14_NC-PadH14)")
	(net 228 "unconnected-(U9G-RSVDP30_NC-PadP30)")
	(net 229 "unconnected-(U9E-RSVDM26_NC-PadM26)")
	(net 230 "unconnected-(U9F-RSVDK30_NC-PadK30)")
	(net 231 "unconnected-(U9C-LED3_0-PadR3)")
	(net 232 "unconnected-(U9G-RSVDU33_NC-PadU33)")
	(net 233 "unconnected-(U9E-RSVDV24_NC-PadV24)")
	(net 234 "unconnected-(U9G-RSVDJ39_NC-PadJ39)")
	(net 235 "unconnected-(U9B-SER1_TX_N-PadB10)")
	(net 236 "unconnected-(U9E-RSVDJ25_NC-PadJ25)")
	(net 237 "unconnected-(U9F-RSVDP36_NC-PadP36)")
	(net 238 "unconnected-(U9F-SYNCE_LOCK_0-PadF8)")
	(net 239 "unconnected-(U9E-RSVDJ23_NC-PadJ23)")
	(net 240 "unconnected-(U9H-RSVDV10_NC-PadV10)")
	(net 241 "unconnected-(U9C-LED1_0-PadU5)")
	(net 242 "unconnected-(U9F-RSVDH16_NC-PadH16)")
	(net 243 "unconnected-(U9A-PET_6_P-PadAC35)")
	(net 244 "unconnected-(U9A-PER_4_P-PadAA27)")
	(net 245 "unconnected-(U9A-PET_6_N-PadAD36)")
	(net 246 "unconnected-(U9G-RSVDK28_NC-PadK28)")
	(net 247 "unconnected-(U9A-PER_6_N-PadAA35)")
	(net 248 "unconnected-(U9G-RSVDN29_NC-PadN29)")
	(net 249 "unconnected-(U9F-RSVDJ15_NC-PadJ15)")
	(net 250 "unconnected-(U9G-RSVDD20_NC-PadD20)")
	(net 251 "unconnected-(U9E-RSVDN25_NC-PadN25)")
	(net 252 "unconnected-(U9A-PET_5_P-PadAC31)")
	(net 253 "unconnected-(U9G-RSVDB42_NC-PadB42)")
	(net 254 "unconnected-(U9F-SYNCE_CLKOUT_2-PadG11)")
	(net 255 "/Power/+3V3_OUT")
	(net 256 "unconnected-(U9C-SDP2_2-PadE7)")
	(net 257 "unconnected-(U9G-RSVDV34_NC-PadV34)")
	(net 258 "unconnected-(U9F-SYNCE_CLKOUT_1-PadF10)")
	(net 259 "unconnected-(U9G-RSVDD32_NC-PadD32)")
	(net 260 "unconnected-(U9F-SYNCE_LOCK_1-PadE9)")
	(net 261 "unconnected-(U9E-RSVDU27_NC-PadU27)")
	(net 262 "unconnected-(U9G-RSVDP32_NC-PadP32)")
	(net 263 "unconnected-(U9D-GPIO_3-PadV42)")
	(net 264 "unconnected-(U9E-RSVDM22_NC-PadM22)")
	(net 265 "unconnected-(U9B-SER1_TX_P-PadA9)")
	(net 266 "unconnected-(U9E-RSVDN27_NC-PadN27)")
	(net 267 "unconnected-(U9A-PER_5_N-PadAA31)")
	(net 268 "unconnected-(U9G-RSVDM30_NC-PadM30)")
	(net 269 "unconnected-(U9C-LED1_1-PadU7)")
	(net 270 "unconnected-(U9F-RSVDN33_NC-PadN33)")
	(net 271 "unconnected-(U9G-RSVDR29_NC-PadR29)")
	(net 272 "unconnected-(U9B-SER0_TX_N-PadB18)")
	(net 273 "unconnected-(U9A-PER_4_N-PadAB28)")
	(net 274 "unconnected-(U9A-PER_5_P-PadY30)")
	(net 275 "unconnected-(U9A-PET_4_N-PadAD28)")
	(net 276 "unconnected-(U9E-RSVDN23_NC-PadN23)")
	(net 277 "unconnected-(U9A-PER_6_P-PadY34)")
	(net 278 "unconnected-(U9E-RSVDR25_NC-PadR25)")
	(net 279 "unconnected-(U9E-RSVDM24_NC-PadM24)")
	(net 280 "unconnected-(U9E-RSVDU25_NC-PadU25)")
	(net 281 "unconnected-(U9E-RSVDL27_NC-PadL27)")
	(net 282 "unconnected-(U9B-SER1_RX_P-PadB6)")
	(net 283 "unconnected-(U9G-RSVDR31_NC-PadR31)")
	(net 284 "unconnected-(U9F-RSVDP34_NC-PadP34)")
	(net 285 "unconnected-(Y1-NC-Pad2)")
	(net 286 "/X710-AT2 10GbE/~{P1_INT_R}")
	(net 287 "/X710-AT2 10GbE/~{P1_INT}")
	(net 288 "/X710-AT2 10GbE/MDIO0_I2C0.MDC")
	(net 289 "/X710-AT2 Misc/~{PCI_DIS}")
	(net 290 "/X710-AT2 Misc/~{DEV_DIS}")
	(net 291 "/2xRJ45/~{P0_LINK_LESS_THAN_10G}")
	(net 292 "/X710-AT2 RSVD/RSVDE19_1P88V")
	(net 293 "/X710-AT2 10GbE/TPIN_3")
	(net 294 "/X710-AT2 10GbE/TPIN_5")
	(net 295 "/X710-AT2 Misc/XTAL_BYPASS")
	(net 296 "unconnected-(U9C-SDP1_3-PadH6)")
	(net 297 "unconnected-(U9G-RSVDT32_NC-PadT32)")
	(net 298 "unconnected-(U9E-RSVDR23_NC-PadR23)")
	(net 299 "/2xRJ45/P0_CT")
	(net 300 "/2xRJ45/P1_CT")
	(net 301 "+1V88_CT")
	(net 302 "+1V0")
	(net 303 "/Power/+VCCD_OUT")
	(net 304 "/OCuLink/SCL")
	(net 305 "unconnected-(U9G-RSVDK26_NC-PadK26)")
	(net 306 "unconnected-(U9G-RSVDV30_NC-PadV30)")
	(net 307 "unconnected-(U9A-PET_7_P-PadAC39)")
	(net 308 "/OCuLink/~{PE_RST}")
	(net 309 "/OCuLink/~{PE_WAKE}")
	(net 310 "/Power/+1V88_OUT")
	(net 311 "/Power/+DVDD_OUT")
	(net 312 "/Power/+1V0_OUT")
	(net 313 "unconnected-(U9E-RSVDK22_NC-PadK22)")
	(net 314 "VCC")
	(net 315 "/Power/3V3_VCC")
	(net 316 "/Power/3V3_BST")
	(net 317 "/Power/3V3_FB")
	(net 318 "/Power/VCCD_BST")
	(net 319 "/OCuLink/~{PE_ RST}_R")
	(net 320 "/OCuLink/~{CWAKE}_R")
	(net 321 "/OCuLink/~{CPRSNT}_R")
	(net 322 "/Power/VCCD_VCC")
	(net 323 "/Power/1V88_BST")
	(net 324 "/Power/1V88_VCC")
	(net 325 "/Power/DVDD_BST")
	(net 326 "/Power/DVDD_VCC")
	(net 327 "/Power/1V0_BST")
	(net 328 "/Power/1V0_VCC")
	(net 329 "/Power/VCCD_FB")
	(net 330 "/Power/1V88_FB")
	(net 331 "/Power/DVDD_FB")
	(net 332 "/Power/1V0_FB")
	(net 333 "/Power/3V3_SW")
	(net 334 "/Power/VCCD_SW")
	(net 335 "/Power/1V88_SW")
	(net 336 "/Power/DVDD_SW")
	(net 337 "/Power/1V0_SW")
	(net 338 "/Power/3V3_PG")
	(net 339 "unconnected-(U9E-RSVDP24_NC-PadP24)")
	(net 340 "/Power/VCCD_EN")
	(net 341 "/Power/1V0_PG")
	(net 342 "/Power/VCCD_PG")
	(net 343 "unconnected-(U9F-RSVDK32_NC-PadK32)")
	(net 344 "unconnected-(U9E-RSVDV26_NC-PadV26)")
	(net 345 "unconnected-(U9F-P1_PTP_SYNC1-PadH12)")
	(net 346 "unconnected-(U9F-XTAL_PTP_XTAL_N-PadH42)")
	(net 347 "unconnected-(U9C-SDP1_0-PadR7)")
	(net 348 "unconnected-(U9A-PET_5_N-PadAD32)")
	(net 349 "unconnected-(U9B-SER1_RX_N-PadA5)")
	(net 350 "/Power/+12V_IN")
	(net 351 "/Power/+5V_USB")
	(net 352 "unconnected-(U9G-RSVDK36_NC-PadK36)")
	(net 353 "/Power/1V88_EN")
	(net 354 "unconnected-(U9C-SDP1_1-PadP4)")
	(net 355 "unconnected-(U9E-RSVDM28_NC-PadM28)")
	(net 356 "/Power/CC2")
	(net 357 "/Power/CC1")
	(net 358 "unconnected-(U9C-LED3_1-PadR5)")
	(net 359 "unconnected-(U9A-PER_7_P-PadY38)")
	(net 360 "/X710-AT2 Misc/NCSI.RXD_1")
	(net 361 "/X710-AT2 Misc/NCSI.TXD_1")
	(net 362 "/X710-AT2 Misc/NCSI.RXD_0")
	(net 363 "/X710-AT2 Misc/NCSI.TXD_0")
	(net 364 "/X710-AT2 Misc/NCSI.ARB_OUT")
	(net 365 "/X710-AT2 Misc/NCSI.CRS_DV")
	(net 366 "/X710-AT2 Misc/NCSI.TX_EN")
	(net 367 "/X710-AT2 Misc/NCSI.REF_CLK")
	(net 368 "/X710-AT2 Misc/NCSI.ARB_IN")
	(net 369 "/Power/1V88_PG")
	(net 370 "unconnected-(U9E-RSVDP28_NC-PadP28)")
	(net 371 "unconnected-(U9C-SDP2_3-PadG7)")
	(net 372 "unconnected-(U9G-RSVDN31_NC-PadN31)")
	(net 373 "Net-(Q2-G)")
	(net 374 "unconnected-(U11-STAT-Pad4)")
	(net 375 "unconnected-(U12-STAT-Pad4)")
	(net 376 "/Power/DVDD_EN")
	(net 377 "/Power/1V0_EN")
	(net 378 "/Power/DVDD_PG")
	(net 379 "/Power/3V3_EN")
	(net 380 "/X710-AT2 10GbE/~{PHY_RESET_3V3}")
	(net 381 "/X710-AT2 Misc/MDIO.MDIO")
	(net 382 "/X710-AT2 Misc/MDIO.MDC")
	(net 383 "/X710-AT2 Misc/REFCLK_SEL")
	(net 384 "/X710-AT2 Misc/~{PHY_RESET}")
	(net 385 "/Fan controller/SENSE")
	(net 386 "Net-(U6-BYPASS)")
	(net 387 "/Fan controller/FREQ")
	(net 388 "/Fan controller/+5V")
	(net 389 "/Fan controller/V_{FAN}")
	(net 390 "/Fan controller/PWM")
	(net 391 "/Fan controller/TACH")
	(net 392 "/Power/ALL_RAILS_OK")
	(net 393 "/OCuLink/~{CPRSNT}")
	(net 394 "/OCuLink/SMBus.SCL")
	(net 395 "/OCuLink/SMBus.SDA")
	(net 396 "Net-(U10-A)")
	(net 397 "Net-(R175-Pad1)")
	(net 398 "/Fan controller/D0")
	(net 399 "/Fan controller/DMIN")
	(net 400 "/Fan controller/SLOPE")
	(net 401 "unconnected-(U10-NC-Pad1)")
	(net 402 "/X710-AT2 PCIe/CLK+")
	(net 403 "/X710-AT2 PCIe/CLK-")
	(net 404 "Net-(Y3-EN)")
	(net 405 "/X710-AT2 PCIe/GEN_F_CLK+")
	(net 406 "/X710-AT2 PCIe/GEN_F_CLK-")
	(net 407 "/X710-AT2 PCIe/GEN_CLK+")
	(net 408 "/X710-AT2 PCIe/GEN_CLK-")
	(net 409 "unconnected-(Y3-NC-Pad2)")
	(net 410 "Net-(D15-A)")
	(net 411 "Net-(D17-C)")
	(net 412 "Net-(D18-C)")
	(net 413 "Net-(D19-C)")
	(net 414 "Net-(D20-C)")
	(net 415 "Net-(D16-C)")
	(net 416 "Net-(Q5-C)")
	(net 417 "Net-(Q7-C)")
	(net 418 "Net-(Q8-C)")
	(net 419 "Net-(Q9-C)")
	(footprint "antmicro-footprints:R_0402_1005Metric"
		(layer "F.Cu")
		(at 97.4 105.2)
		(descr "Resistor SMD 0402")
		(tags "resistor SMD 0402")
		(property "Reference" "R7"
			(at -2.25 15.3 0)
			(layer "F.SilkS")
			(effects
				(font
					(size 0.7 0.7)
					(thickness 0.15)
				)
				(justify left bottom)
			)
		)
		(property "Value" "R_10k_0402"
			(at -1.011843 1.772046 0)
			(layer "F.Fab")
			(hide yes)
			(effects
				(font
					(size 0.7 0.7)
					(thickness 0.15)
				)
				(justify left bottom)
			)
		)
		(property "Datasheet" "https://www.bourns.com/docs/product-datasheets/cr.pdf"
			(at 0 0 0)
			(layer "F.Fab")
			(hide yes)
			(effects
				(font
					(size 1.27 1.27)
					(thickness 0.15)
				)
			)
		)
		(property "Description" "SMD Chip Resistor, 10 kohm, ± 1%, 62.5 mW, 0402 [1005 Metric], Thick Film, General Purpose"
			(at 0 0 0)
			(layer "F.Fab")
			(hide yes)
			(effects
				(font
					(size 1.27 1.27)
					(thickness 0.15)
				)
			)
		)
		(property "MPN" "CR0402-FX-1002GLF"
			(at 0 0 0)
			(unlocked yes)
			(layer "F.Fab")
			(hide yes)
			(effects
				(font
					(size 1 1)
					(thickness 0.15)
				)
			)
		)
		(property "Manufacturer" "Bourns"
			(at 0 0 0)
			(unlocked yes)
			(layer "F.Fab")
			(hide yes)
			(effects
				(font
					(size 1 1)
					(thickness 0.15)
				)
			)
		)
		(property "License" "Apache-2.0"
			(at 0 0 0)
			(unlocked yes)
			(layer "F.Fab")
			(hide yes)
			(effects
				(font
					(size 1 1)
					(thickness 0.15)
				)
			)
		)
		(property "Author" "Antmicro"
			(at 0 0 0)
			(unlocked yes)
			(layer "F.Fab")
			(hide yes)
			(effects
				(font
					(size 1 1)
					(thickness 0.15)
				)
			)
		)
		(property "Val" "10k"
			(at 0 0 0)
			(unlocked yes)
			(layer "F.Fab")
			(hide yes)
			(effects
				(font
					(size 1 1)
					(thickness 0.15)
				)
			)
		)
		(property "Tolerance" "1%"
			(at 0 0 0)
			(unlocked yes)
			(layer "F.Fab")
			(hide yes)
			(effects
				(font
					(size 1 1)
					(thickness 0.15)
				)
			)
		)
		(sheetname "/X710-AT2 Misc/")
		(sheetfile "x710-at2-mics.kicad_sch")
		(attr smd)
		(fp_rect
			(start -0.925 -0.47)
			(end 0.925 0.47)
			(stroke
				(width 0.05)
				(type default)
			)
			(fill no)
			(layer "F.CrtYd")
		)
		(fp_rect
			(start -0.5 -0.25)
			(end 0.5 0.25)
			(stroke
				(width 0.15)
				(type solid)
			)
			(fill no)
			(layer "F.Fab")
		)
		(pad "1" smd roundrect
			(at -0.48 0)
			(size 0.59 0.64)
			(layers "F.Cu" "F.Mask" "F.Paste")
			(roundrect_rratio 0.25)
			(net 133 "/X710-AT2 Misc/MAIN_PWR_OK")
			(pintype "passive")
		)
		(pad "2" smd roundrect
			(at 0.48 0)
			(size 0.59 0.64)
			(layers "F.Cu" "F.Mask" "F.Paste")
			(roundrect_rratio 0.25)
			(net 7 "+3V3")
			(pintype "passive")
		)
	)
	(footprint "antmicro-footprints:USON-10_2.5x1mm_P0.5mm"
		(layer "F.Cu")
		(at 103.248 59.985 -90)
		(descr "USON-10 2.5x1mm_ Pitch 0.5mm")
		(tags "USON-10 2.5x1mm Pitch 0.5mm")
		(property "Reference" "D5"
			(at 1.7 0.698 0)
			(layer "F.SilkS")
			(effects
				(font
					(size 0.7 0.7)
					(thickness 0.15)
				)
				(justify left bottom)
			)
		)
		(property "Value" "ESD204DQAR"
			(at 0.018 2.499 90)
			(layer "F.Fab")
			(hide yes)
			(effects
				(font
					(size 0.7 0.7)
					(thickness 0.15)
				)
				(justify right top)
			)
		)
		(property "Datasheet" "https://www.ti.com/lit/ds/symlink/esd204.pdf?ts=1706004844383&ref_url=https%253A%252F%252Fwww.ti.com%252Finterface%252Fdiodes%252Fesd-protection-diodes%252Fproducts.html"
			(at 0 0 90)
			(layer "F.Fab")
			(hide yes)
			(effects
				(font
					(size 1.27 1.27)
					(thickness 0.15)
				)
			)
		)
		(property "Description" "TVS diode array, 30 kV, USON-10, 3.6 V, 0.55 pF"
			(at 0 0 90)
			(layer "F.Fab")
			(hide yes)
			(effects
				(font
					(size 1.27 1.27)
					(thickness 0.15)
				)
			)
		)
		(property "MPN" "ESD204DQAR"
			(at 0 0 270)
			(unlocked yes)
			(layer "F.Fab")
			(hide yes)
			(effects
				(font
					(size 1 1)
					(thickness 0.15)
				)
			)
		)
		(property "Manufacturer" "Texas Instruments"
			(at 0 0 270)
			(unlocked yes)
			(layer "F.Fab")
			(hide yes)
			(effects
				(font
					(size 1 1)
					(thickness 0.15)
				)
			)
		)
		(property "Author" "Antmicro"
			(at 0 0 270)
			(unlocked yes)
			(layer "F.Fab")
			(hide yes)
			(effects
				(font
					(size 1 1)
					(thickness 0.15)
				)
			)
		)
		(property "License" "Apache-2.0"
			(at 0 0 270)
			(unlocked yes)
			(layer "F.Fab")
			(hide yes)
			(effects
				(font
					(size 1 1)
					(thickness 0.15)
				)
			)
		)
		(sheetname "/OCuLink/")
		(sheetfile "oculink.kicad_sch")
		(attr smd)
		(fp_line
			(start 0.498 1.398)
			(end -0.5 1.398)
			(stroke
				(width 0.15)
				(type solid)
			)
			(layer "F.SilkS")
		)
		(fp_line
			(start 0.498 -1.401)
			(end -0.5 -1.401)
			(stroke
				(width 0.15)
				(type solid)
			)
			(layer "F.SilkS")
		)
		(fp_circle
			(center -0.68 -1.27)
			(end -0.63 -1.27)
			(stroke
				(width 0.15)
				(type solid)
			)
			(fill yes)
			(layer "F.SilkS")
		)
		(fp_rect
			(start -0.8 -1.5)
			(end 0.8 1.499)
			(stroke
				(width 0.05)
				(type solid)
			)
			(fill no)
			(layer "F.CrtYd")
		)
		(fp_line
			(start -0.5 1.249)
			(end 0.498 1.249)
			(stroke
				(width 0.15)
				(type solid)
			)
			(layer "F.Fab")
		)
		(fp_line
			(start -0.5 -1)
			(end -0.5 1.249)
			(stroke
				(width 0.15)
				(type solid)
			)
			(layer "F.Fab")
		)
		(fp_line
			(start -0.25 -1.25)
			(end -0.5 -1)
			(stroke
				(width 0.15)
				(type solid)
			)
			(layer "F.Fab")
		)
		(fp_line
			(start 0.498 -1.25)
			(end 0.498 1.249)
			(stroke
				(width 0.15)
				(type solid)
			)
			(layer "F.Fab")
		)
		(fp_line
			(start 0.498 -1.25)
			(end -0.25 -1.25)
			(stroke
				(width 0.15)
				(type solid)
			)
			(layer "F.Fab")
		)
		(pad "1" smd roundrect
			(at -0.387 -1 180)
			(size 0.25 0.55)
			(layers "F.Cu" "F.Mask" "F.Paste")
			(roundrect_rratio 0.25)
			(net 13 "/OCuLink/PCIe_{x4}.TX0+")
			(pintype "passive")
		)
		(pad "2" smd roundrect
			(at -0.387 -0.5 180)
			(size 0.25 0.55)
			(layers "F.Cu" "F.Mask" "F.Paste")
			(roundrect_rratio 0.25)
			(net 17 "/OCuLink/PCIe_{x4}.TX0-")
			(pintype "passive")
		)
		(pad "3" smd roundrect
			(at -0.387 0 180)
			(size 0.4 0.55)
			(layers "F.Cu" "F.Mask" "F.Paste")
			(roundrect_rratio 0.25)
			(net 28 "GND")
			(pintype "power_in")
		)
		(pad "4" smd roundrect
			(at -0.387 0.498 180)
			(size 0.25 0.55)
			(layers "F.Cu" "F.Mask" "F.Paste")
			(roundrect_rratio 0.25)
			(net 19 "/OCuLink/PCIe_{x4}.TX1+")
			(pintype "passive")
		)
		(pad "5" smd roundrect
			(at -0.387 0.998 180)
			(size 0.25 0.55)
			(layers "F.Cu" "F.Mask" "F.Paste")
			(roundrect_rratio 0.25)
			(net 20 "/OCuLink/PCIe_{x4}.TX1-")
			(pintype "passive")
		)
		(pad "6" smd roundrect
			(at 0.385 0.998 180)
			(size 0.25 0.55)
			(layers "F.Cu" "F.Mask" "F.Paste")
			(roundrect_rratio 0.25)
			(net 20 "/OCuLink/PCIe_{x4}.TX1-")
			(pintype "passive")
		)
		(pad "7" smd roundrect
			(at 0.385 0.498 180)
			(size 0.25 0.55)
			(layers "F.Cu" "F.Mask" "F.Paste")
			(roundrect_rratio 0.25)
			(net 19 "/OCuLink/PCIe_{x4}.TX1+")
			(pintype "passive")
		)
		(pad "8" smd roundrect
			(at 0.385 0 180)
			(size 0.4 0.55)
			(layers "F.Cu" "F.Mask" "F.Paste")
			(roundrect_rratio 0.25)
			(net 28 "GND")
			(pintype "passive")
		)
		(pad "9" smd roundrect
			(at 0.385 -0.5 180)
			(size 0.25 0.55)
			(layers "F.Cu" "F.Mask" "F.Paste")
			(roundrect_rratio 0.25)
			(net 17 "/OCuLink/PCIe_{x4}.TX0-")
			(pintype "passive")
		)
		(pad "10" smd roundrect
			(at 0.385 -1 180)
			(size 0.25 0.55)
			(layers "F.Cu" "F.Mask" "F.Paste")
			(roundrect_rratio 0.25)
			(net 13 "/OCuLink/PCIe_{x4}.TX0+")
			(pintype "passive")
		)
	)
	(footprint "antmicro-footprints:C_0603_1608Metric_EIA"
		(layer "F.Cu")
		(at 70.499998 77.189995 180)
		(descr "Capacitor SMD 0603, IPC-7351 Density Level A")
		(tags "Capacitor 0603")
		(property "Reference" "C4"
			(at 1.149998 0.289995 0)
			(layer "F.SilkS")
			(effects
				(font
					(size 0.7 0.7)
					(thickness 0.15)
				)
				(justify right top)
			)
		)
		(property "Value" "C_22u_16V_0603"
			(at -1.42757 1.770288 0)
			(layer "F.Fab")
			(hide yes)
			(effects
				(font
					(size 0.7 0.7)
					(thickness 0.15)
				)
				(justify right top)
			)
		)
		(property "Datasheet" "https://product.samsungsem.com/mlcc/CL10A226MO7JZN.do"
			(at 0 0 0)
			(layer "F.Fab")
			(hide yes)
			(effects
				(font
					(size 1.27 1.27)
					(thickness 0.15)
				)
			)
		)
		(property "Description" "SMD Multilayer Ceramic Capacitor"
			(at 0 0 0)
			(layer "F.Fab")
			(hide yes)
			(effects
				(font
					(size 1.27 1.27)
					(thickness 0.15)
				)
			)
		)
		(property "MPN" "CL10A226MO7JZNC"
			(at 0 0 180)
			(unlocked yes)
			(layer "F.Fab")
			(hide yes)
			(effects
				(font
					(size 1 1)
					(thickness 0.15)
				)
			)
		)
		(property "Manufacturer" "Samsung Electro-Mechanics"
			(at 0 0 180)
			(unlocked yes)
			(layer "F.Fab")
			(hide yes)
			(effects
				(font
					(size 1 1)
					(thickness 0.15)
				)
			)
		)
		(property "License" "Apache-2.0"
			(at 0 0 180)
			(unlocked yes)
			(layer "F.Fab")
			(hide yes)
			(effects
				(font
					(size 1 1)
					(thickness 0.15)
				)
			)
		)
		(property "Author" "Antmicro"
			(at 0 0 180)
			(unlocked yes)
			(layer "F.Fab")
			(hide yes)
			(effects
				(font
					(size 1 1)
					(thickness 0.15)
				)
			)
		)
		(property "Val" "22u"
			(at 0 0 180)
			(unlocked yes)
			(layer "F.Fab")
			(hide yes)
			(effects
				(font
					(size 1 1)
					(thickness 0.15)
				)
			)
		)
		(property "Voltage" "16V"
			(at 0 0 180)
			(unlocked yes)
			(layer "F.Fab")
			(hide yes)
			(effects
				(font
					(size 1 1)
					(thickness 0.15)
				)
			)
		)
		(property "Dielectric" ""
			(at 0 0 180)
			(unlocked yes)
			(layer "F.Fab")
			(hide yes)
			(effects
				(font
					(size 1 1)
					(thickness 0.15)
				)
			)
		)
		(property "Public" "False"
			(at 0 0 180)
			(unlocked yes)
			(layer "F.Fab")
			(hide yes)
			(effects
				(font
					(size 1 1)
					(thickness 0.15)
				)
			)
		)
		(sheetname "/Power/")
		(sheetfile "power.kicad_sch")
		(attr smd)
		(fp_line
			(start -0.15 0.55)
			(end 0.15 0.55)
			(stroke
				(width 0.15)
				(type solid)
			)
			(layer "F.SilkS")
		)
		(fp_line
			(start -0.15 -0.55)
			(end 0.15 -0.55)
			(stroke
				(width 0.15)
				(type solid)
			)
			(layer "F.SilkS")
		)
		(fp_rect
			(start -1.25 -0.65)
			(end 1.25 0.65)
			(stroke
				(width 0.05)
				(type solid)
			)
			(fill no)
			(layer "F.CrtYd")
		)
		(fp_rect
			(start -0.8 -0.45)
			(end 0.8 0.45)
			(stroke
				(width 0.15)
				(type solid)
			)
			(fill no)
			(layer "F.Fab")
		)
		(pad "1" smd roundrect
			(at -0.7 0 180)
			(size 0.8 1.1)
			(layers "F.Cu" "F.Mask" "F.Paste")
			(roundrect_rratio 0.2)
			(net 28 "GND")
			(pintype "passive")
		)
		(pad "2" smd roundrect
			(at 0.7 0 180)
			(size 0.8 1.1)
			(layers "F.Cu" "F.Mask" "F.Paste")
			(roundrect_rratio 0.2)
			(net 314 "VCC")
			(pintype "passive")
		)
	)
	(footprint "antmicro-footprints:C_0402_1005Metric"
		(layer "F.Cu")
		(at 70.9445 105.91 -90)
		(descr "Capacitor SMD 0402")
		(tags "capacitor SMD 0402")
		(property "Reference" "C73"
			(at 0.69 0.3245 90)
			(layer "F.SilkS")
			(effects
				(font
					(size 0.7 0.7)
					(thickness 0.15)
				)
				(justify right top)
			)
		)
		(property "Value" "C_5p6_0402"
			(at -1.022927 2.155213 90)
			(layer "F.Fab")
			(hide yes)
			(effects
				(font
					(size 0.7 0.7)
					(thickness 0.15)
				)
				(justify right top)
			)
		)
		(property "Datasheet" "https://www.mouser.com/datasheet/3/76/2/GCM1555C1H5R6BA16_01A.pdf"
			(at 0 0 90)
			(layer "F.Fab")
			(hide yes)
			(effects
				(font
					(size 1.27 1.27)
					(thickness 0.15)
				)
			)
		)
		(property "Description" "Multilayer Ceramic Capacitors MLCC - SMD/SMT 5.6 pF 50 VDC 0.1 pF 0402 C0G (NP0) AEC-Q200"
			(at 0 0 90)
			(layer "F.Fab")
			(hide yes)
			(effects
				(font
					(size 1.27 1.27)
					(thickness 0.15)
				)
			)
		)
		(property "MPN" "GCM1555C1H5R6BA16D"
			(at 0 0 270)
			(unlocked yes)
			(layer "F.Fab")
			(hide yes)
			(effects
				(font
					(size 1 1)
					(thickness 0.15)
				)
			)
		)
		(property "Manufacturer" "Murata"
			(at 0 0 270)
			(unlocked yes)
			(layer "F.Fab")
			(hide yes)
			(effects
				(font
					(size 1 1)
					(thickness 0.15)
				)
			)
		)
		(property "License" "Apache-2.0"
			(at 0 0 270)
			(unlocked yes)
			(layer "F.Fab")
			(hide yes)
			(effects
				(font
					(size 1 1)
					(thickness 0.15)
				)
			)
		)
		(property "Author" "Antmicro"
			(at 0 0 270)
			(unlocked yes)
			(layer "F.Fab")
			(hide yes)
			(effects
				(font
					(size 1 1)
					(thickness 0.15)
				)
			)
		)
		(property "Val" "5p6"
			(at 0 0 270)
			(unlocked yes)
			(layer "F.Fab")
			(hide yes)
			(effects
				(font
					(size 1 1)
					(thickness 0.15)
				)
			)
		)
		(property "Voltage" "50V"
			(at 0 0 270)
			(unlocked yes)
			(layer "F.Fab")
			(hide yes)
			(effects
				(font
					(size 1 1)
					(thickness 0.15)
				)
			)
		)
		(property "Dielectric" "C0G"
			(at 0 0 270)
			(unlocked yes)
			(layer "F.Fab")
			(hide yes)
			(effects
				(font
					(size 1 1)
					(thickness 0.15)
				)
			)
		)
		(sheetname "/X710-AT2 Misc/")
		(sheetfile "x710-at2-mics.kicad_sch")
		(attr smd)
		(fp_rect
			(start -0.925 -0.47)
			(end 0.925 0.47)
			(stroke
				(width 0.05)
				(type default)
			)
			(fill no)
			(layer "F.CrtYd")
		)
		(fp_line
			(start -0.494 0.248)
			(end -0.494 -0.25)
			(stroke
				(width 0.15)
				(type solid)
			)
			(layer "F.Fab")
		)
		(fp_line
			(start 0.504 0.248)
			(end -0.494 0.248)
			(stroke
				(width 0.15)
				(type solid)
			)
			(layer "F.Fab")
		)
		(fp_line
			(start -0.494 -0.25)
			(end 0.504 -0.25)
			(stroke
				(width 0.15)
				(type solid)
			)
			(layer "F.Fab")
		)
		(fp_line
			(start 0.504 -0.25)
			(end 0.504 0.248)
			(stroke
				(width 0.15)
				(type solid)
			)
			(layer "F.Fab")
		)
		(pad "1" smd roundrect
			(at -0.48 0 270)
			(size 0.59 0.64)
			(layers "F.Cu" "F.Mask" "F.Paste")
			(roundrect_rratio 0.25)
			(net 28 "GND")
			(pintype "passive")
		)
		(pad "2" smd roundrect
			(at 0.48 0 270)
			(size 0.59 0.64)
			(layers "F.Cu" "F.Mask" "F.Paste")
			(roundrect_rratio 0.25)
			(net 77 "/X710-AT2 Misc/50MHZ_XTAL_R.-")
			(pintype "passive")
		)
	)
	(footprint "antmicro-footprints:C_0402_1005Metric"
		(layer "F.Cu")
		(at 97.498001 62.778655 -90)
		(descr "Capacitor SMD 0402")
		(tags "capacitor SMD 0402")
		(property "Reference" "C195"
			(at 1.806345 -2.351999 270)
			(layer "F.SilkS")
			(effects
				(font
					(size 0.7 0.7)
					(thickness 0.15)
				)
				(justify left bottom)
			)
		)
		(property "Value" "C_220n_16V_0402"
			(at -1.022927 2.155213 270)
			(layer "F.Fab")
			(hide yes)
			(effects
				(font
					(size 0.7 0.7)
					(thickness 0.15)
				)
				(justify left bottom)
			)
		)
		(property "Datasheet" "https://www.murata.com/products/productdetail?partno=GRM155R71C224KA12%23"
			(at 0 0 270)
			(layer "F.Fab")
			(hide yes)
			(effects
				(font
					(size 1.27 1.27)
					(thickness 0.15)
				)
			)
		)
		(property "Description" "SMD Multilayer Ceramic Capacitor, 0.22 µF, 16 V, 0402 [1005 Metric], ± 10%, X7R, GRM Series"
			(at 0 0 270)
			(layer "F.Fab")
			(hide yes)
			(effects
				(font
					(size 1.27 1.27)
					(thickness 0.15)
				)
			)
		)
		(property "MPN" "GRM155R71C224KA12D"
			(at 0 0 270)
			(unlocked yes)
			(layer "F.Fab")
			(hide yes)
			(effects
				(font
					(size 1 1)
					(thickness 0.15)
				)
			)
		)
		(property "Manufacturer" "Murata"
			(at 0 0 270)
			(unlocked yes)
			(layer "F.Fab")
			(hide yes)
			(effects
				(font
					(size 1 1)
					(thickness 0.15)
				)
			)
		)
		(property "License" "Apache-2.0"
			(at 0 0 270)
			(unlocked yes)
			(layer "F.Fab")
			(hide yes)
			(effects
				(font
					(size 1 1)
					(thickness 0.15)
				)
			)
		)
		(property "Author" "Antmicro"
			(at 0 0 270)
			(unlocked yes)
			(layer "F.Fab")
			(hide yes)
			(effects
				(font
					(size 1 1)
					(thickness 0.15)
				)
			)
		)
		(property "Val" "220n"
			(at 0 0 270)
			(unlocked yes)
			(layer "F.Fab")
			(hide yes)
			(effects
				(font
					(size 1 1)
					(thickness 0.15)
				)
			)
		)
		(property "Voltage" "16V"
			(at 0 0 270)
			(unlocked yes)
			(layer "F.Fab")
			(hide yes)
			(effects
				(font
					(size 1 1)
					(thickness 0.15)
				)
			)
		)
		(property "Dielectric" "X7R"
			(at 0 0 270)
			(unlocked yes)
			(layer "F.Fab")
			(hide yes)
			(effects
				(font
					(size 1 1)
					(thickness 0.15)
				)
			)
		)
		(sheetname "/X710-AT2 PCIe/")
		(sheetfile "x710-at2-pcie.kicad_sch")
		(attr smd)
		(fp_rect
			(start -0.925 -0.47)
			(end 0.925 0.47)
			(stroke
				(width 0.05)
				(type default)
			)
			(fill no)
			(layer "F.CrtYd")
		)
		(fp_line
			(start -0.494 0.248)
			(end -0.494 -0.25)
			(stroke
				(width 0.15)
				(type solid)
			)
			(layer "F.Fab")
		)
		(fp_line
			(start 0.504 0.248)
			(end -0.494 0.248)
			(stroke
				(width 0.15)
				(type solid)
			)
			(layer "F.Fab")
		)
		(fp_line
			(start -0.494 -0.25)
			(end 0.504 -0.25)
			(stroke
				(width 0.15)
				(type solid)
			)
			(layer "F.Fab")
		)
		(fp_line
			(start 0.504 -0.25)
			(end 0.504 0.248)
			(stroke
				(width 0.15)
				(type solid)
			)
			(layer "F.Fab")
		)
		(pad "1" smd roundrect
			(at -0.48 0 270)
			(size 0.59 0.64)
			(layers "F.Cu" "F.Mask" "F.Paste")
			(roundrect_rratio 0.25)
			(net 22 "/OCuLink/PCIe_{x4}.TX2-")
			(pintype "passive")
		)
		(pad "2" smd roundrect
			(at 0.48 0 270)
			(size 0.59 0.64)
			(layers "F.Cu" "F.Mask" "F.Paste")
			(roundrect_rratio 0.25)
			(net 41 "/X710-AT2 PCIe/PCIe_{x4}_AC.TX2-")
			(pintype "passive")
		)
	)
	(footprint "antmicro-footprints:C_0402_1005Metric"
		(layer "F.Cu")
		(at 70.693 63.7)
		(descr "Capacitor SMD 0402")
		(tags "capacitor SMD 0402")
		(property "Reference" "C200"
			(at 0.867 0.39 0)
			(layer "F.SilkS")
			(effects
				(font
					(size 0.7 0.7)
					(thickness 0.15)
				)
				(justify left bottom)
			)
		)
		(property "Value" "C_100n_0402"
			(at -1.022927 2.155213 0)
			(layer "F.Fab")
			(hide yes)
			(effects
				(font
					(size 0.7 0.7)
					(thickness 0.15)
				)
				(justify left bottom)
			)
		)
		(property "Datasheet" "https://www.murata.com/products/productdetail?partno=GRM155R61H104KE14%23"
			(at 0 0 0)
			(layer "F.Fab")
			(hide yes)
			(effects
				(font
					(size 1.27 1.27)
					(thickness 0.15)
				)
			)
		)
		(property "Description" "SMD Multilayer Ceramic Capacitor, 0.1 µF, 50 V, 0402 [1005 Metric], ± 10%, X5R, GRM Series"
			(at 0 0 0)
			(layer "F.Fab")
			(hide yes)
			(effects
				(font
					(size 1.27 1.27)
					(thickness 0.15)
				)
			)
		)
		(property "MPN" "GRM155R61H104KE14D"
			(at 0 0 0)
			(unlocked yes)
			(layer "F.Fab")
			(hide yes)
			(effects
				(font
					(size 1 1)
					(thickness 0.15)
				)
			)
		)
		(property "Manufacturer" "Murata"
			(at 0 0 0)
			(unlocked yes)
			(layer "F.Fab")
			(hide yes)
			(effects
				(font
					(size 1 1)
					(thickness 0.15)
				)
			)
		)
		(property "License" "Apache-2.0"
			(at 0 0 0)
			(unlocked yes)
			(layer "F.Fab")
			(hide yes)
			(effects
				(font
					(size 1 1)
					(thickness 0.15)
				)
			)
		)
		(property "Author" "Antmicro"
			(at 0 0 0)
			(unlocked yes)
			(layer "F.Fab")
			(hide yes)
			(effects
				(font
					(size 1 1)
					(thickness 0.15)
				)
			)
		)
		(property "Val" "100n"
			(at 0 0 0)
			(unlocked yes)
			(layer "F.Fab")
			(hide yes)
			(effects
				(font
					(size 1 1)
					(thickness 0.15)
				)
			)
		)
		(property "Voltage" "50V"
			(at 0 0 0)
			(unlocked yes)
			(layer "F.Fab")
			(hide yes)
			(effects
				(font
					(size 1 1)
					(thickness 0.15)
				)
			)
		)
		(property "Dielectric" "X5R"
			(at 0 0 0)
			(unlocked yes)
			(layer "F.Fab")
			(hide yes)
			(effects
				(font
					(size 1 1)
					(thickness 0.15)
				)
			)
		)
		(sheetname "/Power/Ideal diode 1/")
		(sheetfile "ideal-diode.kicad_sch")
		(attr smd)
		(fp_rect
			(start -0.925 -0.47)
			(end 0.925 0.47)
			(stroke
				(width 0.05)
				(type default)
			)
			(fill no)
			(layer "F.CrtYd")
		)
		(fp_line
			(start -0.494 -0.25)
			(end 0.504 -0.25)
			(stroke
				(width 0.15)
				(type solid)
			)
			(layer "F.Fab")
		)
		(fp_line
			(start -0.494 0.248)
			(end -0.494 -0.25)
			(stroke
				(width 0.15)
				(type solid)
			)
			(layer "F.Fab")
		)
		(fp_line
			(start 0.504 -0.25)
			(end 0.504 0.248)
			(stroke
				(width 0.15)
				(type solid)
			)
			(layer "F.Fab")
		)
		(fp_line
			(start 0.504 0.248)
			(end -0.494 0.248)
			(stroke
				(width 0.15)
				(type solid)
			)
			(layer "F.Fab")
		)
		(pad "1" smd roundrect
			(at -0.48 0)
			(size 0.59 0.64)
			(layers "F.Cu" "F.Mask" "F.Paste")
			(roundrect_rratio 0.25)
			(net 28 "GND")
			(pintype "passive")
		)
		(pad "2" smd roundrect
			(at 0.48 0)
			(size 0.59 0.64)
			(layers "F.Cu" "F.Mask" "F.Paste")
			(roundrect_rratio 0.25)
			(net 350 "/Power/+12V_IN")
			(pintype "passive")
		)
	)
	(footprint "antmicro-footprints:C_0402_1005Metric"
		(layer "F.Cu")
		(at 55.1 100.549999 90)
		(descr "Capacitor SMD 0402")
		(tags "capacitor SMD 0402")
		(property "Reference" "C20"
			(at -1.090001 -2.33 90)
			(layer "F.SilkS")
			(effects
				(font
					(size 0.7 0.7)
					(thickness 0.15)
				)
				(justify left bottom)
			)
		)
		(property "Value" "C_33p_0402"
			(at -1.022927 2.155213 90)
			(layer "F.Fab")
			(hide yes)
			(effects
				(font
					(size 0.7 0.7)
					(thickness 0.15)
				)
				(justify left bottom)
			)
		)
		(property "Datasheet" "https://spicat.kyocera-avx.com/product/mlcc/chartview/04025A330FAT2A/"
			(at 0 0 90)
			(layer "F.Fab")
			(hide yes)
			(effects
				(font
					(size 1.27 1.27)
					(thickness 0.15)
				)
			)
		)
		(property "Description" "SMD Multilayer Ceramic Capacitor, 33 pF, 50 V, 0402 [1005 Metric], ± 5%, C0G / NP0, MC"
			(at 0 0 90)
			(layer "F.Fab")
			(hide yes)
			(effects
				(font
					(size 1.27 1.27)
					(thickness 0.15)
				)
			)
		)
		(property "MPN" "04025A330FAT2A"
			(at 0 0 90)
			(unlocked yes)
			(layer "F.Fab")
			(hide yes)
			(effects
				(font
					(size 1 1)
					(thickness 0.15)
				)
			)
		)
		(property "Manufacturer" "KYOCERA AVX"
			(at 0 0 90)
			(unlocked yes)
			(layer "F.Fab")
			(hide yes)
			(effects
				(font
					(size 1 1)
					(thickness 0.15)
				)
			)
		)
		(property "License" "Apache-2.0"
			(at 0 0 90)
			(unlocked yes)
			(layer "F.Fab")
			(hide yes)
			(effects
				(font
					(size 1 1)
					(thickness 0.15)
				)
			)
		)
		(property "Author" "Antmicro"
			(at 0 0 90)
			(unlocked yes)
			(layer "F.Fab")
			(hide yes)
			(effects
				(font
					(size 1 1)
					(thickness 0.15)
				)
			)
		)
		(property "Val" "33p"
			(at 0 0 90)
			(unlocked yes)
			(layer "F.Fab")
			(hide yes)
			(effects
				(font
					(size 1 1)
					(thickness 0.15)
				)
			)
		)
		(property "Voltage" ""
			(at 0 0 90)
			(unlocked yes)
			(layer "F.Fab")
			(hide yes)
			(effects
				(font
					(size 1 1)
					(thickness 0.15)
				)
			)
		)
		(property "Dielectric" ""
			(at 0 0 90)
			(unlocked yes)
			(layer "F.Fab")
			(hide yes)
			(effects
				(font
					(size 1 1)
					(thickness 0.15)
				)
			)
		)
		(sheetname "/Power/")
		(sheetfile "power.kicad_sch")
		(attr smd exclude_from_pos_files exclude_from_bom dnp)
		(fp_rect
			(start -0.925 -0.47)
			(end 0.925 0.47)
			(stroke
				(width 0.05)
				(type default)
			)
			(fill no)
			(layer "F.CrtYd")
		)
		(fp_line
			(start 0.504 -0.25)
			(end 0.504 0.248)
			(stroke
				(width 0.15)
				(type solid)
			)
			(layer "F.Fab")
		)
		(fp_line
			(start -0.494 -0.25)
			(end 0.504 -0.25)
			(stroke
				(width 0.15)
				(type solid)
			)
			(layer "F.Fab")
		)
		(fp_line
			(start 0.504 0.248)
			(end -0.494 0.248)
			(stroke
				(width 0.15)
				(type solid)
			)
			(layer "F.Fab")
		)
		(fp_line
			(start -0.494 0.248)
			(end -0.494 -0.25)
			(stroke
				(width 0.15)
				(type solid)
			)
			(layer "F.Fab")
		)
		(pad "1" smd roundrect
			(at -0.48 0 90)
			(size 0.59 0.64)
			(layers "F.Cu" "F.Mask" "F.Paste")
			(roundrect_rratio 0.25)
			(net 330 "/Power/1V88_FB")
			(pintype "passive")
		)
		(pad "2" smd roundrect
			(at 0.48 0 90)
			(size 0.59 0.64)
			(layers "F.Cu" "F.Mask" "F.Paste")
			(roundrect_rratio 0.25)
			(net 310 "/Power/+1V88_OUT")
			(pintype "passive")
		)
	)
	(footprint "antmicro-footprints:SOT-753"
		(layer "F.Cu")
		(at 81.3 86.35 -90)
		(property "Reference" "U10"
			(at -1 -2.15 90)
			(layer "F.SilkS")
			(effects
				(font
					(size 0.7 0.7)
					(thickness 0.15)
				)
				(justify right top)
			)
		)
		(property "Value" "74LVC1G07_SOT-753"
			(at 0 2.9 90)
			(layer "F.Fab")
			(hide yes)
			(effects
				(font
					(size 0.7 0.7)
					(thickness 0.15)
				)
				(justify right top)
			)
		)
		(property "Datasheet" "https://www.mouser.com/datasheet/2/916/74LVC1G07-1529858.pdf"
			(at 0 0 90)
			(layer "F.Fab")
			(hide yes)
			(effects
				(font
					(size 1.27 1.27)
					(thickness 0.15)
				)
			)
		)
		(property "Description" "Buffer, 74LVC1G07, 1.65 V to 5.5 V, SC-74A-5"
			(at 0 0 90)
			(layer "F.Fab")
			(hide yes)
			(effects
				(font
					(size 1.27 1.27)
					(thickness 0.15)
				)
			)
		)
		(property "MPN" "74LVC1G07GV,125"
			(at 0 0 270)
			(unlocked yes)
			(layer "F.Fab")
			(hide yes)
			(effects
				(font
					(size 1 1)
					(thickness 0.15)
				)
			)
		)
		(property "Manufacturer" "Nexperia"
			(at 0 0 270)
			(unlocked yes)
			(layer "F.Fab")
			(hide yes)
			(effects
				(font
					(size 1 1)
					(thickness 0.15)
				)
			)
		)
		(property "Author" "Antmicro"
			(at 0 0 270)
			(unlocked yes)
			(layer "F.Fab")
			(hide yes)
			(effects
				(font
					(size 1 1)
					(thickness 0.15)
				)
			)
		)
		(property "License" "Apache-2.0"
			(at 0 0 270)
			(unlocked yes)
			(layer "F.Fab")
			(hide yes)
			(effects
				(font
					(size 1 1)
					(thickness 0.15)
				)
			)
		)
		(sheetname "/X710-AT2 Misc/")
		(sheetfile "x710-at2-mics.kicad_sch")
		(attr smd)
		(fp_line
			(start -1.648 1)
			(end -1.648 0.677)
			(stroke
				(width 0.15)
				(type solid)
			)
			(layer "F.SilkS")
		)
		(fp_line
			(start -1.5 1)
			(end -1.648 1)
			(stroke
				(width 0.15)
				(type solid)
			)
			(layer "F.SilkS")
		)
		(fp_line
			(start 1.5 0.998)
			(end 1.648 0.998)
			(stroke
				(width 0.15)
				(type solid)
			)
			(layer "F.SilkS")
		)
		(fp_line
			(start 1.648 0.998)
			(end 1.648 0.699)
			(stroke
				(width 0.15)
				(type solid)
			)
			(layer "F.SilkS")
		)
		(fp_line
			(start -1.651 -1)
			(end -1.651 -0.701)
			(stroke
				(width 0.15)
				(type solid)
			)
			(layer "F.SilkS")
		)
		(fp_line
			(start -1.5 -1)
			(end -1.651 -1)
			(stroke
				(width 0.15)
				(type solid)
			)
			(layer "F.SilkS")
		)
		(fp_line
			(start 1.5 -1)
			(end 1.648 -1)
			(stroke
				(width 0.15)
				(type solid)
			)
			(layer "F.SilkS")
		)
		(fp_line
			(start 1.648 -1)
			(end 1.648 -0.677)
			(stroke
				(width 0.15)
				(type solid)
			)
			(layer "F.SilkS")
		)
		(fp_circle
			(center -1.5 1.35)
			(end -1.46 1.4)
			(stroke
				(width 0.15)
				(type solid)
			)
			(fill yes)
			(layer "F.SilkS")
		)
		(fp_rect
			(start -1.7 -1.901)
			(end 1.699 1.898)
			(stroke
				(width 0.05)
				(type solid)
			)
			(fill no)
			(layer "F.CrtYd")
		)
		(fp_line
			(start -1.351 0.873)
			(end 1.523 0.873)
			(stroke
				(width 0.15)
				(type solid)
			)
			(layer "F.Fab")
		)
		(fp_line
			(start -1.526 0.623)
			(end -1.351 0.873)
			(stroke
				(width 0.15)
				(type solid)
			)
			(layer "F.Fab")
		)
		(fp_line
			(start -1.526 0.623)
			(end -1.526 -0.875)
			(stroke
				(width 0.15)
				(type solid)
			)
			(layer "F.Fab")
		)
		(fp_line
			(start -1.526 -0.875)
			(end 1.523 -0.875)
			(stroke
				(width 0.15)
				(type solid)
			)
			(layer "F.Fab")
		)
		(fp_line
			(start 1.523 -0.875)
			(end 1.523 0.873)
			(stroke
				(width 0.15)
				(type solid)
			)
			(layer "F.Fab")
		)
		(pad "1" smd roundrect
			(at -0.951 1.35 270)
			(size 0.6 1.05)
			(layers "F.Cu" "F.Mask" "F.Paste")
			(roundrect_rratio 0.25)
			(net 401 "unconnected-(U10-NC-Pad1)")
			(pinfunction "NC")
			(pintype "no_connect")
		)
		(pad "2" smd roundrect
			(at 0 1.35 270)
			(size 0.6 1.05)
			(layers "F.Cu" "F.Mask" "F.Paste")
			(roundrect_rratio 0.25)
			(net 396 "Net-(U10-A)")
			(pinfunction "A")
			(pintype "input")
		)
		(pad "3" smd roundrect
			(at 0.949 1.35 270)
			(size 0.6 1.05)
			(layers "F.Cu" "F.Mask" "F.Paste")
			(roundrect_rratio 0.25)
			(net 28 "GND")
			(pinfunction "GND")
			(pintype "power_in")
		)
		(pad "4" smd roundrect
			(at 0.949 -1.351 270)
			(size 0.6 1.05)
			(layers "F.Cu" "F.Mask" "F.Paste")
			(roundrect_rratio 0.25)
			(net 99 "/X710-AT2 Misc/LAN_PWR_GOOD")
			(pinfunction "Y")
			(pintype "output")
		)
		(pad "5" smd roundrect
			(at -0.951 -1.351 270)
			(size 0.6 1.05)
			(layers "F.Cu" "F.Mask" "F.Paste")
			(roundrect_rratio 0.25)
			(net 78 "Net-(U10-VCC)")
			(pinfunction "VCC")
			(pintype "power_in")
		)
	)
	(footprint "antmicro-footprints:C_0603_1608Metric_EIA"
		(layer "F.Cu")
		(at 53.25 103.900001 -90)
		(descr "Capacitor SMD 0603, IPC-7351 Density Level A")
		(tags "Capacitor 0603")
		(property "Reference" "C22"
			(at 1.219999 1.72 270)
			(layer "F.SilkS")
			(effects
				(font
					(size 0.7 0.7)
					(thickness 0.15)
				)
				(justify right top)
			)
		)
		(property "Value" "C_22u_16V_0603"
			(at -1.42757 1.770288 90)
			(layer "F.Fab")
			(hide yes)
			(effects
				(font
					(size 0.7 0.7)
					(thickness 0.15)
				)
				(justify right top)
			)
		)
		(property "Datasheet" "https://product.samsungsem.com/mlcc/CL10A226MO7JZN.do"
			(at 0 0 90)
			(layer "F.Fab")
			(hide yes)
			(effects
				(font
					(size 1.27 1.27)
					(thickness 0.15)
				)
			)
		)
		(property "Description" "SMD Multilayer Ceramic Capacitor"
			(at 0 0 90)
			(layer "F.Fab")
			(hide yes)
			(effects
				(font
					(size 1.27 1.27)
					(thickness 0.15)
				)
			)
		)
		(property "MPN" "CL10A226MO7JZNC"
			(at 0 0 270)
			(unlocked yes)
			(layer "F.Fab")
			(hide yes)
			(effects
				(font
					(size 1 1)
					(thickness 0.15)
				)
			)
		)
		(property "Manufacturer" "Samsung Electro-Mechanics"
			(at 0 0 270)
			(unlocked yes)
			(layer "F.Fab")
			(hide yes)
			(effects
				(font
					(size 1 1)
					(thickness 0.15)
				)
			)
		)
		(property "License" "Apache-2.0"
			(at 0 0 270)
			(unlocked yes)
			(layer "F.Fab")
			(hide yes)
			(effects
				(font
					(size 1 1)
					(thickness 0.15)
				)
			)
		)
		(property "Author" "Antmicro"
			(at 0 0 270)
			(unlocked yes)
			(layer "F.Fab")
			(hide yes)
			(effects
				(font
					(size 1 1)
					(thickness 0.15)
				)
			)
		)
		(property "Val" "22u"
			(at 0 0 270)
			(unlocked yes)
			(layer "F.Fab")
			(hide yes)
			(effects
				(font
					(size 1 1)
					(thickness 0.15)
				)
			)
		)
		(property "Voltage" "16V"
			(at 0 0 270)
			(unlocked yes)
			(layer "F.Fab")
			(hide yes)
			(effects
				(font
					(size 1 1)
					(thickness 0.15)
				)
			)
		)
		(property "Dielectric" ""
			(at 0 0 270)
			(unlocked yes)
			(layer "F.Fab")
			(hide yes)
			(effects
				(font
					(size 1 1)
					(thickness 0.15)
				)
			)
		)
		(property "Public" "False"
			(at 0 0 270)
			(unlocked yes)
			(layer "F.Fab")
			(hide yes)
			(effects
				(font
					(size 1 1)
					(thickness 0.15)
				)
			)
		)
		(sheetname "/Power/")
		(sheetfile "power.kicad_sch")
		(attr smd)
		(fp_line
			(start -0.15 0.55)
			(end 0.15 0.55)
			(stroke
				(width 0.15)
				(type solid)
			)
			(layer "F.SilkS")
		)
		(fp_line
			(start -0.15 -0.55)
			(end 0.15 -0.55)
			(stroke
				(width 0.15)
				(type solid)
			)
			(layer "F.SilkS")
		)
		(fp_rect
			(start -1.25 -0.65)
			(end 1.25 0.65)
			(stroke
				(width 0.05)
				(type solid)
			)
			(fill no)
			(layer "F.CrtYd")
		)
		(fp_rect
			(start -0.8 -0.45)
			(end 0.8 0.45)
			(stroke
				(width 0.15)
				(type solid)
			)
			(fill no)
			(layer "F.Fab")
		)
		(pad "1" smd roundrect
			(at -0.7 0 270)
			(size 0.8 1.1)
			(layers "F.Cu" "F.Mask" "F.Paste")
			(roundrect_rratio 0.2)
			(net 28 "GND")
			(pintype "passive")
		)
		(pad "2" smd roundrect
			(at 0.7 0 270)
			(size 0.8 1.1)
			(layers "F.Cu" "F.Mask" "F.Paste")
			(roundrect_rratio 0.2)
			(net 314 "VCC")
			(pintype "passive")
		)
	)
	(footprint "antmicro-footprints:Amphenol_G14A421211112HR"
		(layer "F.Cu")
		(at 100 53.385001 180)
		(property "Reference" "J9"
			(at 7.95 -6.2 0)
			(unlocked yes)
			(layer "F.SilkS")
			(effects
				(font
					(size 0.7 0.7)
					(thickness 0.15)
				)
				(justify left bottom)
			)
		)
		(property "Value" "OCuLink_x4_Amphenol_G14A421211112HR_CUSTOM_device_side"
			(at 0 6.385 180)
			(unlocked yes)
			(layer "F.Fab")
			(hide yes)
			(effects
				(font
					(size 0.7 0.7)
					(thickness 0.15)
				)
				(justify left bottom)
			)
		)
		(property "Datasheet" "https://cdn.amphenol-cs.com/media/wysiwyg/files/drawing/g14a421x1bxxxhr.pdf"
			(at 0 0 0)
			(layer "F.Fab")
			(hide yes)
			(effects
				(font
					(size 1.27 1.27)
					(thickness 0.15)
				)
			)
		)
		(property "Description" "I/O Connectors OCulink, Receptacle, 0.5mm pitch, 4X, R/A SMT with shell leg SMT type, 30U\" gold plating, LCP, black, T&R packing"
			(at 0 0 0)
			(layer "F.Fab")
			(hide yes)
			(effects
				(font
					(size 1.27 1.27)
					(thickness 0.15)
				)
			)
		)
		(property "Manufacturer" "Amphenol"
			(at 0 0 180)
			(unlocked yes)
			(layer "F.Fab")
			(hide yes)
			(effects
				(font
					(size 1 1)
					(thickness 0.15)
				)
			)
		)
		(property "MPN" "G14A421211112HR"
			(at 0 0 180)
			(unlocked yes)
			(layer "F.Fab")
			(hide yes)
			(effects
				(font
					(size 1 1)
					(thickness 0.15)
				)
			)
		)
		(property "Author" "Antmicro"
			(at 0 0 180)
			(unlocked yes)
			(layer "F.Fab")
			(hide yes)
			(effects
				(font
					(size 1 1)
					(thickness 0.15)
				)
			)
		)
		(property "License" "Apache-2.0"
			(at 0 0 180)
			(unlocked yes)
			(layer "F.Fab")
			(hide yes)
			(effects
				(font
					(size 1 1)
					(thickness 0.15)
				)
			)
		)
		(sheetname "/OCuLink/")
		(sheetfile "oculink.kicad_sch")
		(solder_paste_margin -0.06)
		(attr smd)
		(fp_line
			(start 6.8 -3)
			(end 6.8 -0.4)
			(stroke
				(width 0.1)
				(type default)
			)
			(layer "F.SilkS")
		)
		(fp_line
			(start -6.8 -0.4)
			(end -6.8 -3)
			(stroke
				(width 0.1)
				(type default)
			)
			(layer "F.SilkS")
		)
		(fp_circle
			(center -5.3 -5.52)
			(end -5.25 -5.52)
			(stroke
				(width 0.15)
				(type solid)
			)
			(fill yes)
			(layer "F.SilkS")
		)
		(fp_rect
			(start -8.22 -5.22)
			(end 8.22 4.94)
			(stroke
				(width 0.05)
				(type solid)
			)
			(fill no)
			(layer "F.CrtYd")
		)
		(fp_line
			(start 7 3.065)
			(end -7 3.065)
			(stroke
				(width 0.1)
				(type default)
			)
			(layer "F.Fab")
		)
		(fp_text user "${REFERENCE}"
			(at -8.22 9.885 180)
			(unlocked yes)
			(layer "F.Fab")
			(effects
				(font
					(size 0.7 0.7)
					(thickness 0.15)
				)
				(justify left bottom)
			)
		)
		(fp_text user "Author: Antmicro"
			(at -8.22 11.085 180)
			(layer "F.Fab")
			(effects
				(font
					(size 0.7 0.7)
					(thickness 0.15)
				)
				(justify left bottom)
			)
		)
		(fp_text user "License: Apache-2.0"
			(at -8.22 12.285 180)
			(layer "F.Fab")
			(effects
				(font
					(size 0.7 0.7)
					(thickness 0.15)
				)
				(justify left bottom)
			)
		)
		(fp_text user "PCB EDGE"
			(at 2.8 2.95 180)
			(unlocked yes)
			(layer "F.Fab")
			(effects
				(font
					(size 0.5 0.5)
					(thickness 0.125)
				)
				(justify left bottom)
			)
		)
		(pad "" np_thru_hole circle
			(at -5.42 -1.395 270)
			(size 1 1)
			(drill 1)
			(layers "*.Cu" "*.Mask")
		)
		(pad "" np_thru_hole circle
			(at 5.95 -1.395 270)
			(size 1 1)
			(drill 1)
			(layers "*.Cu" "*.Mask")
		)
		(pad "A1" smd roundrect
			(at -4.75 -2.115 270)
			(size 0.91 0.31)
			(layers "F.Cu" "F.Mask" "F.Paste")
			(roundrect_rratio 0.5)
			(net 90 "+3V3_AUX")
			(pinfunction "V_{ACT}_RX_3V3")
			(pintype "power_in")
		)
		(pad "A2" smd roundrect
			(at -4.25 -2.115 270)
			(size 0.91 0.31)
			(layers "F.Cu" "F.Mask" "F.Paste")
			(roundrect_rratio 0.5)
			(net 28 "GND")
			(pinfunction "GND")
			(pintype "passive")
		)
		(pad "A3" smd roundrect
			(at -3.75 -2.115 270)
			(size 0.91 0.31)
			(layers "F.Cu" "F.Mask" "F.Paste")
			(roundrect_rratio 0.5)
			(net 39 "/OCuLink/PCIe_{x4}.RX0+")
			(pinfunction "PER0+")
			(pintype "output")
		)
		(pad "A4" smd roundrect
			(at -3.25 -2.115 270)
			(size 0.91 0.31)
			(layers "F.Cu" "F.Mask" "F.Paste")
			(roundrect_rratio 0.5)
			(net 36 "/OCuLink/PCIe_{x4}.RX0-")
			(pinfunction "PER0-")
			(pintype "output")
		)
		(pad "A5" smd roundrect
			(at -2.75 -2.115 270)
			(size 0.91 0.31)
			(layers "F.Cu" "F.Mask" "F.Paste")
			(roundrect_rratio 0.5)
			(net 28 "GND")
			(pinfunction "GND")
			(pintype "passive")
		)
		(pad "A6" smd roundrect
			(at -2.25 -2.115 270)
			(size 0.91 0.31)
			(layers "F.Cu" "F.Mask" "F.Paste")
			(roundrect_rratio 0.5)
			(net 37 "/OCuLink/PCIe_{x4}.RX1+")
			(pinfunction "PER1+")
			(pintype "output")
		)
		(pad "A7" smd roundrect
			(at -1.75 -2.115 270)
			(size 0.91 0.31)
			(layers "F.Cu" "F.Mask" "F.Paste")
			(roundrect_rratio 0.5)
			(net 34 "/OCuLink/PCIe_{x4}.RX1-")
			(pinfunction "PER1-")
			(pintype "output")
		)
		(pad "A8" smd roundrect
			(at -1.25 -2.115 270)
			(size 0.91 0.31)
			(layers "F.Cu" "F.Mask" "F.Paste")
			(roundrect_rratio 0.5)
			(net 28 "GND")
			(pinfunction "GND")
			(pintype "passive")
		)
		(pad "A9" smd roundrect
			(at -0.75 -2.115 270)
			(size 0.91 0.31)
			(layers "F.Cu" "F.Mask" "F.Paste")
			(roundrect_rratio 0.5)
			(net 304 "/OCuLink/SCL")
			(pinfunction "SCL")
			(pintype "bidirectional")
		)
		(pad "A10" smd roundrect
			(at -0.25 -2.115 270)
			(size 0.91 0.31)
			(layers "F.Cu" "F.Mask" "F.Paste")
			(roundrect_rratio 0.5)
			(net 226 "/OCuLink/SDA")
			(pinfunction "SDA")
			(pintype "bidirectional")
		)
		(pad "A11" smd roundrect
			(at 0.25 -2.115 270)
			(size 0.91 0.31)
			(layers "F.Cu" "F.Mask" "F.Paste")
			(roundrect_rratio 0.5)
			(net 28 "GND")
			(pinfunction "GND")
			(pintype "passive")
		)
		(pad "A12" smd roundrect
			(at 0.75 -2.115 270)
			(size 0.91 0.31)
			(layers "F.Cu" "F.Mask" "F.Paste")
			(roundrect_rratio 0.5)
			(net 319 "/OCuLink/~{PE_ RST}_R")
			(pinfunction "~{PERST}")
			(pintype "bidirectional")
		)
		(pad "A13" smd roundrect
			(at 1.25 -2.115 270)
			(size 0.91 0.31)
			(layers "F.Cu" "F.Mask" "F.Paste")
			(roundrect_rratio 0.5)
			(net 321 "/OCuLink/~{CPRSNT}_R")
			(pinfunction "~{CPRSNT}")
			(pintype "bidirectional")
		)
		(pad "A14" smd roundrect
			(at 1.75 -2.115 270)
			(size 0.91 0.31)
			(layers "F.Cu" "F.Mask" "F.Paste")
			(roundrect_rratio 0.5)
			(net 28 "GND")
			(pinfunction "GND")
			(pintype "passive")
		)
		(pad "A15" smd roundrect
			(at 2.25 -2.115 270)
			(size 0.91 0.31)
			(layers "F.Cu" "F.Mask" "F.Paste")
			(roundrect_rratio 0.5)
			(net 80 "/OCuLink/PCIe_{x4}.RX2+")
			(pinfunction "PER2+")
			(pintype "output")
		)
		(pad "A16" smd roundrect
			(at 2.75 -2.115 270)
			(size 0.91 0.31)
			(layers "F.Cu" "F.Mask" "F.Paste")
			(roundrect_rratio 0.5)
			(net 104 "/OCuLink/PCIe_{x4}.RX2-")
			(pinfunction "PER2-")
			(pintype "output")
		)
		(pad "A17" smd roundrect
			(at 3.25 -2.115 270)
			(size 0.91 0.31)
			(layers "F.Cu" "F.Mask" "F.Paste")
			(roundrect_rratio 0.5)
			(net 28 "GND")
			(pinfunction "GND")
			(pintype "passive")
		)
		(pad "A18" smd roundrect
			(at 3.75 -2.115 270)
			(size 0.91 0.31)
			(layers "F.Cu" "F.Mask" "F.Paste")
			(roundrect_rratio 0.5)
			(net 98 "/OCuLink/PCIe_{x4}.RX3+")
			(pinfunction "PER3+")
			(pintype "output")
		)
		(pad "A19" smd roundrect
			(at 4.25 -2.115 270)
			(size 0.91 0.31)
			(layers "F.Cu" "F.Mask" "F.Paste")
			(roundrect_rratio 0.5)
			(net 109 "/OCuLink/PCIe_{x4}.RX3-")
			(pinfunction "PER3-")
			(pintype "output")
		)
		(pad "A20" smd roundrect
			(at 4.75 -2.115 270)
			(size 0.91 0.31)
			(layers "F.Cu" "F.Mask" "F.Paste")
			(roundrect_rratio 0.5)
			(net 28 "GND")
			(pinfunction "GND")
			(pintype "passive")
		)
		(pad "A21" smd roundrect
			(at 5.25 -2.115 270)
			(size 0.91 0.31)
			(layers "F.Cu" "F.Mask" "F.Paste")
			(roundrect_rratio 0.5)
			(net 152 "unconnected-(J9-5V-PadA21)")
			(pinfunction "5V")
			(pintype "passive+no_connect")
		)
		(pad "B1" smd roundrect
			(at -5.25 -4.305 270)
			(size 0.91 0.31)
			(layers "F.Cu" "F.Mask" "F.Paste")
			(roundrect_rratio 0.5)
			(net 154 "unconnected-(J9-5V-PadA21)_1")
			(pinfunction "5V")
			(pintype "passive+no_connect")
		)
		(pad "B2" smd roundrect
			(at -4.75 -4.305 270)
			(size 0.91 0.31)
			(layers "F.Cu" "F.Mask" "F.Paste")
			(roundrect_rratio 0.5)
			(net 28 "GND")
			(pinfunction "GND")
			(pintype "passive")
		)
		(pad "B3" smd roundrect
			(at -4.25 -4.305 270)
			(size 0.91 0.31)
			(layers "F.Cu" "F.Mask" "F.Paste")
			(roundrect_rratio 0.5)
			(net 13 "/OCuLink/PCIe_{x4}.TX0+")
			(pinfunction "PET0+")
			(pintype "input")
		)
		(pad "B4" smd roundrect
			(at -3.75 -4.305 270)
			(size 0.91 0.31)
			(layers "F.Cu" "F.Mask" "F.Paste")
			(roundrect_rratio 0.5)
			(net 17 "/OCuLink/PCIe_{x4}.TX0-")
			(pinfunction "PET0-")
			(pintype "input")
		)
		(pad "B5" smd roundrect
			(at -3.25 -4.305 270)
			(size 0.91 0.31)
			(layers "F.Cu" "F.Mask" "F.Paste")
			(roundrect_rratio 0.5)
			(net 28 "GND")
			(pinfunction "GND")
			(pintype "passive")
		)
		(pad "B6" smd roundrect
			(at -2.75 -4.305 270)
			(size 0.91 0.31)
			(layers "F.Cu" "F.Mask" "F.Paste")
			(roundrect_rratio 0.5)
			(net 19 "/OCuLink/PCIe_{x4}.TX1+")
			(pinfunction "PET1+")
			(pintype "input")
		)
		(pad "B7" smd roundrect
			(at -2.25 -4.305 270)
			(size 0.91 0.31)
			(layers "F.Cu" "F.Mask" "F.Paste")
			(roundrect_rratio 0.5)
			(net 20 "/OCuLink/PCIe_{x4}.TX1-")
			(pinfunction "PET1-")
			(pintype "input")
		)
		(pad "B8" smd roundrect
			(at -1.75 -4.305 270)
			(size 0.91 0.31)
			(layers "F.Cu" "F.Mask" "F.Paste")
			(roundrect_rratio 0.5)
			(net 28 "GND")
			(pinfunction "GND")
			(pintype "passive")
		)
		(pad "B9" smd roundrect
			(at -1.25 -4.305 270)
			(size 0.91 0.31)
			(layers "F.Cu" "F.Mask" "F.Paste")
			(roundrect_rratio 0.5)
			(net 151 "unconnected-(J9-NC-PadB9)")
			(pinfunction "NC")
			(pintype "no_connect")
		)
		(pad "B10" smd roundrect
			(at -0.75 -4.305 270)
			(size 0.91 0.31)
			(layers "F.Cu" "F.Mask" "F.Paste")
			(roundrect_rratio 0.5)
			(net 320 "/OCuLink/~{CWAKE}_R")
			(pinfunction "~{CWAKE}")
			(pintype "bidirectional")
		)
		(pad "B11" smd roundrect
			(at -0.25 -4.305 270)
			(size 0.91 0.31)
			(layers "F.Cu" "F.Mask" "F.Paste")
			(roundrect_rratio 0.5)
			(net 28 "GND")
			(pinfunction "GND")
			(pintype "passive")
		)
		(pad "B12" smd roundrect
			(at 0.25 -4.305 270)
			(size 0.91 0.31)
			(layers "F.Cu" "F.Mask" "F.Paste")
			(roundrect_rratio 0.5)
			(net 42 "/OCuLink/REFCLK.+")
			(pinfunction "VSP1")
			(pintype "bidirectional")
		)
		(pad "B13" smd roundrect
			(at 0.75 -4.305 270)
			(size 0.91 0.31)
			(layers "F.Cu" "F.Mask" "F.Paste")
			(roundrect_rratio 0.5)
			(net 45 "/OCuLink/REFCLK.-")
			(pinfunction "VSP2")
			(pintype "bidirectional")
		)
		(pad "B14" smd roundrect
			(at 1.25 -4.305 270)
			(size 0.91 0.31)
			(layers "F.Cu" "F.Mask" "F.Paste")
			(roundrect_rratio 0.5)
			(net 28 "GND")
			(pinfunction "GND")
			(pintype "passive")
		)
		(pad "B15" smd roundrect
			(at 1.75 -4.305 270)
			(size 0.91 0.31)
			(layers "F.Cu" "F.Mask" "F.Paste")
			(roundrect_rratio 0.5)
			(net 21 "/OCuLink/PCIe_{x4}.TX2+")
			(pinfunction "PET2+")
			(pintype "input")
		)
		(pad "B16" smd roundrect
			(at 2.25 -4.305 270)
			(size 0.91 0.31)
			(layers "F.Cu" "F.Mask" "F.Paste")
			(roundrect_rratio 0.5)
			(net 22 "/OCuLink/PCIe_{x4}.TX2-")
			(pinfunction "PET2-")
			(pintype "input")
		)
		(pad "B17" smd roundrect
			(at 2.75 -4.305 270)
			(size 0.91 0.31)
			(layers "F.Cu" "F.Mask" "F.Paste")
			(roundrect_rratio 0.5)
			(net 28 "GND")
			(pinfunction "GND")
			(pintype "passive")
		)
		(pad "B18" smd roundrect
			(at 3.25 -4.305 270)
			(size 0.91 0.31)
			(layers "F.Cu" "F.Mask" "F.Paste")
			(roundrect_rratio 0.5)
			(net 25 "/OCuLink/PCIe_{x4}.TX3+")
			(pinfunction "PET3+")
			(pintype "input")
		)
		(pad "B19" smd roundrect
			(at 3.75 -4.305 270)
			(size 0.91 0.31)
			(layers "F.Cu" "F.Mask" "F.Paste")
			(roundrect_rratio 0.5)
			(net 26 "/OCuLink/PCIe_{x4}.TX3-")
			(pinfunction "PET3-")
			(pintype "input")
		)
		(pad "B20" smd roundrect
			(at 4.25 -4.305 270)
			(size 0.91 0.31)
			(layers "F.Cu" "F.Mask" "F.Paste")
			(roundrect_rratio 0.5)
			(net 28 "GND")
			(pinfunction "GND")
			(pintype "passive")
		)
		(pad "B21" smd roundrect
			(at 4.75 -4.305 270)
			(size 0.91 0.31)
			(layers "F.Cu" "F.Mask" "F.Paste")
			(roundrect_rratio 0.5)
			(net 90 "+3V3_AUX")
			(pinfunction "V_{ACT}_TX_3V3")
			(pintype "power_in")
		)
		(pad "SH" smd roundrect
			(at -6.91 -3.915 270)
			(size 1.38 1.81)
			(layers "F.Cu" "F.Mask" "F.Paste")
			(roundrect_rratio 0.1)
			(net 28 "GND")
			(pinfunction "SH")
			(pintype "passive")
		)
		(pad "SH" smd roundrect
			(at -6.91 0.805 270)
			(size 1.81 1.8)
			(layers "F.Cu" "F.Mask" "F.Paste")
			(roundrect_rratio 0.1)
			(net 28 "GND")
			(pinfunction "SH")
			(pintype "passive")
		)
		(pad "SH" smd roundrect
			(at 6.91 -3.915 270)
			(size 1.38 1.81)
			(layers "F.Cu" "F.Mask" "F.Paste")
			(roundrect_rratio 0.1)
			(net 28 "GND")
			(pinfunction "SH")
			(pintype "passive")
		)
		(pad "SH" smd roundrect
			(at 6.91 0.805 270)
			(size 1.81 1.8)
			(layers "F.Cu" "F.Mask" "F.Paste")
			(roundrect_rratio 0.1)
			(net 28 "GND")
			(pinfunction "SH")
			(pintype "passive")
		)
	)
	(footprint "antmicro-footprints:MP_Pad6mm_Drill3.2mm"
		(layer "F.Cu")
		(at 56.75 134.68)
		(property "Reference" "MP1"
			(at -0.9 -3.48 0)
			(layer "F.SilkS")
			(hide yes)
			(effects
				(font
					(size 0.7 0.7)
					(thickness 0.15)
				)
				(justify left bottom)
			)
		)
		(property "Value" "MP_Pad6mm_Drill3.2mm"
			(at 0 3.9 0)
			(layer "F.Fab")
			(hide yes)
			(effects
				(font
					(size 0.7 0.7)
					(thickness 0.15)
				)
				(justify left bottom)
			)
		)
		(property "Description" "Mechanical part"
			(at 0 0 0)
			(layer "F.Fab")
			(hide yes)
			(effects
				(font
					(size 1.27 1.27)
					(thickness 0.15)
				)
			)
		)
		(property "Author" "Antmicro"
			(at 0 0 0)
			(unlocked yes)
			(layer "F.Fab")
			(hide yes)
			(effects
				(font
					(size 1 1)
					(thickness 0.15)
				)
			)
		)
		(property "License" "Apache-2.0"
			(at 0 0 0)
			(unlocked yes)
			(layer "F.Fab")
			(hide yes)
			(effects
				(font
					(size 1 1)
					(thickness 0.15)
				)
			)
		)
		(sheetname "/")
		(sheetfile "oculink-to-10gbe-adapter.kicad_sch")
		(attr exclude_from_pos_files exclude_from_bom)
		(fp_circle
			(center 0 0)
			(end 3.25 0)
			(stroke
				(width 0.05)
				(type default)
			)
			(fill no)
			(layer "F.CrtYd")
		)
		(pad "1" thru_hole circle
			(at 0 0)
			(size 6 6)
			(drill 3.2)
			(layers "*.Cu" "*.Mask")
			(remove_unused_layers no)
			(net 28 "GND")
			(pintype "passive")
		)
	)
	(footprint "antmicro-footprints:C_0603_1608Metric_EIA"
		(layer "F.Cu")
		(at 63.199999 108.55 180)
		(descr "Capacitor SMD 0603, IPC-7351 Density Level A")
		(tags "Capacitor 0603")
		(property "Reference" "C207"
			(at -2.620001 2.68 0)
			(layer "F.SilkS")
			(effects
				(font
					(size 0.7 0.7)
					(thickness 0.15)
				)
				(justify right top)
			)
		)
		(property "Value" "C_22u_16V_0603"
			(at -1.42757 1.770288 0)
			(layer "F.Fab")
			(hide yes)
			(effects
				(font
					(size 0.7 0.7)
					(thickness 0.15)
				)
				(justify right top)
			)
		)
		(property "Datasheet" "https://product.samsungsem.com/mlcc/CL10A226MO7JZN.do"
			(at 0 0 0)
			(layer "F.Fab")
			(hide yes)
			(effects
				(font
					(size 1.27 1.27)
					(thickness 0.15)
				)
			)
		)
		(property "Description" "SMD Multilayer Ceramic Capacitor"
			(at 0 0 0)
			(layer "F.Fab")
			(hide yes)
			(effects
				(font
					(size 1.27 1.27)
					(thickness 0.15)
				)
			)
		)
		(property "MPN" "CL10A226MO7JZNC"
			(at 0 0 180)
			(unlocked yes)
			(layer "F.Fab")
			(hide yes)
			(effects
				(font
					(size 1 1)
					(thickness 0.15)
				)
			)
		)
		(property "Manufacturer" "Samsung Electro-Mechanics"
			(at 0 0 180)
			(unlocked yes)
			(layer "F.Fab")
			(hide yes)
			(effects
				(font
					(size 1 1)
					(thickness 0.15)
				)
			)
		)
		(property "License" "Apache-2.0"
			(at 0 0 180)
			(unlocked yes)
			(layer "F.Fab")
			(hide yes)
			(effects
				(font
					(size 1 1)
					(thickness 0.15)
				)
			)
		)
		(property "Author" "Antmicro"
			(at 0 0 180)
			(unlocked yes)
			(layer "F.Fab")
			(hide yes)
			(effects
				(font
					(size 1 1)
					(thickness 0.15)
				)
			)
		)
		(property "Val" "22u"
			(at 0 0 180)
			(unlocked yes)
			(layer "F.Fab")
			(hide yes)
			(effects
				(font
					(size 1 1)
					(thickness 0.15)
				)
			)
		)
		(property "Voltage" "16V"
			(at 0 0 180)
			(unlocked yes)
			(layer "F.Fab")
			(hide yes)
			(effects
				(font
					(size 1 1)
					(thickness 0.15)
				)
			)
		)
		(property "Dielectric" ""
			(at 0 0 180)
			(unlocked yes)
			(layer "F.Fab")
			(hide yes)
			(effects
				(font
					(size 1 1)
					(thickness 0.15)
				)
			)
		)
		(property "Public" "False"
			(at 0 0 180)
			(unlocked yes)
			(layer "F.Fab")
			(hide yes)
			(effects
				(font
					(size 1 1)
					(thickness 0.15)
				)
			)
		)
		(sheetname "/Power/")
		(sheetfile "power.kicad_sch")
		(attr smd)
		(fp_line
			(start -0.15 0.55)
			(end 0.15 0.55)
			(stroke
				(width 0.15)
				(type solid)
			)
			(layer "F.SilkS")
		)
		(fp_line
			(start -0.15 -0.55)
			(end 0.15 -0.55)
			(stroke
				(width 0.15)
				(type solid)
			)
			(layer "F.SilkS")
		)
		(fp_rect
			(start -1.25 -0.65)
			(end 1.25 0.65)
			(stroke
				(width 0.05)
				(type solid)
			)
			(fill no)
			(layer "F.CrtYd")
		)
		(fp_rect
			(start -0.8 -0.45)
			(end 0.8 0.45)
			(stroke
				(width 0.15)
				(type solid)
			)
			(fill no)
			(layer "F.Fab")
		)
		(pad "1" smd roundrect
			(at -0.7 0 180)
			(size 0.8 1.1)
			(layers "F.Cu" "F.Mask" "F.Paste")
			(roundrect_rratio 0.2)
			(net 28 "GND")
			(pintype "passive")
		)
		(pad "2" smd roundrect
			(at 0.7 0 180)
			(size 0.8 1.1)
			(layers "F.Cu" "F.Mask" "F.Paste")
			(roundrect_rratio 0.2)
			(net 312 "/Power/+1V0_OUT")
			(pintype "passive")
		)
	)
	(footprint "antmicro-footprints:Vishay_PowerPAK_1212-8_Single"
		(layer "F.Cu")
		(at 82.9 66 90)
		(descr "PowerPAK 1212-8 Single")
		(tags "Vishay PowerPAK 1212-8 Single")
		(property "Reference" "Q3"
			(at -1.95 -1.9 90)
			(layer "F.SilkS")
			(effects
				(font
					(size 0.7 0.7)
					(thickness 0.15)
				)
				(justify left bottom)
			)
		)
		(property "Value" "SQS401EN-T1_BE3"
			(at 0 2.7 90)
			(layer "F.Fab")
			(hide yes)
			(effects
				(font
					(size 0.7 0.7)
					(thickness 0.15)
				)
				(justify left bottom)
			)
		)
		(property "Datasheet" "https://www.vishay.com/docs/65529/sqs401en.pdf"
			(at 0 0 90)
			(layer "F.Fab")
			(hide yes)
			(effects
				(font
					(size 1.27 1.27)
					(thickness 0.15)
				)
			)
		)
		(property "Description" "MOSFET, P Channel, 40 V, 16A, 0.047 ohm, PowerPAK 1212-8, Surface Mount"
			(at 0 0 90)
			(layer "F.Fab")
			(hide yes)
			(effects
				(font
					(size 1.27 1.27)
					(thickness 0.15)
				)
			)
		)
		(property "MPN" "SQS401EN-T1_BE3"
			(at 0 0 90)
			(unlocked yes)
			(layer "F.Fab")
			(hide yes)
			(effects
				(font
					(size 1 1)
					(thickness 0.15)
				)
			)
		)
		(property "Manufacturer" "Vishay"
			(at 0 0 90)
			(unlocked yes)
			(layer "F.Fab")
			(hide yes)
			(effects
				(font
					(size 1 1)
					(thickness 0.15)
				)
			)
		)
		(property "Author" "Antmicro"
			(at 0 0 90)
			(unlocked yes)
			(layer "F.Fab")
			(hide yes)
			(effects
				(font
					(size 1 1)
					(thickness 0.15)
				)
			)
		)
		(property "License" "Apache-2.0"
			(at 0 0 90)
			(unlocked yes)
			(layer "F.Fab")
			(hide yes)
			(effects
				(font
					(size 1 1)
					(thickness 0.15)
				)
			)
		)
		(sheetname "/Power/Ideal diode 2/")
		(sheetfile "ideal-diode.kicad_sch")
		(attr smd)
		(fp_line
			(start 1.648 -1.651)
			(end 1.648 -1.317)
			(stroke
				(width 0.15)
				(type solid)
			)
			(layer "F.SilkS")
		)
		(fp_line
			(start -1.651 -1.651)
			(end 1.648 -1.651)
			(stroke
				(width 0.15)
				(type solid)
			)
			(layer "F.SilkS")
		)
		(fp_line
			(start -1.651 -1.651)
			(end -1.651 -1.317)
			(stroke
				(width 0.15)
				(type solid)
			)
			(layer "F.SilkS")
		)
		(fp_line
			(start 1.634 1.3)
			(end 1.634 1.634)
			(stroke
				(width 0.15)
				(type solid)
			)
			(layer "F.SilkS")
		)
		(fp_line
			(start -1.635 1.3)
			(end -1.635 1.634)
			(stroke
				(width 0.15)
				(type solid)
			)
			(layer "F.SilkS")
		)
		(fp_line
			(start -1.635 1.634)
			(end 1.634 1.634)
			(stroke
				(width 0.15)
				(type solid)
			)
			(layer "F.SilkS")
		)
		(fp_circle
			(center -1.9 -1.4)
			(end -1.85 -1.4)
			(stroke
				(width 0.15)
				(type solid)
			)
			(fill yes)
			(layer "F.SilkS")
		)
		(fp_rect
			(start -2 -1.8)
			(end 2 1.798)
			(stroke
				(width 0.05)
				(type solid)
			)
			(fill no)
			(layer "F.CrtYd")
		)
		(fp_line
			(start -1.6425 -1.4175)
			(end -1.4175 -1.6425)
			(stroke
				(width 0.15)
				(type solid)
			)
			(layer "F.Fab")
		)
		(fp_rect
			(start -1.651 -1.651)
			(end 1.648 1.648)
			(stroke
				(width 0.15)
				(type solid)
			)
			(fill no)
			(layer "F.Fab")
		)
		(pad "1" smd rect
			(at -1.436 -0.99 90)
			(size 0.99 0.405)
			(layers "F.Cu" "F.Mask" "F.Paste")
			(net 314 "VCC")
			(pinfunction "S")
			(pintype "passive")
		)
		(pad "2" smd rect
			(at -1.436 -0.332 90)
			(size 0.99 0.405)
			(layers "F.Cu" "F.Mask" "F.Paste")
			(net 314 "VCC")
			(pinfunction "S")
			(pintype "passive")
		)
		(pad "3" smd rect
			(at -1.436 0.33 90)
			(size 0.99 0.405)
			(layers "F.Cu" "F.Mask" "F.Paste")
			(net 314 "VCC")
			(pinfunction "S")
			(pintype "passive")
		)
		(pad "4" smd rect
			(at -1.436 0.988 90)
			(size 0.99 0.405)
			(layers "F.Cu" "F.Mask" "F.Paste")
			(net 156 "Net-(Q3-G)")
			(pinfunction "G")
			(pintype "passive")
		)
		(pad "5" smd custom
			(at 0.557 0 90)
			(size 1.725 2.235)
			(layers "F.Cu" "F.Mask" "F.Paste")
			(net 351 "/Power/+5V_USB")
			(pinfunction "D")
			(pintype "passive")
			(zone_connect 2)
			(options
				(clearance outline)
				(anchor rect)
			)
			(primitives
				(gr_poly
					(pts
						(xy 0.8625 0.1275) (xy 0.8625 -0.1275) (xy 1.3725 -0.1275) (xy 1.3725 -0.5325) (xy 0.8625 -0.5325)
						(xy 0.8625 -0.7875) (xy 1.3725 -0.7875) (xy 1.3725 -1.195) (xy 0.6125 -1.195) (xy 0.6125 1.195)
						(xy 1.3725 1.195) (xy 1.3725 0.7875) (xy 0.8625 0.7875) (xy 0.8625 0.5325) (xy 1.3725 0.5325)
						(xy 1.3725 0.1275)
					)
					(width 0)
					(fill yes)
				)
			)
		)
	)
	(footprint "antmicro-footprints:R_0402_1005Metric"
		(layer "F.Cu")
		(at 110.15 106.55 -90)
		(descr "Resistor SMD 0402")
		(tags "resistor SMD 0402")
		(property "Reference" "R177"
			(at 0.1 2.55 90)
			(layer "F.SilkS")
			(effects
				(font
					(size 0.7 0.7)
					(thickness 0.15)
				)
				(justify left bottom)
			)
		)
		(property "Value" "R_0R_0402"
			(at -1.011843 1.772046 90)
			(layer "F.Fab")
			(hide yes)
			(effects
				(font
					(size 0.7 0.7)
					(thickness 0.15)
				)
				(justify right top)
			)
		)
		(property "Datasheet" "https://industrial.panasonic.com/cdbs/www-data/pdf/RDA0000/AOA0000C301.pdf"
			(at 0 0 90)
			(layer "F.Fab")
			(hide yes)
			(effects
				(font
					(size 1.27 1.27)
					(thickness 0.15)
				)
			)
		)
		(property "Description" "SMD Chip Resistor, Jumper, 0 ohm, 100 mW, 0402 [1005 Metric], Thick Film, General Purpose"
			(at 0 0 90)
			(layer "F.Fab")
			(hide yes)
			(effects
				(font
					(size 1.27 1.27)
					(thickness 0.15)
				)
			)
		)
		(property "MPN" "ERJ2GE0R00X"
			(at 0 0 270)
			(unlocked yes)
			(layer "F.Fab")
			(hide yes)
			(effects
				(font
					(size 1 1)
					(thickness 0.15)
				)
			)
		)
		(property "Manufacturer" "Panasonic"
			(at 0 0 270)
			(unlocked yes)
			(layer "F.Fab")
			(hide yes)
			(effects
				(font
					(size 1 1)
					(thickness 0.15)
				)
			)
		)
		(property "License" "Apache-2.0"
			(at 0 0 270)
			(unlocked yes)
			(layer "F.Fab")
			(hide yes)
			(effects
				(font
					(size 1 1)
					(thickness 0.15)
				)
			)
		)
		(property "Author" "Antmicro"
			(at 0 0 270)
			(unlocked yes)
			(layer "F.Fab")
			(hide yes)
			(effects
				(font
					(size 1 1)
					(thickness 0.15)
				)
			)
		)
		(property "Val" "0R"
			(at 0 0 270)
			(unlocked yes)
			(layer "F.Fab")
			(hide yes)
			(effects
				(font
					(size 1 1)
					(thickness 0.15)
				)
			)
		)
		(property "Tolerance" "~"
			(at 0 0 270)
			(unlocked yes)
			(layer "F.Fab")
			(hide yes)
			(effects
				(font
					(size 1 1)
					(thickness 0.15)
				)
			)
		)
		(property "Current" "1A"
			(at 0 0 270)
			(unlocked yes)
			(layer "F.Fab")
			(hide yes)
			(effects
				(font
					(size 1 1)
					(thickness 0.15)
				)
			)
		)
		(sheetname "/Fan controller/")
		(sheetfile "fan-controller.kicad_sch")
		(attr smd exclude_from_pos_files exclude_from_bom dnp)
		(fp_rect
			(start -0.925 -0.47)
			(end 0.925 0.47)
			(stroke
				(width 0.05)
				(type default)
			)
			(fill no)
			(layer "F.CrtYd")
		)
		(fp_rect
			(start -0.5 -0.25)
			(end 0.5 0.25)
			(stroke
				(width 0.15)
				(type solid)
			)
			(fill no)
			(layer "F.Fab")
		)
		(pad "1" smd roundrect
			(at -0.48 0 270)
			(size 0.59 0.64)
			(layers "F.Cu" "F.Mask" "F.Paste")
			(roundrect_rratio 0.25)
			(net 398 "/Fan controller/D0")
			(pintype "passive")
		)
		(pad "2" smd roundrect
			(at 0.48 0 270)
			(size 0.59 0.64)
			(layers "F.Cu" "F.Mask" "F.Paste")
			(roundrect_rratio 0.25)
			(net 388 "/Fan controller/+5V")
			(pintype "passive")
		)
	)
	(footprint "antmicro-footprints:R_0402_1005Metric"
		(layer "F.Cu")
		(at 101.3 104.25)
		(descr "Resistor SMD 0402")
		(tags "resistor SMD 0402")
		(property "Reference" "R89"
			(at -0.8 15.175 0)
			(layer "F.SilkS")
			(effects
				(font
					(size 0.7 0.7)
					(thickness 0.15)
				)
				(justify left bottom)
			)
		)
		(property "Value" "R_100k_0402"
			(at -1.011843 1.772046 0)
			(layer "F.Fab")
			(hide yes)
			(effects
				(font
					(size 0.7 0.7)
					(thickness 0.15)
				)
				(justify left bottom)
			)
		)
		(property "Datasheet" "https://www.bourns.com/docs/product-datasheets/cr.pdf"
			(at 0 0 0)
			(layer "F.Fab")
			(hide yes)
			(effects
				(font
					(size 1.27 1.27)
					(thickness 0.15)
				)
			)
		)
		(property "Description" "SMD Chip Resistor, 100 kohm, ± 1%, 62.5 mW, 0402 [1005 Metric], Thick Film, General Purpose"
			(at 0 0 0)
			(layer "F.Fab")
			(hide yes)
			(effects
				(font
					(size 1.27 1.27)
					(thickness 0.15)
				)
			)
		)
		(property "MPN" "CR0402-FX-1003GLF"
			(at 0 0 0)
			(unlocked yes)
			(layer "F.Fab")
			(hide yes)
			(effects
				(font
					(size 1 1)
					(thickness 0.15)
				)
			)
		)
		(property "Manufacturer" "Bourns"
			(at 0 0 0)
			(unlocked yes)
			(layer "F.Fab")
			(hide yes)
			(effects
				(font
					(size 1 1)
					(thickness 0.15)
				)
			)
		)
		(property "License" "Apache-2.0"
			(at 0 0 0)
			(unlocked yes)
			(layer "F.Fab")
			(hide yes)
			(effects
				(font
					(size 1 1)
					(thickness 0.15)
				)
			)
		)
		(property "Author" "Antmicro"
			(at 0 0 0)
			(unlocked yes)
			(layer "F.Fab")
			(hide yes)
			(effects
				(font
					(size 1 1)
					(thickness 0.15)
				)
			)
		)
		(property "Val" "100k"
			(at 0 0 0)
			(unlocked yes)
			(layer "F.Fab")
			(hide yes)
			(effects
				(font
					(size 1 1)
					(thickness 0.15)
				)
			)
		)
		(property "Tolerance" "1%"
			(at 0 0 0)
			(unlocked yes)
			(layer "F.Fab")
			(hide yes)
			(effects
				(font
					(size 1 1)
					(thickness 0.15)
				)
			)
		)
		(sheetname "/X710-AT2 Misc/")
		(sheetfile "x710-at2-mics.kicad_sch")
		(attr smd)
		(fp_rect
			(start -0.925 -0.47)
			(end 0.925 0.47)
			(stroke
				(width 0.05)
				(type default)
			)
			(fill no)
			(layer "F.CrtYd")
		)
		(fp_rect
			(start -0.5 -0.25)
			(end 0.5 0.25)
			(stroke
				(width 0.15)
				(type solid)
			)
			(fill no)
			(layer "F.Fab")
		)
		(pad "1" smd roundrect
			(at -0.48 0)
			(size 0.59 0.64)
			(layers "F.Cu" "F.Mask" "F.Paste")
			(roundrect_rratio 0.25)
			(net 28 "GND")
			(pintype "passive")
		)
		(pad "2" smd roundrect
			(at 0.48 0)
			(size 0.59 0.64)
			(layers "F.Cu" "F.Mask" "F.Paste")
			(roundrect_rratio 0.25)
			(net 367 "/X710-AT2 Misc/NCSI.REF_CLK")
			(pintype "passive")
		)
	)
	(footprint "antmicro-footprints:C_0603_1608Metric_EIA"
		(layer "F.Cu")
		(at 51.9 111.6 -90)
		(descr "Capacitor SMD 0603, IPC-7351 Density Level A")
		(tags "Capacitor 0603")
		(property "Reference" "C30"
			(at 1.01 0.47 90)
			(layer "F.SilkS")
			(effects
				(font
					(size 0.7 0.7)
					(thickness 0.15)
				)
				(justify right top)
			)
		)
		(property "Value" "C_22u_16V_0603"
			(at -1.42757 1.770288 90)
			(layer "F.Fab")
			(hide yes)
			(effects
				(font
					(size 0.7 0.7)
					(thickness 0.15)
				)
				(justify right top)
			)
		)
		(property "Datasheet" "https://product.samsungsem.com/mlcc/CL10A226MO7JZN.do"
			(at 0 0 90)
			(layer "F.Fab")
			(hide yes)
			(effects
				(font
					(size 1.27 1.27)
					(thickness 0.15)
				)
			)
		)
		(property "Description" "SMD Multilayer Ceramic Capacitor"
			(at 0 0 90)
			(layer "F.Fab")
			(hide yes)
			(effects
				(font
					(size 1.27 1.27)
					(thickness 0.15)
				)
			)
		)
		(property "MPN" "CL10A226MO7JZNC"
			(at 0 0 270)
			(unlocked yes)
			(layer "F.Fab")
			(hide yes)
			(effects
				(font
					(size 1 1)
					(thickness 0.15)
				)
			)
		)
		(property "Manufacturer" "Samsung Electro-Mechanics"
			(at 0 0 270)
			(unlocked yes)
			(layer "F.Fab")
			(hide yes)
			(effects
				(font
					(size 1 1)
					(thickness 0.15)
				)
			)
		)
		(property "License" "Apache-2.0"
			(at 0 0 270)
			(unlocked yes)
			(layer "F.Fab")
			(hide yes)
			(effects
				(font
					(size 1 1)
					(thickness 0.15)
				)
			)
		)
		(property "Author" "Antmicro"
			(at 0 0 270)
			(unlocked yes)
			(layer "F.Fab")
			(hide yes)
			(effects
				(font
					(size 1 1)
					(thickness 0.15)
				)
			)
		)
		(property "Val" "22u"
			(at 0 0 270)
			(unlocked yes)
			(layer "F.Fab")
			(hide yes)
			(effects
				(font
					(size 1 1)
					(thickness 0.15)
				)
			)
		)
		(property "Voltage" "16V"
			(at 0 0 270)
			(unlocked yes)
			(layer "F.Fab")
			(hide yes)
			(effects
				(font
					(size 1 1)
					(thickness 0.15)
				)
			)
		)
		(property "Dielectric" ""
			(at 0 0 270)
			(unlocked yes)
			(layer "F.Fab")
			(hide yes)
			(effects
				(font
					(size 1 1)
					(thickness 0.15)
				)
			)
		)
		(property "Public" "False"
			(at 0 0 270)
			(unlocked yes)
			(layer "F.Fab")
			(hide yes)
			(effects
				(font
					(size 1 1)
					(thickness 0.15)
				)
			)
		)
		(sheetname "/Power/")
		(sheetfile "power.kicad_sch")
		(attr smd)
		(fp_line
			(start -0.15 0.55)
			(end 0.15 0.55)
			(stroke
				(width 0.15)
				(type solid)
			)
			(layer "F.SilkS")
		)
		(fp_line
			(start -0.15 -0.55)
			(end 0.15 -0.55)
			(stroke
				(width 0.15)
				(type solid)
			)
			(layer "F.SilkS")
		)
		(fp_rect
			(start -1.25 -0.65)
			(end 1.25 0.65)
			(stroke
				(width 0.05)
				(type solid)
			)
			(fill no)
			(layer "F.CrtYd")
		)
		(fp_rect
			(start -0.8 -0.45)
			(end 0.8 0.45)
			(stroke
				(width 0.15)
				(type solid)
			)
			(fill no)
			(layer "F.Fab")
		)
		(pad "1" smd roundrect
			(at -0.7 0 270)
			(size 0.8 1.1)
			(layers "F.Cu" "F.Mask" "F.Paste")
			(roundrect_rratio 0.2)
			(net 28 "GND")
			(pintype "passive")
		)
		(pad "2" smd roundrect
			(at 0.7 0 270)
			(size 0.8 1.1)
			(layers "F.Cu" "F.Mask" "F.Paste")
			(roundrect_rratio 0.2)
			(net 314 "VCC")
			(pintype "passive")
		)
	)
	(footprint "antmicro-footprints:SOD-123FL"
		(layer "F.Cu")
		(at 68.1 62.02)
		(property "Reference" "D1"
			(at 2.38 0.35 0)
			(layer "F.SilkS")
			(effects
				(font
					(size 0.7 0.7)
					(thickness 0.15)
				)
				(justify left bottom)
			)
		)
		(property "Value" "SZSMF4L14AT3G"
			(at 0 1.967 0)
			(layer "F.Fab")
			(hide yes)
			(effects
				(font
					(size 0.7 0.7)
					(thickness 0.15)
				)
				(justify left bottom)
			)
		)
		(property "Datasheet" "https://www.mouser.com/datasheet/2/240/media-3320461.pdf"
			(at 0 0 0)
			(layer "F.Fab")
			(hide yes)
			(effects
				(font
					(size 1.27 1.27)
					(thickness 0.15)
				)
			)
		)
		(property "Description" "ESD, TVS Diode, 14V, UNI, 400W, SOD-123FL"
			(at 0 0 0)
			(layer "F.Fab")
			(hide yes)
			(effects
				(font
					(size 1.27 1.27)
					(thickness 0.15)
				)
			)
		)
		(property "MPN" "SZSMF4L12AT3G"
			(at 0 0 0)
			(unlocked yes)
			(layer "F.Fab")
			(hide yes)
			(effects
				(font
					(size 1 1)
					(thickness 0.15)
				)
			)
		)
		(property "Author" "Antmicro"
			(at 0 0 0)
			(unlocked yes)
			(layer "F.Fab")
			(hide yes)
			(effects
				(font
					(size 1 1)
					(thickness 0.15)
				)
			)
		)
		(property "License" "Apache-2.0"
			(at 0 0 0)
			(unlocked yes)
			(layer "F.Fab")
			(hide yes)
			(effects
				(font
					(size 1 1)
					(thickness 0.15)
				)
			)
		)
		(property "Manufacturer" "Littelfuse"
			(at 0 0 0)
			(unlocked yes)
			(layer "F.Fab")
			(hide yes)
			(effects
				(font
					(size 1 1)
					(thickness 0.15)
				)
			)
		)
		(sheetname "/Power/")
		(sheetfile "power.kicad_sch")
		(attr smd)
		(fp_line
			(start -2.3 -1.1)
			(end -2.3 1.1)
			(stroke
				(width 0.15)
				(type solid)
			)
			(layer "F.SilkS")
		)
		(fp_line
			(start -2.3 1.1)
			(end 0 1.1)
			(stroke
				(width 0.15)
				(type solid)
			)
			(layer "F.SilkS")
		)
		(fp_line
			(start 0 -1.1)
			(end -2.3 -1.1)
			(stroke
				(width 0.15)
				(type solid)
			)
			(layer "F.SilkS")
		)
		(fp_rect
			(start -2.35 -1.125)
			(end 2.35 1.125)
			(stroke
				(width 0.05)
				(type solid)
			)
			(fill no)
			(layer "F.CrtYd")
		)
		(fp_rect
			(start -1.825 -0.875)
			(end 1.824 0.873)
			(stroke
				(width 0.15)
				(type solid)
			)
			(fill no)
			(layer "F.Fab")
		)
		(fp_rect
			(start -0.775 -0.875)
			(end -0.525 0.875)
			(stroke
				(width 0.15)
				(type solid)
			)
			(fill yes)
			(layer "F.Fab")
		)
		(pad "1" smd roundrect
			(at -1.43 0)
			(size 1.34 1.8)
			(layers "F.Cu" "F.Mask" "F.Paste")
			(roundrect_rratio 0.14)
			(net 350 "/Power/+12V_IN")
			(pinfunction "C")
			(pintype "passive")
		)
		(pad "2" smd roundrect
			(at 1.429 0)
			(size 1.34 1.8)
			(layers "F.Cu" "F.Mask" "F.Paste")
			(roundrect_rratio 0.14)
			(net 28 "GND")
			(pinfunction "A")
			(pintype "passive")
		)
	)
	(footprint "antmicro-footprints:R_0603_1608Metric"
		(layer "F.Cu")
		(at 63.2 107.2)
		(descr "Resistor SMD 0603")
		(tags "resistor SMD 0603")
		(property "Reference" "R19"
			(at -0.16 -1.41 0)
			(layer "F.SilkS")
			(effects
				(font
					(size 0.7 0.7)
					(thickness 0.15)
				)
				(justify left bottom)
			)
		)
		(property "Value" "R_0R_22.4A_0603"
			(at 0 1.6 0)
			(layer "F.Fab")
			(hide yes)
			(effects
				(font
					(size 0.7 0.7)
					(thickness 0.15)
				)
				(justify left bottom)
			)
		)
		(property "Datasheet" "https://fscdn.rohm.com/en/products/databook/datasheet/passive/resistor/chip_resistor/pmr-jpw-e.pdf"
			(at 0 0 0)
			(layer "F.Fab")
			(hide yes)
			(effects
				(font
					(size 1.27 1.27)
					(thickness 0.15)
				)
			)
		)
		(property "Description" "SMD Chip Resistor"
			(at 0 0 0)
			(layer "F.Fab")
			(hide yes)
			(effects
				(font
					(size 1.27 1.27)
					(thickness 0.15)
				)
			)
		)
		(property "MPN" "PMR03EZPJ000"
			(at 0 0 0)
			(unlocked yes)
			(layer "F.Fab")
			(hide yes)
			(effects
				(font
					(size 1 1)
					(thickness 0.15)
				)
			)
		)
		(property "Manufacturer" "ROHM Semiconductor"
			(at 0 0 0)
			(unlocked yes)
			(layer "F.Fab")
			(hide yes)
			(effects
				(font
					(size 1 1)
					(thickness 0.15)
				)
			)
		)
		(property "Val" "0R"
			(at 0 0 0)
			(unlocked yes)
			(layer "F.Fab")
			(hide yes)
			(effects
				(font
					(size 1 1)
					(thickness 0.15)
				)
			)
		)
		(property "Max. Curr." "22.4A"
			(at 0 0 0)
			(unlocked yes)
			(layer "F.Fab")
			(hide yes)
			(effects
				(font
					(size 1 1)
					(thickness 0.15)
				)
			)
		)
		(property "Author" "Antmicro"
			(at 0 0 0)
			(unlocked yes)
			(layer "F.Fab")
			(hide yes)
			(effects
				(font
					(size 1 1)
					(thickness 0.15)
				)
			)
		)
		(property "License" "Apache-2.0"
			(at 0 0 0)
			(unlocked yes)
			(layer "F.Fab")
			(hide yes)
			(effects
				(font
					(size 1 1)
					(thickness 0.15)
				)
			)
		)
		(property "Tolerance" "template_tolerance"
			(at 0 0 0)
			(unlocked yes)
			(layer "F.Fab")
			(hide yes)
			(effects
				(font
					(size 1 1)
					(thickness 0.15)
				)
			)
		)
		(sheetname "/Power/")
		(sheetfile "power.kicad_sch")
		(attr smd)
		(fp_line
			(start -0.15 -0.4)
			(end 0.15 -0.4)
			(stroke
				(width 0.15)
				(type solid)
			)
			(layer "F.SilkS")
		)
		(fp_line
			(start -0.15 0.4)
			(end 0.15 0.4)
			(stroke
				(width 0.15)
				(type solid)
			)
			(layer "F.SilkS")
		)
		(fp_rect
			(start -1.25 -0.65)
			(end 1.25 0.65)
			(stroke
				(width 0.05)
				(type solid)
			)
			(fill no)
			(layer "F.CrtYd")
		)
		(fp_rect
			(start -0.8 -0.4)
			(end 0.8 0.4)
			(stroke
				(width 0.15)
				(type solid)
			)
			(fill no)
			(layer "F.Fab")
		)
		(pad "1" smd roundrect
			(at -0.7 0)
			(size 0.8 1)
			(layers "F.Cu" "F.Mask" "F.Paste")
			(roundrect_rratio 0.2)
			(net 312 "/Power/+1V0_OUT")
			(pintype "passive")
		)
		(pad "2" smd roundrect
			(at 0.7 0)
			(size 0.8 1)
			(layers "F.Cu" "F.Mask" "F.Paste")
			(roundrect_rratio 0.2)
			(net 302 "+1V0")
			(pintype "passive")
		)
	)
	(footprint "antmicro-footprints:C_0603_1608Metric_EIA"
		(layer "F.Cu")
		(at 60.649999 100.850001)
		(descr "Capacitor SMD 0603, IPC-7351 Density Level A")
		(tags "Capacitor 0603")
		(property "Reference" "C206"
			(at -4.039999 -1.140001 0)
			(layer "F.SilkS")
			(effects
				(font
					(size 0.7 0.7)
					(thickness 0.15)
				)
				(justify left bottom)
			)
		)
		(property "Value" "C_22u_16V_0603"
			(at -1.42757 1.770288 0)
			(layer "F.Fab")
			(hide yes)
			(effects
				(font
					(size 0.7 0.7)
					(thickness 0.15)
				)
				(justify left bottom)
			)
		)
		(property "Datasheet" "https://product.samsungsem.com/mlcc/CL10A226MO7JZN.do"
			(at 0 0 0)
			(layer "F.Fab")
			(hide yes)
			(effects
				(font
					(size 1.27 1.27)
					(thickness 0.15)
				)
			)
		)
		(property "Description" "SMD Multilayer Ceramic Capacitor"
			(at 0 0 0)
			(layer "F.Fab")
			(hide yes)
			(effects
				(font
					(size 1.27 1.27)
					(thickness 0.15)
				)
			)
		)
		(property "MPN" "CL10A226MO7JZNC"
			(at 0 0 0)
			(unlocked yes)
			(layer "F.Fab")
			(hide yes)
			(effects
				(font
					(size 1 1)
					(thickness 0.15)
				)
			)
		)
		(property "Manufacturer" "Samsung Electro-Mechanics"
			(at 0 0 0)
			(unlocked yes)
			(layer "F.Fab")
			(hide yes)
			(effects
				(font
					(size 1 1)
					(thickness 0.15)
				)
			)
		)
		(property "License" "Apache-2.0"
			(at 0 0 0)
			(unlocked yes)
			(layer "F.Fab")
			(hide yes)
			(effects
				(font
					(size 1 1)
					(thickness 0.15)
				)
			)
		)
		(property "Author" "Antmicro"
			(at 0 0 0)
			(unlocked yes)
			(layer "F.Fab")
			(hide yes)
			(effects
				(font
					(size 1 1)
					(thickness 0.15)
				)
			)
		)
		(property "Val" "22u"
			(at 0 0 0)
			(unlocked yes)
			(layer "F.Fab")
			(hide yes)
			(effects
				(font
					(size 1 1)
					(thickness 0.15)
				)
			)
		)
		(property "Voltage" "16V"
			(at 0 0 0)
			(unlocked yes)
			(layer "F.Fab")
			(hide yes)
			(effects
				(font
					(size 1 1)
					(thickness 0.15)
				)
			)
		)
		(property "Dielectric" ""
			(at 0 0 0)
			(unlocked yes)
			(layer "F.Fab")
			(hide yes)
			(effects
				(font
					(size 1 1)
					(thickness 0.15)
				)
			)
		)
		(property "Public" "False"
			(at 0 0 0)
			(unlocked yes)
			(layer "F.Fab")
			(hide yes)
			(effects
				(font
					(size 1 1)
					(thickness 0.15)
				)
			)
		)
		(sheetname "/Power/")
		(sheetfile "power.kicad_sch")
		(attr smd)
		(fp_line
			(start -0.15 -0.55)
			(end 0.15 -0.55)
			(stroke
				(width 0.15)
				(type solid)
			)
			(layer "F.SilkS")
		)
		(fp_line
			(start -0.15 0.55)
			(end 0.15 0.55)
			(stroke
				(width 0.15)
				(type solid)
			)
			(layer "F.SilkS")
		)
		(fp_rect
			(start -1.25 -0.65)
			(end 1.25 0.65)
			(stroke
				(width 0.05)
				(type solid)
			)
			(fill no)
			(layer "F.CrtYd")
		)
		(fp_rect
			(start -0.8 -0.45)
			(end 0.8 0.45)
			(stroke
				(width 0.15)
				(type solid)
			)
			(fill no)
			(layer "F.Fab")
		)
		(pad "1" smd roundrect
			(at -0.7 0)
			(size 0.8 1.1)
			(layers "F.Cu" "F.Mask" "F.Paste")
			(roundrect_rratio 0.2)
			(net 28 "GND")
			(pintype "passive")
		)
		(pad "2" smd roundrect
			(at 0.7 0)
			(size 0.8 1.1)
			(layers "F.Cu" "F.Mask" "F.Paste")
			(roundrect_rratio 0.2)
			(net 310 "/Power/+1V88_OUT")
			(pintype "passive")
		)
	)
	(footprint "antmicro-footprints:C_0402_1005Metric"
		(layer "F.Cu")
		(at 86.833 63.7)
		(descr "Capacitor SMD 0402")
		(tags "capacitor SMD 0402")
		(property "Reference" "C202"
			(at -1.543 -0.48 0)
			(layer "F.SilkS")
			(effects
				(font
					(size 0.7 0.7)
					(thickness 0.15)
				)
				(justify left bottom)
			)
		)
		(property "Value" "C_100n_0402"
			(at -1.022927 2.155213 0)
			(layer "F.Fab")
			(hide yes)
			(effects
				(font
					(size 0.7 0.7)
					(thickness 0.15)
				)
				(justify left bottom)
			)
		)
		(property "Datasheet" "https://www.murata.com/products/productdetail?partno=GRM155R61H104KE14%23"
			(at 0 0 0)
			(layer "F.Fab")
			(hide yes)
			(effects
				(font
					(size 1.27 1.27)
					(thickness 0.15)
				)
			)
		)
		(property "Description" "SMD Multilayer Ceramic Capacitor, 0.1 µF, 50 V, 0402 [1005 Metric], ± 10%, X5R, GRM Series"
			(at 0 0 0)
			(layer "F.Fab")
			(hide yes)
			(effects
				(font
					(size 1.27 1.27)
					(thickness 0.15)
				)
			)
		)
		(property "MPN" "GRM155R61H104KE14D"
			(at 0 0 0)
			(unlocked yes)
			(layer "F.Fab")
			(hide yes)
			(effects
				(font
					(size 1 1)
					(thickness 0.15)
				)
			)
		)
		(property "Manufacturer" "Murata"
			(at 0 0 0)
			(unlocked yes)
			(layer "F.Fab")
			(hide yes)
			(effects
				(font
					(size 1 1)
					(thickness 0.15)
				)
			)
		)
		(property "License" "Apache-2.0"
			(at 0 0 0)
			(unlocked yes)
			(layer "F.Fab")
			(hide yes)
			(effects
				(font
					(size 1 1)
					(thickness 0.15)
				)
			)
		)
		(property "Author" "Antmicro"
			(at 0 0 0)
			(unlocked yes)
			(layer "F.Fab")
			(hide yes)
			(effects
				(font
					(size 1 1)
					(thickness 0.15)
				)
			)
		)
		(property "Val" "100n"
			(at 0 0 0)
			(unlocked yes)
			(layer "F.Fab")
			(hide yes)
			(effects
				(font
					(size 1 1)
					(thickness 0.15)
				)
			)
		)
		(property "Voltage" "50V"
			(at 0 0 0)
			(unlocked yes)
			(layer "F.Fab")
			(hide yes)
			(effects
				(font
					(size 1 1)
					(thickness 0.15)
				)
			)
		)
		(property "Dielectric" "X5R"
			(at 0 0 0)
			(unlocked yes)
			(layer "F.Fab")
			(hide yes)
			(effects
				(font
					(size 1 1)
					(thickness 0.15)
				)
			)
		)
		(sheetname "/Power/Ideal diode 2/")
		(sheetfile "ideal-diode.kicad_sch")
		(attr smd)
		(fp_rect
			(start -0.925 -0.47)
			(end 0.925 0.47)
			(stroke
				(width 0.05)
				(type default)
			)
			(fill no)
			(layer "F.CrtYd")
		)
		(fp_line
			(start -0.494 -0.25)
			(end 0.504 -0.25)
			(stroke
				(width 0.15)
				(type solid)
			)
			(layer "F.Fab")
		)
		(fp_line
			(start -0.494 0.248)
			(end -0.494 -0.25)
			(stroke
				(width 0.15)
				(type solid)
			)
			(layer "F.Fab")
		)
		(fp_line
			(start 0.504 -0.25)
			(end 0.504 0.248)
			(stroke
				(width 0.15)
				(type solid)
			)
			(layer "F.Fab")
		)
		(fp_line
			(start 0.504 0.248)
			(end -0.494 0.248)
			(stroke
				(width 0.15)
				(type solid)
			)
			(layer "F.Fab")
		)
		(pad "1" smd roundrect
			(at -0.48 0)
			(size 0.59 0.64)
			(layers "F.Cu" "F.Mask" "F.Paste")
			(roundrect_rratio 0.25)
			(net 28 "GND")
			(pintype "passive")
		)
		(pad "2" smd roundrect
			(at 0.48 0)
			(size 0.59 0.64)
			(layers "F.Cu" "F.Mask" "F.Paste")
			(roundrect_rratio 0.25)
			(net 351 "/Power/+5V_USB")
			(pintype "passive")
		)
	)
	(footprint "antmicro-footprints:C_0402_1005Metric"
		(layer "F.Cu")
		(at 115.9 101.100001 180)
		(descr "Capacitor SMD 0402")
		(tags "capacitor SMD 0402")
		(property "Reference" "C210"
			(at -0.82 -0.439999 0)
			(layer "F.SilkS")
			(effects
				(font
					(size 0.7 0.7)
					(thickness 0.15)
				)
				(justify left bottom)
			)
		)
		(property "Value" "C_10n_0402"
			(at -1.022927 2.155213 0)
			(layer "F.Fab")
			(hide yes)
			(effects
				(font
					(size 0.7 0.7)
					(thickness 0.15)
				)
				(justify right top)
			)
		)
		(property "Datasheet" "https://www.murata.com/products/productdetail?partno=GRM155R71H103KA88%23"
			(at 0 0 0)
			(layer "F.Fab")
			(hide yes)
			(effects
				(font
					(size 1.27 1.27)
					(thickness 0.15)
				)
			)
		)
		(property "Description" "SMD Multilayer Ceramic Capacitor, 10000 pF, 50 V, 0402 [1005 Metric], ± 10%, X7R, GRM Series"
			(at 0 0 0)
			(layer "F.Fab")
			(hide yes)
			(effects
				(font
					(size 1.27 1.27)
					(thickness 0.15)
				)
			)
		)
		(property "MPN" "GRM155R71H103KA88D"
			(at 0 0 180)
			(unlocked yes)
			(layer "F.Fab")
			(hide yes)
			(effects
				(font
					(size 1 1)
					(thickness 0.15)
				)
			)
		)
		(property "Manufacturer" "Murata"
			(at 0 0 180)
			(unlocked yes)
			(layer "F.Fab")
			(hide yes)
			(effects
				(font
					(size 1 1)
					(thickness 0.15)
				)
			)
		)
		(property "License" "Apache-2.0"
			(at 0 0 180)
			(unlocked yes)
			(layer "F.Fab")
			(hide yes)
			(effects
				(font
					(size 1 1)
					(thickness 0.15)
				)
			)
		)
		(property "Author" "Antmicro"
			(at 0 0 180)
			(unlocked yes)
			(layer "F.Fab")
			(hide yes)
			(effects
				(font
					(size 1 1)
					(thickness 0.15)
				)
			)
		)
		(property "Val" "10n"
			(at 0 0 180)
			(unlocked yes)
			(layer "F.Fab")
			(hide yes)
			(effects
				(font
					(size 1 1)
					(thickness 0.15)
				)
			)
		)
		(property "Voltage" "50V"
			(at 0 0 180)
			(unlocked yes)
			(layer "F.Fab")
			(hide yes)
			(effects
				(font
					(size 1 1)
					(thickness 0.15)
				)
			)
		)
		(property "Dielectric" "X7R"
			(at 0 0 180)
			(unlocked yes)
			(layer "F.Fab")
			(hide yes)
			(effects
				(font
					(size 1 1)
					(thickness 0.15)
				)
			)
		)
		(sheetname "/Fan controller/")
		(sheetfile "fan-controller.kicad_sch")
		(attr smd exclude_from_pos_files exclude_from_bom dnp)
		(fp_rect
			(start -0.925 -0.47)
			(end 0.925 0.47)
			(stroke
				(width 0.05)
				(type default)
			)
			(fill no)
			(layer "F.CrtYd")
		)
		(fp_line
			(start 0.504 0.248)
			(end -0.494 0.248)
			(stroke
				(width 0.15)
				(type solid)
			)
			(layer "F.Fab")
		)
		(fp_line
			(start 0.504 -0.25)
			(end 0.504 0.248)
			(stroke
				(width 0.15)
				(type solid)
			)
			(layer "F.Fab")
		)
		(fp_line
			(start -0.494 0.248)
			(end -0.494 -0.25)
			(stroke
				(width 0.15)
				(type solid)
			)
			(layer "F.Fab")
		)
		(fp_line
			(start -0.494 -0.25)
			(end 0.504 -0.25)
			(stroke
				(width 0.15)
				(type solid)
			)
			(layer "F.Fab")
		)
		(pad "1" smd roundrect
			(at -0.48 0 180)
			(size 0.59 0.64)
			(layers "F.Cu" "F.Mask" "F.Paste")
			(roundrect_rratio 0.25)
			(net 28 "GND")
			(pintype "passive")
		)
		(pad "2" smd roundrect
			(at 0.48 0 180)
			(size 0.59 0.64)
			(layers "F.Cu" "F.Mask" "F.Paste")
			(roundrect_rratio 0.25)
			(net 386 "Net-(U6-BYPASS)")
			(pintype "passive")
		)
	)
	(footprint "antmicro-footprints:C_0402_1005Metric"
		(layer "F.Cu")
		(at 109.15 106.55 90)
		(descr "Capacitor SMD 0402")
		(tags "capacitor SMD 0402")
		(property "Reference" "C213"
			(at -0.1 -2.6 90)
			(layer "F.SilkS")
			(effects
				(font
					(size 0.7 0.7)
					(thickness 0.15)
				)
				(justify left bottom)
			)
		)
		(property "Value" "C_470p_0402"
			(at -1.022927 2.155213 90)
			(layer "F.Fab")
			(hide yes)
			(effects
				(font
					(size 0.7 0.7)
					(thickness 0.15)
				)
				(justify left bottom)
			)
		)
		(property "Datasheet" "https://www.passivecomponent.com/wp-content/uploads/datasheet/WTC_MLCC_General_Purpose.pdf"
			(at 0 0 90)
			(layer "F.Fab")
			(hide yes)
			(effects
				(font
					(size 1.27 1.27)
					(thickness 0.15)
				)
			)
		)
		(property "Description" "SMD Multilayer Ceramic Capacitor, General Purpose, 470 pF, 25 V, 0402 [1005 Metric], ± 10%, X7R"
			(at 0 0 90)
			(layer "F.Fab")
			(hide yes)
			(effects
				(font
					(size 1.27 1.27)
					(thickness 0.15)
				)
			)
		)
		(property "MPN" "0402B471K250CT"
			(at 0 0 90)
			(unlocked yes)
			(layer "F.Fab")
			(hide yes)
			(effects
				(font
					(size 1 1)
					(thickness 0.15)
				)
			)
		)
		(property "Manufacturer" "Walsin"
			(at 0 0 90)
			(unlocked yes)
			(layer "F.Fab")
			(hide yes)
			(effects
				(font
					(size 1 1)
					(thickness 0.15)
				)
			)
		)
		(property "License" "Apache-2.0"
			(at 0 0 90)
			(unlocked yes)
			(layer "F.Fab")
			(hide yes)
			(effects
				(font
					(size 1 1)
					(thickness 0.15)
				)
			)
		)
		(property "Author" "Antmicro"
			(at 0 0 90)
			(unlocked yes)
			(layer "F.Fab")
			(hide yes)
			(effects
				(font
					(size 1 1)
					(thickness 0.15)
				)
			)
		)
		(property "Val" "470p"
			(at 0 0 90)
			(unlocked yes)
			(layer "F.Fab")
			(hide yes)
			(effects
				(font
					(size 1 1)
					(thickness 0.15)
				)
			)
		)
		(property "Voltage" "25V"
			(at 0 0 90)
			(unlocked yes)
			(layer "F.Fab")
			(hide yes)
			(effects
				(font
					(size 1 1)
					(thickness 0.15)
				)
			)
		)
		(property "Dielectric" "X7R"
			(at 0 0 90)
			(unlocked yes)
			(layer "F.Fab")
			(hide yes)
			(effects
				(font
					(size 1 1)
					(thickness 0.15)
				)
			)
		)
		(sheetname "/Fan controller/")
		(sheetfile "fan-controller.kicad_sch")
		(attr smd exclude_from_pos_files exclude_from_bom dnp)
		(fp_rect
			(start -0.925 -0.47)
			(end 0.925 0.47)
			(stroke
				(width 0.05)
				(type default)
			)
			(fill no)
			(layer "F.CrtYd")
		)
		(fp_line
			(start 0.504 -0.25)
			(end 0.504 0.248)
			(stroke
				(width 0.15)
				(type solid)
			)
			(layer "F.Fab")
		)
		(fp_line
			(start -0.494 -0.25)
			(end 0.504 -0.25)
			(stroke
				(width 0.15)
				(type solid)
			)
			(layer "F.Fab")
		)
		(fp_line
			(start 0.504 0.248)
			(end -0.494 0.248)
			(stroke
				(width 0.15)
				(type solid)
			)
			(layer "F.Fab")
		)
		(fp_line
			(start -0.494 0.248)
			(end -0.494 -0.25)
			(stroke
				(width 0.15)
				(type solid)
			)
			(layer "F.Fab")
		)
		(pad "1" smd roundrect
			(at -0.48 0 90)
			(size 0.59 0.64)
			(layers "F.Cu" "F.Mask" "F.Paste")
			(roundrect_rratio 0.25)
			(net 28 "GND")
			(pintype "passive")
		)
		(pad "2" smd roundrect
			(at 0.48 0 90)
			(size 0.59 0.64)
			(layers "F.Cu" "F.Mask" "F.Paste")
			(roundrect_rratio 0.25)
			(net 387 "/Fan controller/FREQ")
			(pintype "passive")
		)
	)
	(footprint "antmicro-footprints:R_0402_1005Metric"
		(layer "F.Cu")
		(at 54.431 82.764 90)
		(descr "Resistor SMD 0402")
		(tags "resistor SMD 0402")
		(property "Reference" "R54"
			(at -0.926 -0.321 90)
			(layer "F.SilkS")
			(effects
				(font
					(size 0.7 0.7)
					(thickness 0.15)
				)
				(justify left bottom)
			)
		)
		(property "Value" "R_8k2_0402"
			(at -1.011843 1.772046 90)
			(layer "F.Fab")
			(hide yes)
			(effects
				(font
					(size 0.7 0.7)
					(thickness 0.15)
				)
				(justify left bottom)
			)
		)
		(property "Datasheet" "https://www.bourns.com/docs/product-datasheets/cr.pdf"
			(at 0 0 90)
			(layer "F.Fab")
			(hide yes)
			(effects
				(font
					(size 1.27 1.27)
					(thickness 0.15)
				)
			)
		)
		(property "Description" "SMD Chip Resistor"
			(at 0 0 90)
			(layer "F.Fab")
			(hide yes)
			(effects
				(font
					(size 1.27 1.27)
					(thickness 0.15)
				)
			)
		)
		(property "MPN" "CR0402-FX-8201GLF"
			(at 0 0 90)
			(unlocked yes)
			(layer "F.Fab")
			(hide yes)
			(effects
				(font
					(size 1 1)
					(thickness 0.15)
				)
			)
		)
		(property "Manufacturer" "Bourns"
			(at 0 0 90)
			(unlocked yes)
			(layer "F.Fab")
			(hide yes)
			(effects
				(font
					(size 1 1)
					(thickness 0.15)
				)
			)
		)
		(property "License" "Apache-2.0"
			(at 0 0 90)
			(unlocked yes)
			(layer "F.Fab")
			(hide yes)
			(effects
				(font
					(size 1 1)
					(thickness 0.15)
				)
			)
		)
		(property "Author" "Antmicro"
			(at 0 0 90)
			(unlocked yes)
			(layer "F.Fab")
			(hide yes)
			(effects
				(font
					(size 1 1)
					(thickness 0.15)
				)
			)
		)
		(property "Val" "8k2"
			(at 0 0 90)
			(unlocked yes)
			(layer "F.Fab")
			(hide yes)
			(effects
				(font
					(size 1 1)
					(thickness 0.15)
				)
			)
		)
		(property "Tolerance" "1%"
			(at 0 0 90)
			(unlocked yes)
			(layer "F.Fab")
			(hide yes)
			(effects
				(font
					(size 1 1)
					(thickness 0.15)
				)
			)
		)
		(sheetname "/X710-AT2 PCIe/")
		(sheetfile "x710-at2-pcie.kicad_sch")
		(attr smd)
		(fp_rect
			(start -0.925 -0.47)
			(end 0.925 0.47)
			(stroke
				(width 0.05)
				(type default)
			)
			(fill no)
			(layer "F.CrtYd")
		)
		(fp_rect
			(start -0.5 -0.25)
			(end 0.5 0.25)
			(stroke
				(width 0.15)
				(type solid)
			)
			(fill no)
			(layer "F.Fab")
		)
		(pad "1" smd roundrect
			(at -0.48 0 90)
			(size 0.59 0.64)
			(layers "F.Cu" "F.Mask" "F.Paste")
			(roundrect_rratio 0.25)
			(net 28 "GND")
			(pintype "passive")
		)
		(pad "2" smd roundrect
			(at 0.48 0 90)
			(size 0.59 0.64)
			(layers "F.Cu" "F.Mask" "F.Paste")
			(roundrect_rratio 0.25)
			(net 16 "/X710-AT2 PCIe/PCIe_JTAG.JTCK")
			(pintype "passive")
		)
	)
	(footprint "antmicro-footprints:R_0402_1005Metric"
		(layer "F.Cu")
		(at 54.099998 100.55 -90)
		(descr "Resistor SMD 0402")
		(tags "resistor SMD 0402")
		(property "Reference" "R18"
			(at -1.09 3.029998 90)
			(layer "F.SilkS")
			(effects
				(font
					(size 0.7 0.7)
					(thickness 0.15)
				)
				(justify right top)
			)
		)
		(property "Value" "R_30k_0402"
			(at -1.011843 1.772046 90)
			(layer "F.Fab")
			(hide yes)
			(effects
				(font
					(size 0.7 0.7)
					(thickness 0.15)
				)
				(justify right top)
			)
		)
		(property "Datasheet" "https://www.bourns.com/docs/product-datasheets/cr.pdf"
			(at 0 0 90)
			(layer "F.Fab")
			(hide yes)
			(effects
				(font
					(size 1.27 1.27)
					(thickness 0.15)
				)
			)
		)
		(property "Description" "SMD Chip Resistor, 30 kohm, ± 1%, 63 mW, 0402 [1005 Metric], Thick Film, General Purpose"
			(at 0 0 90)
			(layer "F.Fab")
			(hide yes)
			(effects
				(font
					(size 1.27 1.27)
					(thickness 0.15)
				)
			)
		)
		(property "MPN" "CR0402-FX-3002GLF"
			(at 0 0 270)
			(unlocked yes)
			(layer "F.Fab")
			(hide yes)
			(effects
				(font
					(size 1 1)
					(thickness 0.15)
				)
			)
		)
		(property "Manufacturer" "Bourns"
			(at 0 0 270)
			(unlocked yes)
			(layer "F.Fab")
			(hide yes)
			(effects
				(font
					(size 1 1)
					(thickness 0.15)
				)
			)
		)
		(property "License" "Apache-2.0"
			(at 0 0 270)
			(unlocked yes)
			(layer "F.Fab")
			(hide yes)
			(effects
				(font
					(size 1 1)
					(thickness 0.15)
				)
			)
		)
		(property "Author" "Antmicro"
			(at 0 0 270)
			(unlocked yes)
			(layer "F.Fab")
			(hide yes)
			(effects
				(font
					(size 1 1)
					(thickness 0.15)
				)
			)
		)
		(property "Val" "30k"
			(at 0 0 270)
			(unlocked yes)
			(layer "F.Fab")
			(hide yes)
			(effects
				(font
					(size 1 1)
					(thickness 0.15)
				)
			)
		)
		(property "Tolerance" "1%"
			(at 0 0 270)
			(unlocked yes)
			(layer "F.Fab")
			(hide yes)
			(effects
				(font
					(size 1 1)
					(thickness 0.15)
				)
			)
		)
		(sheetname "/Power/")
		(sheetfile "power.kicad_sch")
		(attr smd)
		(fp_rect
			(start -0.925 -0.47)
			(end 0.925 0.47)
			(stroke
				(width 0.05)
				(type default)
			)
			(fill no)
			(layer "F.CrtYd")
		)
		(fp_rect
			(start -0.5 -0.25)
			(end 0.5 0.25)
			(stroke
				(width 0.15)
				(type solid)
			)
			(fill no)
			(layer "F.Fab")
		)
		(pad "1" smd roundrect
			(at -0.48 0 270)
			(size 0.59 0.64)
			(layers "F.Cu" "F.Mask" "F.Paste")
			(roundrect_rratio 0.25)
			(net 28 "GND")
			(pintype "passive")
		)
		(pad "2" smd roundrect
			(at 0.48 0 270)
			(size 0.59 0.64)
			(layers "F.Cu" "F.Mask" "F.Paste")
			(roundrect_rratio 0.25)
			(net 330 "/Power/1V88_FB")
			(pintype "passive")
		)
	)
	(footprint "antmicro-footprints:L_Bourns-SRP2512A"
		(layer "F.Cu")
		(at 70.1 100.95)
		(property "Reference" "L9"
			(at -2.92 1.71 180)
			(layer "F.SilkS")
			(effects
				(font
					(size 0.7 0.7)
					(thickness 0.15)
				)
				(justify left bottom)
			)
		)
		(property "Value" "L_4u7_1.55A_Bourns-SRP2512A"
			(at 0 2.25 180)
			(layer "F.Fab")
			(hide yes)
			(effects
				(font
					(size 0.7 0.7)
					(thickness 0.15)
				)
				(justify left bottom)
			)
		)
		(property "Datasheet" "https://www.bourns.com/docs/Product-Datasheets/srp2512a.pdf"
			(at 0 0 0)
			(layer "F.Fab")
			(hide yes)
			(effects
				(font
					(size 1.27 1.27)
					(thickness 0.15)
				)
			)
		)
		(property "Description" "4.7 µH Shielded Drum Core, Wirewound Inductor 1.55 A 235mOhm Max 1008 (2520 Metric)"
			(at 0 0 0)
			(layer "F.Fab")
			(hide yes)
			(effects
				(font
					(size 1.27 1.27)
					(thickness 0.15)
				)
			)
		)
		(property "Val" "4u7/1.55A"
			(at 0 0 0)
			(unlocked yes)
			(layer "F.Fab")
			(hide yes)
			(effects
				(font
					(size 1 1)
					(thickness 0.15)
				)
			)
		)
		(property "Manufacturer" "Bourns"
			(at 0 0 0)
			(unlocked yes)
			(layer "F.Fab")
			(hide yes)
			(effects
				(font
					(size 1 1)
					(thickness 0.15)
				)
			)
		)
		(property "MPN" "SRP2512A-4R7M"
			(at 0 0 0)
			(unlocked yes)
			(layer "F.Fab")
			(hide yes)
			(effects
				(font
					(size 1 1)
					(thickness 0.15)
				)
			)
		)
		(property "ISat" "1.9 A"
			(at 0 0 0)
			(unlocked yes)
			(layer "F.Fab")
			(hide yes)
			(effects
				(font
					(size 1 1)
					(thickness 0.15)
				)
			)
		)
		(property "IMax" "1.55 A"
			(at 0 0 0)
			(unlocked yes)
			(layer "F.Fab")
			(hide yes)
			(effects
				(font
					(size 1 1)
					(thickness 0.15)
				)
			)
		)
		(property "Size" "2.5x2.0"
			(at 0 0 0)
			(unlocked yes)
			(layer "F.Fab")
			(hide yes)
			(effects
				(font
					(size 1 1)
					(thickness 0.15)
				)
			)
		)
		(property "Author" "Antmicro"
			(at 0 0 0)
			(unlocked yes)
			(layer "F.Fab")
			(hide yes)
			(effects
				(font
					(size 1 1)
					(thickness 0.15)
				)
			)
		)
		(property "License" "Apache-2.0"
			(at 0 0 0)
			(unlocked yes)
			(layer "F.Fab")
			(hide yes)
			(effects
				(font
					(size 1 1)
					(thickness 0.15)
				)
			)
		)
		(sheetname "/X710-AT2 power/")
		(sheetfile "x710-at2-power.kicad_sch")
		(attr smd)
		(fp_line
			(start -0.351 1)
			(end 0.349 1)
			(stroke
				(width 0.15)
				(type solid)
			)
			(layer "F.SilkS")
		)
		(fp_line
			(start -0.35 -1)
			(end 0.35 -1)
			(stroke
				(width 0.15)
				(type solid)
			)
			(layer "F.SilkS")
		)
		(fp_rect
			(start -1.65 -1.3)
			(end 1.65 1.3)
			(stroke
				(width 0.05)
				(type solid)
			)
			(fill no)
			(layer "F.CrtYd")
		)
		(pad "1" smd roundrect
			(at -1 0 90)
			(size 2 0.8)
			(layers "F.Cu" "F.Mask" "F.Paste")
			(roundrect_rratio 0.1)
			(net 302 "+1V0")
			(pintype "passive")
		)
		(pad "2" smd roundrect
			(at 1 0 90)
			(size 2 0.8)
			(layers "F.Cu" "F.Mask" "F.Paste")
			(roundrect_rratio 0.1)
			(net 12 "XFI_VDD")
			(pintype "passive")
		)
	)
	(footprint "antmicro-footprints:MP_Pad6mm_Drill3.2mm"
		(layer "F.Cu")
		(at 113 134.68)
		(property "Reference" "MP2"
			(at -1.1 -3.48 0)
			(layer "F.SilkS")
			(hide yes)
			(effects
				(font
					(size 0.7 0.7)
					(thickness 0.15)
				)
				(justify left bottom)
			)
		)
		(property "Value" "MP_Pad6mm_Drill3.2mm"
			(at 0 3.9 0)
			(layer "F.Fab")
			(hide yes)
			(effects
				(font
					(size 0.7 0.7)
					(thickness 0.15)
				)
				(justify left bottom)
			)
		)
		(property "Description" "Mechanical part"
			(at 0 0 0)
			(layer "F.Fab")
			(hide yes)
			(effects
				(font
					(size 1.27 1.27)
					(thickness 0.15)
				)
			)
		)
		(property "Author" "Antmicro"
			(at 0 0 0)
			(unlocked yes)
			(layer "F.Fab")
			(hide yes)
			(effects
				(font
					(size 1 1)
					(thickness 0.15)
				)
			)
		)
		(property "License" "Apache-2.0"
			(at 0 0 0)
			(unlocked yes)
			(layer "F.Fab")
			(hide yes)
			(effects
				(font
					(size 1 1)
					(thickness 0.15)
				)
			)
		)
		(sheetname "/")
		(sheetfile "oculink-to-10gbe-adapter.kicad_sch")
		(attr exclude_from_pos_files exclude_from_bom)
		(fp_circle
			(center 0 0)
			(end 3.25 0)
			(stroke
				(width 0.05)
				(type default)
			)
			(fill no)
			(layer "F.CrtYd")
		)
		(pad "1" thru_hole circle
			(at 0 0)
			(size 6 6)
			(drill 3.2)
			(layers "*.Cu" "*.Mask")
			(remove_unused_layers no)
			(net 28 "GND")
			(pintype "passive")
		)
	)
	(footprint "antmicro-footprints:R_0402_1005Metric"
		(layer "F.Cu")
		(at 57.85 78 90)
		(descr "Resistor SMD 0402")
		(tags "resistor SMD 0402")
		(property "Reference" "R33"
			(at -1.06 1.38 90)
			(layer "F.SilkS")
			(effects
				(font
					(size 0.7 0.7)
					(thickness 0.15)
				)
				(justify left bottom)
			)
		)
		(property "Value" "R_0R_0402"
			(at -1.011843 1.772046 90)
			(layer "F.Fab")
			(hide yes)
			(effects
				(font
					(size 0.7 0.7)
					(thickness 0.15)
				)
				(justify left bottom)
			)
		)
		(property "Datasheet" "https://industrial.panasonic.com/cdbs/www-data/pdf/RDA0000/AOA0000C301.pdf"
			(at 0 0 90)
			(layer "F.Fab")
			(hide yes)
			(effects
				(font
					(size 1.27 1.27)
					(thickness 0.15)
				)
			)
		)
		(property "Description" "SMD Chip Resistor, Jumper, 0 ohm, 100 mW, 0402 [1005 Metric], Thick Film, General Purpose"
			(at 0 0 90)
			(layer "F.Fab")
			(hide yes)
			(effects
				(font
					(size 1.27 1.27)
					(thickness 0.15)
				)
			)
		)
		(property "MPN" "ERJ2GE0R00X"
			(at 0 0 90)
			(unlocked yes)
			(layer "F.Fab")
			(hide yes)
			(effects
				(font
					(size 1 1)
					(thickness 0.15)
				)
			)
		)
		(property "Manufacturer" "Panasonic"
			(at 0 0 90)
			(unlocked yes)
			(layer "F.Fab")
			(hide yes)
			(effects
				(font
					(size 1 1)
					(thickness 0.15)
				)
			)
		)
		(property "License" "Apache-2.0"
			(at 0 0 90)
			(unlocked yes)
			(layer "F.Fab")
			(hide yes)
			(effects
				(font
					(size 1 1)
					(thickness 0.15)
				)
			)
		)
		(property "Author" "Antmicro"
			(at 0 0 90)
			(unlocked yes)
			(layer "F.Fab")
			(hide yes)
			(effects
				(font
					(size 1 1)
					(thickness 0.15)
				)
			)
		)
		(property "Val" "0R"
			(at 0 0 90)
			(unlocked yes)
			(layer "F.Fab")
			(hide yes)
			(effects
				(font
					(size 1 1)
					(thickness 0.15)
				)
			)
		)
		(property "Tolerance" "~"
			(at 0 0 90)
			(unlocked yes)
			(layer "F.Fab")
			(hide yes)
			(effects
				(font
					(size 1 1)
					(thickness 0.15)
				)
			)
		)
		(property "Current" "1A"
			(at 0 0 90)
			(unlocked yes)
			(layer "F.Fab")
			(hide yes)
			(effects
				(font
					(size 1 1)
					(thickness 0.15)
				)
			)
		)
		(sheetname "/Power/")
		(sheetfile "power.kicad_sch")
		(attr smd)
		(fp_rect
			(start -0.925 -0.47)
			(end 0.925 0.47)
			(stroke
				(width 0.05)
				(type default)
			)
			(fill no)
			(layer "F.CrtYd")
		)
		(fp_rect
			(start -0.5 -0.25)
			(end 0.5 0.25)
			(stroke
				(width 0.15)
				(type solid)
			)
			(fill no)
			(layer "F.Fab")
		)
		(pad "1" smd roundrect
			(at -0.48 0 90)
			(size 0.59 0.64)
			(layers "F.Cu" "F.Mask" "F.Paste")
			(roundrect_rratio 0.25)
			(net 378 "/Power/DVDD_PG")
			(pintype "passive")
		)
		(pad "2" smd roundrect
			(at 0.48 0 90)
			(size 0.59 0.64)
			(layers "F.Cu" "F.Mask" "F.Paste")
			(roundrect_rratio 0.25)
			(net 392 "/Power/ALL_RAILS_OK")
			(pintype "passive")
		)
	)
	(footprint "antmicro-footprints:C_0402_1005Metric"
		(layer "F.Cu")
		(at 56.399999 97.799999)
		(descr "Capacitor SMD 0402")
		(tags "capacitor SMD 0402")
		(property "Reference" "C38"
			(at -1.549999 1.210001 0)
			(layer "F.SilkS")
			(effects
				(font
					(size 0.7 0.7)
					(thickness 0.15)
				)
				(justify left bottom)
			)
		)
		(property "Value" "C_100n_0402"
			(at -1.022927 2.155213 0)
			(layer "F.Fab")
			(hide yes)
			(effects
				(font
					(size 0.7 0.7)
					(thickness 0.15)
				)
				(justify left bottom)
			)
		)
		(property "Datasheet" "https://www.murata.com/products/productdetail?partno=GRM155R61H104KE14%23"
			(at 0 0 0)
			(layer "F.Fab")
			(hide yes)
			(effects
				(font
					(size 1.27 1.27)
					(thickness 0.15)
				)
			)
		)
		(property "Description" "SMD Multilayer Ceramic Capacitor, 0.1 µF, 50 V, 0402 [1005 Metric], ± 10%, X5R, GRM Series"
			(at 0 0 0)
			(layer "F.Fab")
			(hide yes)
			(effects
				(font
					(size 1.27 1.27)
					(thickness 0.15)
				)
			)
		)
		(property "MPN" "GRM155R61H104KE14D"
			(at 0 0 0)
			(unlocked yes)
			(layer "F.Fab")
			(hide yes)
			(effects
				(font
					(size 1 1)
					(thickness 0.15)
				)
			)
		)
		(property "Manufacturer" "Murata"
			(at 0 0 0)
			(unlocked yes)
			(layer "F.Fab")
			(hide yes)
			(effects
				(font
					(size 1 1)
					(thickness 0.15)
				)
			)
		)
		(property "License" "Apache-2.0"
			(at 0 0 0)
			(unlocked yes)
			(layer "F.Fab")
			(hide yes)
			(effects
				(font
					(size 1 1)
					(thickness 0.15)
				)
			)
		)
		(property "Author" "Antmicro"
			(at 0 0 0)
			(unlocked yes)
			(layer "F.Fab")
			(hide yes)
			(effects
				(font
					(size 1 1)
					(thickness 0.15)
				)
			)
		)
		(property "Val" "100n"
			(at 0 0 0)
			(unlocked yes)
			(layer "F.Fab")
			(hide yes)
			(effects
				(font
					(size 1 1)
					(thickness 0.15)
				)
			)
		)
		(property "Voltage" "50V"
			(at 0 0 0)
			(unlocked yes)
			(layer "F.Fab")
			(hide yes)
			(effects
				(font
					(size 1 1)
					(thickness 0.15)
				)
			)
		)
		(property "Dielectric" "X5R"
			(at 0 0 0)
			(unlocked yes)
			(layer "F.Fab")
			(hide yes)
			(effects
				(font
					(size 1 1)
					(thickness 0.15)
				)
			)
		)
		(sheetname "/Power/")
		(sheetfile "power.kicad_sch")
		(attr smd)
		(fp_rect
			(start -0.925 -0.47)
			(end 0.925 0.47)
			(stroke
				(width 0.05)
				(type default)
			)
			(fill no)
			(layer "F.CrtYd")
		)
		(fp_line
			(start -0.494 -0.25)
			(end 0.504 -0.25)
			(stroke
				(width 0.15)
				(type solid)
			)
			(layer "F.Fab")
		)
		(fp_line
			(start -0.494 0.248)
			(end -0.494 -0.25)
			(stroke
				(width 0.15)
				(type solid)
			)
			(layer "F.Fab")
		)
		(fp_line
			(start 0.504 -0.25)
			(end 0.504 0.248)
			(stroke
				(width 0.15)
				(type solid)
			)
			(layer "F.Fab")
		)
		(fp_line
			(start 0.504 0.248)
			(end -0.494 0.248)
			(stroke
				(width 0.15)
				(type solid)
			)
			(layer "F.Fab")
		)
		(pad "1" smd roundrect
			(at -0.48 0)
			(size 0.59 0.64)
			(layers "F.Cu" "F.Mask" "F.Paste")
			(roundrect_rratio 0.25)
			(net 325 "/Power/DVDD_BST")
			(pintype "passive")
		)
		(pad "2" smd roundrect
			(at 0.48 0)
			(size 0.59 0.64)
			(layers "F.Cu" "F.Mask" "F.Paste")
			(roundrect_rratio 0.25)
			(net 336 "/Power/DVDD_SW")
			(pintype "passive")
		)
	)
	(footprint "antmicro-footprints:C_0402_1005Metric"
		(layer "F.Cu")
		(at 109.15 102.05 90)
		(descr "Capacitor SMD 0402")
		(tags "capacitor SMD 0402")
		(property "Reference" "C209"
			(at -1.35 -0.65 90)
			(layer "F.SilkS")
			(effects
				(font
					(size 0.7 0.7)
					(thickness 0.15)
				)
				(justify left bottom)
			)
		)
		(property "Value" "C_1u_25V_0402"
			(at -1.022927 2.155213 90)
			(layer "F.Fab")
			(hide yes)
			(effects
				(font
					(size 0.7 0.7)
					(thickness 0.15)
				)
				(justify left bottom)
			)
		)
		(property "Datasheet" "https://www.murata.com/products/productdetail?partno=GRM155R61E105KE11%23"
			(at 0 0 90)
			(layer "F.Fab")
			(hide yes)
			(effects
				(font
					(size 1.27 1.27)
					(thickness 0.15)
				)
			)
		)
		(property "Description" "SMD Multilayer Ceramic Capacitor, 1 µF, 25 V, 0402 [1005 Metric], ± 10%, X5R, GRM Series"
			(at 0 0 90)
			(layer "F.Fab")
			(hide yes)
			(effects
				(font
					(size 1.27 1.27)
					(thickness 0.15)
				)
			)
		)
		(property "MPN" "GRM155R61E105KE11J"
			(at 0 0 90)
			(unlocked yes)
			(layer "F.Fab")
			(hide yes)
			(effects
				(font
					(size 1 1)
					(thickness 0.15)
				)
			)
		)
		(property "Manufacturer" "Murata"
			(at 0 0 90)
			(unlocked yes)
			(layer "F.Fab")
			(hide yes)
			(effects
				(font
					(size 1 1)
					(thickness 0.15)
				)
			)
		)
		(property "License" "Apache-2.0"
			(at 0 0 90)
			(unlocked yes)
			(layer "F.Fab")
			(hide yes)
			(effects
				(font
					(size 1 1)
					(thickness 0.15)
				)
			)
		)
		(property "Author" "Antmicro"
			(at 0 0 90)
			(unlocked yes)
			(layer "F.Fab")
			(hide yes)
			(effects
				(font
					(size 1 1)
					(thickness 0.15)
				)
			)
		)
		(property "Val" "1u"
			(at 0 0 90)
			(unlocked yes)
			(layer "F.Fab")
			(hide yes)
			(effects
				(font
					(size 1 1)
					(thickness 0.15)
				)
			)
		)
		(property "Voltage" "25V"
			(at 0 0 90)
			(unlocked yes)
			(layer "F.Fab")
			(hide yes)
			(effects
				(font
					(size 1 1)
					(thickness 0.15)
				)
			)
		)
		(property "Dielectric" "X5R"
			(at 0 0 90)
			(unlocked yes)
			(layer "F.Fab")
			(hide yes)
			(effects
				(font
					(size 1 1)
					(thickness 0.15)
				)
			)
		)
		(sheetname "/Fan controller/")
		(sheetfile "fan-controller.kicad_sch")
		(attr smd exclude_from_pos_files exclude_from_bom dnp)
		(fp_rect
			(start -0.925 -0.47)
			(end 0.925 0.47)
			(stroke
				(width 0.05)
				(type default)
			)
			(fill no)
			(layer "F.CrtYd")
		)
		(fp_line
			(start 0.504 -0.25)
			(end 0.504 0.248)
			(stroke
				(width 0.15)
				(type solid)
			)
			(layer "F.Fab")
		)
		(fp_line
			(start -0.494 -0.25)
			(end 0.504 -0.25)
			(stroke
				(width 0.15)
				(type solid)
			)
			(layer "F.Fab")
		)
		(fp_line
			(start 0.504 0.248)
			(end -0.494 0.248)
			(stroke
				(width 0.15)
				(type solid)
			)
			(layer "F.Fab")
		)
		(fp_line
			(start -0.494 0.248)
			(end -0.494 -0.25)
			(stroke
				(width 0.15)
				(type solid)
			)
			(layer "F.Fab")
		)
		(pad "1" smd roundrect
			(at -0.48 0 90)
			(size 0.59 0.64)
			(layers "F.Cu" "F.Mask" "F.Paste")
			(roundrect_rratio 0.25)
			(net 28 "GND")
			(pintype "passive")
		)
		(pad "2" smd roundrect
			(at 0.48 0 90)
			(size 0.59 0.64)
			(layers "F.Cu" "F.Mask" "F.Paste")
			(roundrect_rratio 0.25)
			(net 385 "/Fan controller/SENSE")
			(pintype "passive")
		)
	)
	(footprint "antmicro-footprints:R_0402_1005Metric"
		(layer "F.Cu")
		(at 57.15 125.1 180)
		(descr "Resistor SMD 0402")
		(tags "resistor SMD 0402")
		(property "Reference" "R145"
			(at -1.5 -0.772697 0)
			(layer "F.SilkS")
			(effects
				(font
					(size 0.7 0.7)
					(thickness 0.15)
				)
				(justify right top)
			)
		)
		(property "Value" "R_1k_0402"
			(at -1.011843 1.772046 0)
			(layer "F.Fab")
			(hide yes)
			(effects
				(font
					(size 0.7 0.7)
					(thickness 0.15)
				)
				(justify right top)
			)
		)
		(property "Datasheet" "https://www.bourns.com/docs/product-datasheets/cr.pdf"
			(at 0 0 0)
			(layer "F.Fab")
			(hide yes)
			(effects
				(font
					(size 1.27 1.27)
					(thickness 0.15)
				)
			)
		)
		(property "Description" "SMD Chip Resistor, 1 kohm, ± 1%, 63 mW, 0402 [1005 Metric], Thick Film, General Purpose"
			(at 0 0 0)
			(layer "F.Fab")
			(hide yes)
			(effects
				(font
					(size 1.27 1.27)
					(thickness 0.15)
				)
			)
		)
		(property "MPN" "CR0402-FX-1001GLF"
			(at 0 0 180)
			(unlocked yes)
			(layer "F.Fab")
			(hide yes)
			(effects
				(font
					(size 1 1)
					(thickness 0.15)
				)
			)
		)
		(property "Manufacturer" "Bourns"
			(at 0 0 180)
			(unlocked yes)
			(layer "F.Fab")
			(hide yes)
			(effects
				(font
					(size 1 1)
					(thickness 0.15)
				)
			)
		)
		(property "License" "Apache-2.0"
			(at 0 0 180)
			(unlocked yes)
			(layer "F.Fab")
			(hide yes)
			(effects
				(font
					(size 1 1)
					(thickness 0.15)
				)
			)
		)
		(property "Author" "Antmicro"
			(at 0 0 180)
			(unlocked yes)
			(layer "F.Fab")
			(hide yes)
			(effects
				(font
					(size 1 1)
					(thickness 0.15)
				)
			)
		)
		(property "Val" "1k"
			(at 0 0 180)
			(unlocked yes)
			(layer "F.Fab")
			(hide yes)
			(effects
				(font
					(size 1 1)
					(thickness 0.15)
				)
			)
		)
		(property "Tolerance" "1%"
			(at 0 0 180)
			(unlocked yes)
			(layer "F.Fab")
			(hide yes)
			(effects
				(font
					(size 1 1)
					(thickness 0.15)
				)
			)
		)
		(sheetname "/Power/")
		(sheetfile "power.kicad_sch")
		(attr smd)
		(fp_poly
			(pts
				(xy -0.925 -0.47) (xy 0.925 -0.47) (xy 0.925 0.47) (xy -0.925 0.47)
			)
			(stroke
				(width 0.05)
				(type default)
			)
			(fill no)
			(layer "F.CrtYd")
		)
		(fp_poly
			(pts
				(xy -0.5 -0.25) (xy 0.5 -0.25) (xy 0.5 0.25) (xy -0.5 0.25)
			)
			(stroke
				(width 0.15)
				(type solid)
			)
			(fill no)
			(layer "F.Fab")
		)
		(pad "1" smd roundrect
			(at -0.48 0 180)
			(size 0.59 0.64)
			(layers "F.Cu" "F.Mask" "F.Paste")
			(roundrect_rratio 0.25)
			(net 416 "Net-(Q5-C)")
			(pintype "passive")
		)
		(pad "2" smd roundrect
			(at 0.48 0 180)
			(size 0.59 0.64)
			(layers "F.Cu" "F.Mask" "F.Paste")
			(roundrect_rratio 0.25)
			(net 411 "Net-(D17-C)")
			(pintype "passive")
		)
	)
	(footprint "antmicro-footprints:R_0402_1005Metric"
		(layer "F.Cu")
		(at 72.8 91.305 90)
		(descr "Resistor SMD 0402")
		(tags "resistor SMD 0402")
		(property "Reference" "R96"
			(at 0.785 0.34 90)
			(layer "F.SilkS")
			(effects
				(font
					(size 0.7 0.7)
					(thickness 0.15)
				)
				(justify left bottom)
			)
		)
		(property "Value" "R_10k_0402"
			(at -1.011843 1.772046 90)
			(layer "F.Fab")
			(hide yes)
			(effects
				(font
					(size 0.7 0.7)
					(thickness 0.15)
				)
				(justify left bottom)
			)
		)
		(property "Datasheet" "https://www.bourns.com/docs/product-datasheets/cr.pdf"
			(at 0 0 90)
			(layer "F.Fab")
			(hide yes)
			(effects
				(font
					(size 1.27 1.27)
					(thickness 0.15)
				)
			)
		)
		(property "Description" "SMD Chip Resistor, 10 kohm, ± 1%, 62.5 mW, 0402 [1005 Metric], Thick Film, General Purpose"
			(at 0 0 90)
			(layer "F.Fab")
			(hide yes)
			(effects
				(font
					(size 1.27 1.27)
					(thickness 0.15)
				)
			)
		)
		(property "MPN" "CR0402-FX-1002GLF"
			(at 0 0 90)
			(unlocked yes)
			(layer "F.Fab")
			(hide yes)
			(effects
				(font
					(size 1 1)
					(thickness 0.15)
				)
			)
		)
		(property "Manufacturer" "Bourns"
			(at 0 0 90)
			(unlocked yes)
			(layer "F.Fab")
			(hide yes)
			(effects
				(font
					(size 1 1)
					(thickness 0.15)
				)
			)
		)
		(property "License" "Apache-2.0"
			(at 0 0 90)
			(unlocked yes)
			(layer "F.Fab")
			(hide yes)
			(effects
				(font
					(size 1 1)
					(thickness 0.15)
				)
			)
		)
		(property "Author" "Antmicro"
			(at 0 0 90)
			(unlocked yes)
			(layer "F.Fab")
			(hide yes)
			(effects
				(font
					(size 1 1)
					(thickness 0.15)
				)
			)
		)
		(property "Val" "10k"
			(at 0 0 90)
			(unlocked yes)
			(layer "F.Fab")
			(hide yes)
			(effects
				(font
					(size 1 1)
					(thickness 0.15)
				)
			)
		)
		(property "Tolerance" "1%"
			(at 0 0 90)
			(unlocked yes)
			(layer "F.Fab")
			(hide yes)
			(effects
				(font
					(size 1 1)
					(thickness 0.15)
				)
			)
		)
		(sheetname "/X710-AT2 Misc/")
		(sheetfile "x710-at2-mics.kicad_sch")
		(attr smd exclude_from_pos_files exclude_from_bom dnp)
		(fp_rect
			(start -0.925 -0.47)
			(end 0.925 0.47)
			(stroke
				(width 0.05)
				(type default)
			)
			(fill no)
			(layer "F.CrtYd")
		)
		(fp_rect
			(start -0.5 -0.25)
			(end 0.5 0.25)
			(stroke
				(width 0.15)
				(type solid)
			)
			(fill no)
			(layer "F.Fab")
		)
		(pad "1" smd roundrect
			(at -0.48 0 90)
			(size 0.59 0.64)
			(layers "F.Cu" "F.Mask" "F.Paste")
			(roundrect_rratio 0.25)
			(net 99 "/X710-AT2 Misc/LAN_PWR_GOOD")
			(pintype "passive")
		)
		(pad "2" smd roundrect
			(at 0.48 0 90)
			(size 0.59 0.64)
			(layers "F.Cu" "F.Mask" "F.Paste")
			(roundrect_rratio 0.25)
			(net 7 "+3V3")
			(pintype "passive")
		)
	)
	(footprint "antmicro-footprints:R_0402_1005Metric"
		(layer "F.Cu")
		(at 57.15 122.75 180)
		(descr "Resistor SMD 0402")
		(tags "resistor SMD 0402")
		(property "Reference" "R146"
			(at -1.5 -0.772697 0)
			(layer "F.SilkS")
			(effects
				(font
					(size 0.7 0.7)
					(thickness 0.15)
				)
				(justify right top)
			)
		)
		(property "Value" "R_1k_0402"
			(at -1.011843 1.772046 0)
			(layer "F.Fab")
			(hide yes)
			(effects
				(font
					(size 0.7 0.7)
					(thickness 0.15)
				)
				(justify right top)
			)
		)
		(property "Datasheet" "https://www.bourns.com/docs/product-datasheets/cr.pdf"
			(at 0 0 0)
			(layer "F.Fab")
			(hide yes)
			(effects
				(font
					(size 1.27 1.27)
					(thickness 0.15)
				)
			)
		)
		(property "Description" "SMD Chip Resistor, 1 kohm, ± 1%, 63 mW, 0402 [1005 Metric], Thick Film, General Purpose"
			(at 0 0 0)
			(layer "F.Fab")
			(hide yes)
			(effects
				(font
					(size 1.27 1.27)
					(thickness 0.15)
				)
			)
		)
		(property "MPN" "CR0402-FX-1001GLF"
			(at 0 0 180)
			(unlocked yes)
			(layer "F.Fab")
			(hide yes)
			(effects
				(font
					(size 1 1)
					(thickness 0.15)
				)
			)
		)
		(property "Manufacturer" "Bourns"
			(at 0 0 180)
			(unlocked yes)
			(layer "F.Fab")
			(hide yes)
			(effects
				(font
					(size 1 1)
					(thickness 0.15)
				)
			)
		)
		(property "License" "Apache-2.0"
			(at 0 0 180)
			(unlocked yes)
			(layer "F.Fab")
			(hide yes)
			(effects
				(font
					(size 1 1)
					(thickness 0.15)
				)
			)
		)
		(property "Author" "Antmicro"
			(at 0 0 180)
			(unlocked yes)
			(layer "F.Fab")
			(hide yes)
			(effects
				(font
					(size 1 1)
					(thickness 0.15)
				)
			)
		)
		(property "Val" "1k"
			(at 0 0 180)
			(unlocked yes)
			(layer "F.Fab")
			(hide yes)
			(effects
				(font
					(size 1 1)
					(thickness 0.15)
				)
			)
		)
		(property "Tolerance" "1%"
			(at 0 0 180)
			(unlocked yes)
			(layer "F.Fab")
			(hide yes)
			(effects
				(font
					(size 1 1)
					(thickness 0.15)
				)
			)
		)
		(sheetname "/Power/")
		(sheetfile "power.kicad_sch")
		(attr smd)
		(fp_poly
			(pts
				(xy -0.925 -0.47) (xy 0.925 -0.47) (xy 0.925 0.47) (xy -0.925 0.47)
			)
			(stroke
				(width 0.05)
				(type default)
			)
			(fill no)
			(layer "F.CrtYd")
		)
		(fp_poly
			(pts
				(xy -0.5 -0.25) (xy 0.5 -0.25) (xy 0.5 0.25) (xy -0.5 0.25)
			)
			(stroke
				(width 0.15)
				(type solid)
			)
			(fill no)
			(layer "F.Fab")
		)
		(pad "1" smd roundrect
			(at -0.48 0 180)
			(size 0.59 0.64)
			(layers "F.Cu" "F.Mask" "F.Paste")
			(roundrect_rratio 0.25)
			(net 417 "Net-(Q7-C)")
			(pintype "passive")
		)
		(pad "2" smd roundrect
			(at 0.48 0 180)
			(size 0.59 0.64)
			(layers "F.Cu" "F.Mask" "F.Paste")
			(roundrect_rratio 0.25)
			(net 412 "Net-(D18-C)")
			(pintype "passive")
		)
	)
	(footprint "antmicro-footprints:R_0402_1005Metric"
		(layer "F.Cu")
		(at 82.25 83.15 180)
		(descr "Resistor SMD 0402")
		(tags "resistor SMD 0402")
		(property "Reference" "R173"
			(at -0.8 -0.45 0)
			(layer "F.SilkS")
			(effects
				(font
					(size 0.7 0.7)
					(thickness 0.15)
				)
				(justify left bottom)
			)
		)
		(property "Value" "R_0R_0402"
			(at -1.011843 1.772046 0)
			(layer "F.Fab")
			(hide yes)
			(effects
				(font
					(size 0.7 0.7)
					(thickness 0.15)
				)
				(justify right top)
			)
		)
		(property "Datasheet" "https://industrial.panasonic.com/cdbs/www-data/pdf/RDA0000/AOA0000C301.pdf"
			(at 0 0 0)
			(layer "F.Fab")
			(hide yes)
			(effects
				(font
					(size 1.27 1.27)
					(thickness 0.15)
				)
			)
		)
		(property "Description" "SMD Chip Resistor, Jumper, 0 ohm, 100 mW, 0402 [1005 Metric], Thick Film, General Purpose"
			(at 0 0 0)
			(layer "F.Fab")
			(hide yes)
			(effects
				(font
					(size 1.27 1.27)
					(thickness 0.15)
				)
			)
		)
		(property "MPN" "ERJ2GE0R00X"
			(at 0 0 180)
			(unlocked yes)
			(layer "F.Fab")
			(hide yes)
			(effects
				(font
					(size 1 1)
					(thickness 0.15)
				)
			)
		)
		(property "Manufacturer" "Panasonic"
			(at 0 0 180)
			(unlocked yes)
			(layer "F.Fab")
			(hide yes)
			(effects
				(font
					(size 1 1)
					(thickness 0.15)
				)
			)
		)
		(property "License" "Apache-2.0"
			(at 0 0 180)
			(unlocked yes)
			(layer "F.Fab")
			(hide yes)
			(effects
				(font
					(size 1 1)
					(thickness 0.15)
				)
			)
		)
		(property "Author" "Antmicro"
			(at 0 0 180)
			(unlocked yes)
			(layer "F.Fab")
			(hide yes)
			(effects
				(font
					(size 1 1)
					(thickness 0.15)
				)
			)
		)
		(property "Val" "0R"
			(at 0 0 180)
			(unlocked yes)
			(layer "F.Fab")
			(hide yes)
			(effects
				(font
					(size 1 1)
					(thickness 0.15)
				)
			)
		)
		(property "Tolerance" "~"
			(at 0 0 180)
			(unlocked yes)
			(layer "F.Fab")
			(hide yes)
			(effects
				(font
					(size 1 1)
					(thickness 0.15)
				)
			)
		)
		(property "Current" "1A"
			(at 0 0 180)
			(unlocked yes)
			(layer "F.Fab")
			(hide yes)
			(effects
				(font
					(size 1 1)
					(thickness 0.15)
				)
			)
		)
		(sheetname "/X710-AT2 Misc/")
		(sheetfile "x710-at2-mics.kicad_sch")
		(attr smd)
		(fp_rect
			(start -0.925 -0.47)
			(end 0.925 0.47)
			(stroke
				(width 0.05)
				(type default)
			)
			(fill no)
			(layer "F.CrtYd")
		)
		(fp_rect
			(start -0.5 -0.25)
			(end 0.5 0.25)
			(stroke
				(width 0.15)
				(type solid)
			)
			(fill no)
			(layer "F.Fab")
		)
		(pad "1" smd roundrect
			(at -0.48 0 180)
			(size 0.59 0.64)
			(layers "F.Cu" "F.Mask" "F.Paste")
			(roundrect_rratio 0.25)
			(net 78 "Net-(U10-VCC)")
			(pintype "passive")
		)
		(pad "2" smd roundrect
			(at 0.48 0 180)
			(size 0.59 0.64)
			(layers "F.Cu" "F.Mask" "F.Paste")
			(roundrect_rratio 0.25)
			(net 7 "+3V3")
			(pintype "passive")
		)
	)
	(footprint "antmicro-footprints:C_0402_1005Metric"
		(layer "F.Cu")
		(at 96 65.285 -90)
		(descr "Capacitor SMD 0402")
		(tags "capacitor SMD 0402")
		(property "Reference" "C197"
			(at 0.842273 -0.399995 270)
			(layer "F.SilkS")
			(effects
				(font
					(size 0.7 0.7)
					(thickness 0.15)
				)
				(justify right bottom)
			)
		)
		(property "Value" "C_220n_16V_0402"
			(at -1.022927 2.155213 270)
			(layer "F.Fab")
			(hide yes)
			(effects
				(font
					(size 0.7 0.7)
					(thickness 0.15)
				)
				(justify left bottom)
			)
		)
		(property "Datasheet" "https://www.murata.com/products/productdetail?partno=GRM155R71C224KA12%23"
			(at 0 0 270)
			(layer "F.Fab")
			(hide yes)
			(effects
				(font
					(size 1.27 1.27)
					(thickness 0.15)
				)
			)
		)
		(property "Description" "SMD Multilayer Ceramic Capacitor, 0.22 µF, 16 V, 0402 [1005 Metric], ± 10%, X7R, GRM Series"
			(at 0 0 270)
			(layer "F.Fab")
			(hide yes)
			(effects
				(font
					(size 1.27 1.27)
					(thickness 0.15)
				)
			)
		)
		(property "MPN" "GRM155R71C224KA12D"
			(at 0 0 270)
			(unlocked yes)
			(layer "F.Fab")
			(hide yes)
			(effects
				(font
					(size 1 1)
					(thickness 0.15)
				)
			)
		)
		(property "Manufacturer" "Murata"
			(at 0 0 270)
			(unlocked yes)
			(layer "F.Fab")
			(hide yes)
			(effects
				(font
					(size 1 1)
					(thickness 0.15)
				)
			)
		)
		(property "License" "Apache-2.0"
			(at 0 0 270)
			(unlocked yes)
			(layer "F.Fab")
			(hide yes)
			(effects
				(font
					(size 1 1)
					(thickness 0.15)
				)
			)
		)
		(property "Author" "Antmicro"
			(at 0 0 270)
			(unlocked yes)
			(layer "F.Fab")
			(hide yes)
			(effects
				(font
					(size 1 1)
					(thickness 0.15)
				)
			)
		)
		(property "Val" "220n"
			(at 0 0 270)
			(unlocked yes)
			(layer "F.Fab")
			(hide yes)
			(effects
				(font
					(size 1 1)
					(thickness 0.15)
				)
			)
		)
		(property "Voltage" "16V"
			(at 0 0 270)
			(unlocked yes)
			(layer "F.Fab")
			(hide yes)
			(effects
				(font
					(size 1 1)
					(thickness 0.15)
				)
			)
		)
		(property "Dielectric" "X7R"
			(at 0 0 270)
			(unlocked yes)
			(layer "F.Fab")
			(hide yes)
			(effects
				(font
					(size 1 1)
					(thickness 0.15)
				)
			)
		)
		(sheetname "/X710-AT2 PCIe/")
		(sheetfile "x710-at2-pcie.kicad_sch")
		(attr smd)
		(fp_rect
			(start -0.925 -0.47)
			(end 0.925 0.47)
			(stroke
				(width 0.05)
				(type default)
			)
			(fill no)
			(layer "F.CrtYd")
		)
		(fp_line
			(start -0.494 0.248)
			(end -0.494 -0.25)
			(stroke
				(width 0.15)
				(type solid)
			)
			(layer "F.Fab")
		)
		(fp_line
			(start 0.504 0.248)
			(end -0.494 0.248)
			(stroke
				(width 0.15)
				(type solid)
			)
			(layer "F.Fab")
		)
		(fp_line
			(start -0.494 -0.25)
			(end 0.504 -0.25)
			(stroke
				(width 0.15)
				(type solid)
			)
			(layer "F.Fab")
		)
		(fp_line
			(start 0.504 -0.25)
			(end 0.504 0.248)
			(stroke
				(width 0.15)
				(type solid)
			)
			(layer "F.Fab")
		)
		(pad "1" smd roundrect
			(at -0.48 0 270)
			(size 0.59 0.64)
			(layers "F.Cu" "F.Mask" "F.Paste")
			(roundrect_rratio 0.25)
			(net 26 "/OCuLink/PCIe_{x4}.TX3-")
			(pintype "passive")
		)
		(pad "2" smd roundrect
			(at 0.48 0 270)
			(size 0.59 0.64)
			(layers "F.Cu" "F.Mask" "F.Paste")
			(roundrect_rratio 0.25)
			(net 46 "/X710-AT2 PCIe/PCIe_{x4}_AC.TX3-")
			(pintype "passive")
		)
	)
	(footprint "antmicro-footprints:C_0603_1608Metric_EIA"
		(layer "F.Cu")
		(at 53.25 96.199999 -90)
		(descr "Capacitor SMD 0603, IPC-7351 Density Level A")
		(tags "Capacitor 0603")
		(property "Reference" "C40"
			(at 1.210001 0.44 270)
			(layer "F.SilkS")
			(effects
				(font
					(size 0.7 0.7)
					(thickness 0.15)
				)
				(justify right top)
			)
		)
		(property "Value" "C_22u_16V_0603"
			(at -1.42757 1.770288 90)
			(layer "F.Fab")
			(hide yes)
			(effects
				(font
					(size 0.7 0.7)
					(thickness 0.15)
				)
				(justify right top)
			)
		)
		(property "Datasheet" "https://product.samsungsem.com/mlcc/CL10A226MO7JZN.do"
			(at 0 0 90)
			(layer "F.Fab")
			(hide yes)
			(effects
				(font
					(size 1.27 1.27)
					(thickness 0.15)
				)
			)
		)
		(property "Description" "SMD Multilayer Ceramic Capacitor"
			(at 0 0 90)
			(layer "F.Fab")
			(hide yes)
			(effects
				(font
					(size 1.27 1.27)
					(thickness 0.15)
				)
			)
		)
		(property "MPN" "CL10A226MO7JZNC"
			(at 0 0 270)
			(unlocked yes)
			(layer "F.Fab")
			(hide yes)
			(effects
				(font
					(size 1 1)
					(thickness 0.15)
				)
			)
		)
		(property "Manufacturer" "Samsung Electro-Mechanics"
			(at 0 0 270)
			(unlocked yes)
			(layer "F.Fab")
			(hide yes)
			(effects
				(font
					(size 1 1)
					(thickness 0.15)
				)
			)
		)
		(property "License" "Apache-2.0"
			(at 0 0 270)
			(unlocked yes)
			(layer "F.Fab")
			(hide yes)
			(effects
				(font
					(size 1 1)
					(thickness 0.15)
				)
			)
		)
		(property "Author" "Antmicro"
			(at 0 0 270)
			(unlocked yes)
			(layer "F.Fab")
			(hide yes)
			(effects
				(font
					(size 1 1)
					(thickness 0.15)
				)
			)
		)
		(property "Val" "22u"
			(at 0 0 270)
			(unlocked yes)
			(layer "F.Fab")
			(hide yes)
			(effects
				(font
					(size 1 1)
					(thickness 0.15)
				)
			)
		)
		(property "Voltage" "16V"
			(at 0 0 270)
			(unlocked yes)
			(layer "F.Fab")
			(hide yes)
			(effects
				(font
					(size 1 1)
					(thickness 0.15)
				)
			)
		)
		(property "Dielectric" ""
			(at 0 0 270)
			(unlocked yes)
			(layer "F.Fab")
			(hide yes)
			(effects
				(font
					(size 1 1)
					(thickness 0.15)
				)
			)
		)
		(property "Public" "False"
			(at 0 0 270)
			(unlocked yes)
			(layer "F.Fab")
			(hide yes)
			(effects
				(font
					(size 1 1)
					(thickness 0.15)
				)
			)
		)
		(sheetname "/Power/")
		(sheetfile "power.kicad_sch")
		(attr smd)
		(fp_line
			(start -0.15 0.55)
			(end 0.15 0.55)
			(stroke
				(width 0.15)
				(type solid)
			)
			(layer "F.SilkS")
		)
		(fp_line
			(start -0.15 -0.55)
			(end 0.15 -0.55)
			(stroke
				(width 0.15)
				(type solid)
			)
			(layer "F.SilkS")
		)
		(fp_rect
			(start -1.25 -0.65)
			(end 1.25 0.65)
			(stroke
				(width 0.05)
				(type solid)
			)
			(fill no)
			(layer "F.CrtYd")
		)
		(fp_rect
			(start -0.8 -0.45)
			(end 0.8 0.45)
			(stroke
				(width 0.15)
				(type solid)
			)
			(fill no)
			(layer "F.Fab")
		)
		(pad "1" smd roundrect
			(at -0.7 0 270)
			(size 0.8 1.1)
			(layers "F.Cu" "F.Mask" "F.Paste")
			(roundrect_rratio 0.2)
			(net 28 "GND")
			(pintype "passive")
		)
		(pad "2" smd roundrect
			(at 0.7 0 270)
			(size 0.8 1.1)
			(layers "F.Cu" "F.Mask" "F.Paste")
			(roundrect_rratio 0.2)
			(net 314 "VCC")
			(pintype "passive")
		)
	)
	(footprint "antmicro-footprints:C_0603_1608Metric_EIA"
		(layer "F.Cu")
		(at 51.900001 88.500001 -90)
		(descr "Capacitor SMD 0603, IPC-7351 Density Level A")
		(tags "Capacitor 0603")
		(property "Reference" "C12"
			(at 1.239999 0.950001 90)
			(layer "F.SilkS")
			(effects
				(font
					(size 0.7 0.7)
					(thickness 0.15)
				)
				(justify right top)
			)
		)
		(property "Value" "C_22u_16V_0603"
			(at -1.42757 1.770288 90)
			(layer "F.Fab")
			(hide yes)
			(effects
				(font
					(size 0.7 0.7)
					(thickness 0.15)
				)
				(justify right top)
			)
		)
		(property "Datasheet" "https://product.samsungsem.com/mlcc/CL10A226MO7JZN.do"
			(at 0 0 90)
			(layer "F.Fab")
			(hide yes)
			(effects
				(font
					(size 1.27 1.27)
					(thickness 0.15)
				)
			)
		)
		(property "Description" "SMD Multilayer Ceramic Capacitor"
			(at 0 0 90)
			(layer "F.Fab")
			(hide yes)
			(effects
				(font
					(size 1.27 1.27)
					(thickness 0.15)
				)
			)
		)
		(property "MPN" "CL10A226MO7JZNC"
			(at 0 0 270)
			(unlocked yes)
			(layer "F.Fab")
			(hide yes)
			(effects
				(font
					(size 1 1)
					(thickness 0.15)
				)
			)
		)
		(property "Manufacturer" "Samsung Electro-Mechanics"
			(at 0 0 270)
			(unlocked yes)
			(layer "F.Fab")
			(hide yes)
			(effects
				(font
					(size 1 1)
					(thickness 0.15)
				)
			)
		)
		(property "License" "Apache-2.0"
			(at 0 0 270)
			(unlocked yes)
			(layer "F.Fab")
			(hide yes)
			(effects
				(font
					(size 1 1)
					(thickness 0.15)
				)
			)
		)
		(property "Author" "Antmicro"
			(at 0 0 270)
			(unlocked yes)
			(layer "F.Fab")
			(hide yes)
			(effects
				(font
					(size 1 1)
					(thickness 0.15)
				)
			)
		)
		(property "Val" "22u"
			(at 0 0 270)
			(unlocked yes)
			(layer "F.Fab")
			(hide yes)
			(effects
				(font
					(size 1 1)
					(thickness 0.15)
				)
			)
		)
		(property "Voltage" "16V"
			(at 0 0 270)
			(unlocked yes)
			(layer "F.Fab")
			(hide yes)
			(effects
				(font
					(size 1 1)
					(thickness 0.15)
				)
			)
		)
		(property "Dielectric" ""
			(at 0 0 270)
			(unlocked yes)
			(layer "F.Fab")
			(hide yes)
			(effects
				(font
					(size 1 1)
					(thickness 0.15)
				)
			)
		)
		(property "Public" "False"
			(at 0 0 270)
			(unlocked yes)
			(layer "F.Fab")
			(hide yes)
			(effects
				(font
					(size 1 1)
					(thickness 0.15)
				)
			)
		)
		(sheetname "/Power/")
		(sheetfile "power.kicad_sch")
		(attr smd)
		(fp_line
			(start -0.15 0.55)
			(end 0.15 0.55)
			(stroke
				(width 0.15)
				(type solid)
			)
			(layer "F.SilkS")
		)
		(fp_line
			(start -0.15 -0.55)
			(end 0.15 -0.55)
			(stroke
				(width 0.15)
				(type solid)
			)
			(layer "F.SilkS")
		)
		(fp_rect
			(start -1.25 -0.65)
			(end 1.25 0.65)
			(stroke
				(width 0.05)
				(type solid)
			)
			(fill no)
			(layer "F.CrtYd")
		)
		(fp_rect
			(start -0.8 -0.45)
			(end 0.8 0.45)
			(stroke
				(width 0.15)
				(type solid)
			)
			(fill no)
			(layer "F.Fab")
		)
		(pad "1" smd roundrect
			(at -0.7 0 270)
			(size 0.8 1.1)
			(layers "F.Cu" "F.Mask" "F.Paste")
			(roundrect_rratio 0.2)
			(net 28 "GND")
			(pintype "passive")
		)
		(pad "2" smd roundrect
			(at 0.7 0 270)
			(size 0.8 1.1)
			(layers "F.Cu" "F.Mask" "F.Paste")
			(roundrect_rratio 0.2)
			(net 314 "VCC")
			(pintype "passive")
		)
	)
	(footprint "antmicro-footprints:R_0402_1005Metric"
		(layer "F.Cu")
		(at 104.625001 95.35 90)
		(descr "Resistor SMD 0402")
		(tags "resistor SMD 0402")
		(property "Reference" "R115"
			(at 0.85 -0.525001 90)
			(layer "F.SilkS")
			(effects
				(font
					(size 0.7 0.7)
					(thickness 0.15)
				)
				(justify right bottom)
			)
		)
		(property "Value" "R_2k_0402"
			(at -1.011843 1.772046 90)
			(layer "F.Fab")
			(hide yes)
			(effects
				(font
					(size 0.7 0.7)
					(thickness 0.15)
				)
				(justify left bottom)
			)
		)
		(property "Datasheet" "https://www.bourns.com/docs/product-datasheets/cr.pdf"
			(at 0 0 90)
			(layer "F.Fab")
			(hide yes)
			(effects
				(font
					(size 1.27 1.27)
					(thickness 0.15)
				)
			)
		)
		(property "Description" "SMD Chip Resistor, 2 kohm, ± 1%, 62.5 mW, 0402 [1005 Metric], Thick Film, General Purpose"
			(at 0 0 90)
			(layer "F.Fab")
			(hide yes)
			(effects
				(font
					(size 1.27 1.27)
					(thickness 0.15)
				)
			)
		)
		(property "MPN" "CR0402-FX-2001GLF"
			(at 0 0 90)
			(unlocked yes)
			(layer "F.Fab")
			(hide yes)
			(effects
				(font
					(size 1 1)
					(thickness 0.15)
				)
			)
		)
		(property "Manufacturer" "Bourns"
			(at 0 0 90)
			(unlocked yes)
			(layer "F.Fab")
			(hide yes)
			(effects
				(font
					(size 1 1)
					(thickness 0.15)
				)
			)
		)
		(property "License" "Apache-2.0"
			(at 0 0 90)
			(unlocked yes)
			(layer "F.Fab")
			(hide yes)
			(effects
				(font
					(size 1 1)
					(thickness 0.15)
				)
			)
		)
		(property "Author" "Antmicro"
			(at 0 0 90)
			(unlocked yes)
			(layer "F.Fab")
			(hide yes)
			(effects
				(font
					(size 1 1)
					(thickness 0.15)
				)
			)
		)
		(property "Val" "2k"
			(at 0 0 90)
			(unlocked yes)
			(layer "F.Fab")
			(hide yes)
			(effects
				(font
					(size 1 1)
					(thickness 0.15)
				)
			)
		)
		(property "Tolerance" "1%"
			(at 0 0 90)
			(unlocked yes)
			(layer "F.Fab")
			(hide yes)
			(effects
				(font
					(size 1 1)
					(thickness 0.15)
				)
			)
		)
		(sheetname "/X710-AT2 Misc/")
		(sheetfile "x710-at2-mics.kicad_sch")
		(attr smd)
		(fp_rect
			(start -0.925 -0.47)
			(end 0.925 0.47)
			(stroke
				(width 0.05)
				(type default)
			)
			(fill no)
			(layer "F.CrtYd")
		)
		(fp_rect
			(start -0.5 -0.25)
			(end 0.5 0.25)
			(stroke
				(width 0.15)
				(type solid)
			)
			(fill no)
			(layer "F.Fab")
		)
		(pad "1" smd roundrect
			(at -0.48 0 90)
			(size 0.59 0.64)
			(layers "F.Cu" "F.Mask" "F.Paste")
			(roundrect_rratio 0.25)
			(net 382 "/X710-AT2 Misc/MDIO.MDC")
			(pintype "passive")
		)
		(pad "2" smd roundrect
			(at 0.48 0 90)
			(size 0.59 0.64)
			(layers "F.Cu" "F.Mask" "F.Paste")
			(roundrect_rratio 0.25)
			(net 18 "+1V88")
			(pintype "passive")
		)
	)
	(footprint "antmicro-footprints:C_0402_1005Metric"
		(layer "F.Cu")
		(at 55.100001 85.149999 90)
		(descr "Capacitor SMD 0402")
		(tags "capacitor SMD 0402")
		(property "Reference" "C11"
			(at -1.140001 -2.310001 90)
			(layer "F.SilkS")
			(effects
				(font
					(size 0.7 0.7)
					(thickness 0.15)
				)
				(justify left bottom)
			)
		)
		(property "Value" "C_33p_0402"
			(at -1.022927 2.155213 90)
			(layer "F.Fab")
			(hide yes)
			(effects
				(font
					(size 0.7 0.7)
					(thickness 0.15)
				)
				(justify left bottom)
			)
		)
		(property "Datasheet" "https://spicat.kyocera-avx.com/product/mlcc/chartview/04025A330FAT2A/"
			(at 0 0 90)
			(layer "F.Fab")
			(hide yes)
			(effects
				(font
					(size 1.27 1.27)
					(thickness 0.15)
				)
			)
		)
		(property "Description" "SMD Multilayer Ceramic Capacitor, 33 pF, 50 V, 0402 [1005 Metric], ± 5%, C0G / NP0, MC"
			(at 0 0 90)
			(layer "F.Fab")
			(hide yes)
			(effects
				(font
					(size 1.27 1.27)
					(thickness 0.15)
				)
			)
		)
		(property "MPN" "04025A330FAT2A"
			(at 0 0 90)
			(unlocked yes)
			(layer "F.Fab")
			(hide yes)
			(effects
				(font
					(size 1 1)
					(thickness 0.15)
				)
			)
		)
		(property "Manufacturer" "KYOCERA AVX"
			(at 0 0 90)
			(unlocked yes)
			(layer "F.Fab")
			(hide yes)
			(effects
				(font
					(size 1 1)
					(thickness 0.15)
				)
			)
		)
		(property "License" "Apache-2.0"
			(at 0 0 90)
			(unlocked yes)
			(layer "F.Fab")
			(hide yes)
			(effects
				(font
					(size 1 1)
					(thickness 0.15)
				)
			)
		)
		(property "Author" "Antmicro"
			(at 0 0 90)
			(unlocked yes)
			(layer "F.Fab")
			(hide yes)
			(effects
				(font
					(size 1 1)
					(thickness 0.15)
				)
			)
		)
		(property "Val" "33p"
			(at 0 0 90)
			(unlocked yes)
			(layer "F.Fab")
			(hide yes)
			(effects
				(font
					(size 1 1)
					(thickness 0.15)
				)
			)
		)
		(property "Voltage" ""
			(at 0 0 90)
			(unlocked yes)
			(layer "F.Fab")
			(hide yes)
			(effects
				(font
					(size 1 1)
					(thickness 0.15)
				)
			)
		)
		(property "Dielectric" ""
			(at 0 0 90)
			(unlocked yes)
			(layer "F.Fab")
			(hide yes)
			(effects
				(font
					(size 1 1)
					(thickness 0.15)
				)
			)
		)
		(sheetname "/Power/")
		(sheetfile "power.kicad_sch")
		(attr smd exclude_from_pos_files exclude_from_bom dnp)
		(fp_rect
			(start -0.925 -0.47)
			(end 0.925 0.47)
			(stroke
				(width 0.05)
				(type default)
			)
			(fill no)
			(layer "F.CrtYd")
		)
		(fp_line
			(start 0.504 -0.25)
			(end 0.504 0.248)
			(stroke
				(width 0.15)
				(type solid)
			)
			(layer "F.Fab")
		)
		(fp_line
			(start -0.494 -0.25)
			(end 0.504 -0.25)
			(stroke
				(width 0.15)
				(type solid)
			)
			(layer "F.Fab")
		)
		(fp_line
			(start 0.504 0.248)
			(end -0.494 0.248)
			(stroke
				(width 0.15)
				(type solid)
			)
			(layer "F.Fab")
		)
		(fp_line
			(start -0.494 0.248)
			(end -0.494 -0.25)
			(stroke
				(width 0.15)
				(type solid)
			)
			(layer "F.Fab")
		)
		(pad "1" smd roundrect
			(at -0.48 0 90)
			(size 0.59 0.64)
			(layers "F.Cu" "F.Mask" "F.Paste")
			(roundrect_rratio 0.25)
			(net 329 "/Power/VCCD_FB")
			(pintype "passive")
		)
		(pad "2" smd roundrect
			(at 0.48 0 90)
			(size 0.59 0.64)
			(layers "F.Cu" "F.Mask" "F.Paste")
			(roundrect_rratio 0.25)
			(net 303 "/Power/+VCCD_OUT")
			(pintype "passive")
		)
	)
	(footprint "antmicro-footprints:C_0402_1005Metric"
		(layer "F.Cu")
		(at 57.099998 100.550002 -90)
		(descr "Capacitor SMD 0402")
		(tags "capacitor SMD 0402")
		(property "Reference" "C24"
			(at 0.819998 -0.710002 180)
			(layer "F.SilkS")
			(effects
				(font
					(size 0.7 0.7)
					(thickness 0.12)
					(bold yes)
				)
				(justify right top)
			)
		)
		(property "Value" "C_1u_25V_0402"
			(at -1.022927 2.155213 90)
			(layer "F.Fab")
			(hide yes)
			(effects
				(font
					(size 0.7 0.7)
					(thickness 0.15)
				)
				(justify right top)
			)
		)
		(property "Datasheet" "https://www.murata.com/products/productdetail?partno=GRM155R61E105KE11%23"
			(at 0 0 90)
			(layer "F.Fab")
			(hide yes)
			(effects
				(font
					(size 1.27 1.27)
					(thickness 0.15)
				)
			)
		)
		(property "Description" "SMD Multilayer Ceramic Capacitor, 1 µF, 25 V, 0402 [1005 Metric], ± 10%, X5R, GRM Series"
			(at 0 0 90)
			(layer "F.Fab")
			(hide yes)
			(effects
				(font
					(size 1.27 1.27)
					(thickness 0.15)
				)
			)
		)
		(property "MPN" "GRM155R61E105KE11J"
			(at 0 0 270)
			(unlocked yes)
			(layer "F.Fab")
			(hide yes)
			(effects
				(font
					(size 1 1)
					(thickness 0.15)
				)
			)
		)
		(property "Manufacturer" "Murata"
			(at 0 0 270)
			(unlocked yes)
			(layer "F.Fab")
			(hide yes)
			(effects
				(font
					(size 1 1)
					(thickness 0.15)
				)
			)
		)
		(property "License" "Apache-2.0"
			(at 0 0 270)
			(unlocked yes)
			(layer "F.Fab")
			(hide yes)
			(effects
				(font
					(size 1 1)
					(thickness 0.15)
				)
			)
		)
		(property "Author" "Antmicro"
			(at 0 0 270)
			(unlocked yes)
			(layer "F.Fab")
			(hide yes)
			(effects
				(font
					(size 1 1)
					(thickness 0.15)
				)
			)
		)
		(property "Val" "1u"
			(at 0 0 270)
			(unlocked yes)
			(layer "F.Fab")
			(hide yes)
			(effects
				(font
					(size 1 1)
					(thickness 0.15)
				)
			)
		)
		(property "Voltage" "25V"
			(at 0 0 270)
			(unlocked yes)
			(layer "F.Fab")
			(hide yes)
			(effects
				(font
					(size 1 1)
					(thickness 0.15)
				)
			)
		)
		(property "Dielectric" "X5R"
			(at 0 0 270)
			(unlocked yes)
			(layer "F.Fab")
			(hide yes)
			(effects
				(font
					(size 1 1)
					(thickness 0.15)
				)
			)
		)
		(sheetname "/Power/")
		(sheetfile "power.kicad_sch")
		(attr smd)
		(fp_rect
			(start -0.925 -0.47)
			(end 0.925 0.47)
			(stroke
				(width 0.05)
				(type default)
			)
			(fill no)
			(layer "F.CrtYd")
		)
		(fp_line
			(start -0.494 0.248)
			(end -0.494 -0.25)
			(stroke
				(width 0.15)
				(type solid)
			)
			(layer "F.Fab")
		)
		(fp_line
			(start 0.504 0.248)
			(end -0.494 0.248)
			(stroke
				(width 0.15)
				(type solid)
			)
			(layer "F.Fab")
		)
		(fp_line
			(start -0.494 -0.25)
			(end 0.504 -0.25)
			(stroke
				(width 0.15)
				(type solid)
			)
			(layer "F.Fab")
		)
		(fp_line
			(start 0.504 -0.25)
			(end 0.504 0.248)
			(stroke
				(width 0.15)
				(type solid)
			)
			(layer "F.Fab")
		)
		(pad "1" smd roundrect
			(at -0.48 0 270)
			(size 0.59 0.64)
			(layers "F.Cu" "F.Mask" "F.Paste")
			(roundrect_rratio 0.25)
			(net 28 "GND")
			(pintype "passive")
		)
		(pad "2" smd roundrect
			(at 0.48 0 270)
			(size 0.59 0.64)
			(layers "F.Cu" "F.Mask" "F.Paste")
			(roundrect_rratio 0.25)
			(net 324 "/Power/1V88_VCC")
			(pintype "passive")
		)
	)
	(footprint "antmicro-footprints:R_0402_1005Metric"
		(layer "F.Cu")
		(at 111.35 93.45 90)
		(descr "Resistor SMD 0402")
		(tags "resistor SMD 0402")
		(property "Reference" "R66"
			(at 3.85 0.4 90)
			(layer "F.SilkS")
			(effects
				(font
					(size 0.7 0.7)
					(thickness 0.15)
				)
				(justify left bottom)
			)
		)
		(property "Value" "R_3k3_0402"
			(at -1.011843 1.772046 90)
			(layer "F.Fab")
			(hide yes)
			(effects
				(font
					(size 0.7 0.7)
					(thickness 0.15)
				)
				(justify left bottom)
			)
		)
		(property "Datasheet" "https://www.bourns.com/docs/product-datasheets/cr.pdf"
			(at 0 0 90)
			(layer "F.Fab")
			(hide yes)
			(effects
				(font
					(size 1.27 1.27)
					(thickness 0.15)
				)
			)
		)
		(property "Description" "SMD Chip Resistor, 3.3 kohm, ± 1%, 63 mW, 0402 [1005 Metric], Thick Film, General Purpose"
			(at 0 0 90)
			(layer "F.Fab")
			(hide yes)
			(effects
				(font
					(size 1.27 1.27)
					(thickness 0.15)
				)
			)
		)
		(property "MPN" "CR0402-FX-3301GLF"
			(at 0 0 90)
			(unlocked yes)
			(layer "F.Fab")
			(hide yes)
			(effects
				(font
					(size 1 1)
					(thickness 0.15)
				)
			)
		)
		(property "Manufacturer" "Bourns"
			(at 0 0 90)
			(unlocked yes)
			(layer "F.Fab")
			(hide yes)
			(effects
				(font
					(size 1 1)
					(thickness 0.15)
				)
			)
		)
		(property "License" "Apache-2.0"
			(at 0 0 90)
			(unlocked yes)
			(layer "F.Fab")
			(hide yes)
			(effects
				(font
					(size 1 1)
					(thickness 0.15)
				)
			)
		)
		(property "Author" "Antmicro"
			(at 0 0 90)
			(unlocked yes)
			(layer "F.Fab")
			(hide yes)
			(effects
				(font
					(size 1 1)
					(thickness 0.15)
				)
			)
		)
		(property "Val" "3k3"
			(at 0 0 90)
			(unlocked yes)
			(layer "F.Fab")
			(hide yes)
			(effects
				(font
					(size 1 1)
					(thickness 0.15)
				)
			)
		)
		(property "Tolerance" "1%"
			(at 0 0 90)
			(unlocked yes)
			(layer "F.Fab")
			(hide yes)
			(effects
				(font
					(size 1 1)
					(thickness 0.15)
				)
			)
		)
		(sheetname "/X710-AT2 10GbE/")
		(sheetfile "x710-at2-10gbe.kicad_sch")
		(attr smd)
		(fp_rect
			(start -0.925 -0.47)
			(end 0.925 0.47)
			(stroke
				(width 0.05)
				(type default)
			)
			(fill no)
			(layer "F.CrtYd")
		)
		(fp_rect
			(start -0.5 -0.25)
			(end 0.5 0.25)
			(stroke
				(width 0.15)
				(type solid)
			)
			(fill no)
			(layer "F.Fab")
		)
		(pad "1" smd roundrect
			(at -0.48 0 90)
			(size 0.59 0.64)
			(layers "F.Cu" "F.Mask" "F.Paste")
			(roundrect_rratio 0.25)
			(net 132 "/X710-AT2 10GbE/MDIO0_SDA0")
			(pintype "passive")
		)
		(pad "2" smd roundrect
			(at 0.48 0 90)
			(size 0.59 0.64)
			(layers "F.Cu" "F.Mask" "F.Paste")
			(roundrect_rratio 0.25)
			(net 7 "+3V3")
			(pintype "passive")
		)
	)
	(footprint "antmicro-footprints:R_0402_1005Metric"
		(layer "F.Cu")
		(at 73.849999 82.039995)
		(descr "Resistor SMD 0402")
		(tags "resistor SMD 0402")
		(property "Reference" "R4"
			(at -3.899999 -7.139995 0)
			(layer "F.SilkS")
			(effects
				(font
					(size 0.7 0.7)
					(thickness 0.15)
				)
				(justify left bottom)
			)
		)
		(property "Value" "R_100k_0402"
			(at -1.011843 1.772046 0)
			(layer "F.Fab")
			(hide yes)
			(effects
				(font
					(size 0.7 0.7)
					(thickness 0.15)
				)
				(justify left bottom)
			)
		)
		(property "Datasheet" "https://www.bourns.com/docs/product-datasheets/cr.pdf"
			(at 0 0 0)
			(layer "F.Fab")
			(hide yes)
			(effects
				(font
					(size 1.27 1.27)
					(thickness 0.15)
				)
			)
		)
		(property "Description" "SMD Chip Resistor, 100 kohm, ± 1%, 62.5 mW, 0402 [1005 Metric], Thick Film, General Purpose"
			(at 0 0 0)
			(layer "F.Fab")
			(hide yes)
			(effects
				(font
					(size 1.27 1.27)
					(thickness 0.15)
				)
			)
		)
		(property "MPN" "CR0402-FX-1003GLF"
			(at 0 0 0)
			(unlocked yes)
			(layer "F.Fab")
			(hide yes)
			(effects
				(font
					(size 1 1)
					(thickness 0.15)
				)
			)
		)
		(property "Manufacturer" "Bourns"
			(at 0 0 0)
			(unlocked yes)
			(layer "F.Fab")
			(hide yes)
			(effects
				(font
					(size 1 1)
					(thickness 0.15)
				)
			)
		)
		(property "License" "Apache-2.0"
			(at 0 0 0)
			(unlocked yes)
			(layer "F.Fab")
			(hide yes)
			(effects
				(font
					(size 1 1)
					(thickness 0.15)
				)
			)
		)
		(property "Author" "Antmicro"
			(at 0 0 0)
			(unlocked yes)
			(layer "F.Fab")
			(hide yes)
			(effects
				(font
					(size 1 1)
					(thickness 0.15)
				)
			)
		)
		(property "Val" "100k"
			(at 0 0 0)
			(unlocked yes)
			(layer "F.Fab")
			(hide yes)
			(effects
				(font
					(size 1 1)
					(thickness 0.15)
				)
			)
		)
		(property "Tolerance" "1%"
			(at 0 0 0)
			(unlocked yes)
			(layer "F.Fab")
			(hide yes)
			(effects
				(font
					(size 1 1)
					(thickness 0.15)
				)
			)
		)
		(sheetname "/Power/")
		(sheetfile "power.kicad_sch")
		(attr smd)
		(fp_rect
			(start -0.925 -0.47)
			(end 0.925 0.47)
			(stroke
				(width 0.05)
				(type default)
			)
			(fill no)
			(layer "F.CrtYd")
		)
		(fp_rect
			(start -0.5 -0.25)
			(end 0.5 0.25)
			(stroke
				(width 0.15)
				(type solid)
			)
			(fill no)
			(layer "F.Fab")
		)
		(pad "1" smd roundrect
			(at -0.48 0)
			(size 0.59 0.64)
			(layers "F.Cu" "F.Mask" "F.Paste")
			(roundrect_rratio 0.25)
			(net 338 "/Power/3V3_PG")
			(pintype "passive")
		)
		(pad "2" smd roundrect
			(at 0.48 0)
			(size 0.59 0.64)
			(layers "F.Cu" "F.Mask" "F.Paste")
			(roundrect_rratio 0.25)
			(net 315 "/Power/3V3_VCC")
			(pintype "passive")
		)
	)
	(footprint "antmicro-footprints:R_0402_1005Metric"
		(layer "F.Cu")
		(at 99.349999 109.1 180)
		(descr "Resistor SMD 0402")
		(tags "resistor SMD 0402")
		(property "Reference" "R44"
			(at 1.249999 -15.7 0)
			(layer "F.SilkS")
			(effects
				(font
					(size 0.7 0.7)
					(thickness 0.15)
				)
				(justify left bottom)
			)
		)
		(property "Value" "R_22R_0402"
			(at -1.011843 1.772046 0)
			(layer "F.Fab")
			(hide yes)
			(effects
				(font
					(size 0.7 0.7)
					(thickness 0.15)
				)
				(justify right top)
			)
		)
		(property "Datasheet" "https://www.bourns.com/docs/product-datasheets/cr.pdf"
			(at 0 0 0)
			(layer "F.Fab")
			(hide yes)
			(effects
				(font
					(size 1.27 1.27)
					(thickness 0.15)
				)
			)
		)
		(property "Description" "SMD Chip Resistor, 22 ohm, ± 1%, 62.5 mW, 0402 [1005 Metric], Thick Film, General Purpose"
			(at 0 0 0)
			(layer "F.Fab")
			(hide yes)
			(effects
				(font
					(size 1.27 1.27)
					(thickness 0.15)
				)
			)
		)
		(property "MPN" "CR0402-FX-22R0GLF"
			(at 0 0 180)
			(unlocked yes)
			(layer "F.Fab")
			(hide yes)
			(effects
				(font
					(size 1 1)
					(thickness 0.15)
				)
			)
		)
		(property "Manufacturer" "Bourns"
			(at 0 0 180)
			(unlocked yes)
			(layer "F.Fab")
			(hide yes)
			(effects
				(font
					(size 1 1)
					(thickness 0.15)
				)
			)
		)
		(property "License" "Apache-2.0"
			(at 0 0 180)
			(unlocked yes)
			(layer "F.Fab")
			(hide yes)
			(effects
				(font
					(size 1 1)
					(thickness 0.15)
				)
			)
		)
		(property "Author" "Antmicro"
			(at 0 0 180)
			(unlocked yes)
			(layer "F.Fab")
			(hide yes)
			(effects
				(font
					(size 1 1)
					(thickness 0.15)
				)
			)
		)
		(property "Val" "22R"
			(at 0 0 180)
			(unlocked yes)
			(layer "F.Fab")
			(hide yes)
			(effects
				(font
					(size 1 1)
					(thickness 0.15)
				)
			)
		)
		(property "Tolerance" "1%"
			(at 0 0 180)
			(unlocked yes)
			(layer "F.Fab")
			(hide yes)
			(effects
				(font
					(size 1 1)
					(thickness 0.15)
				)
			)
		)
		(sheetname "/X710-AT2 10GbE/")
		(sheetfile "x710-at2-10gbe.kicad_sch")
		(attr smd)
		(fp_rect
			(start -0.925 -0.47)
			(end 0.925 0.47)
			(stroke
				(width 0.05)
				(type default)
			)
			(fill no)
			(layer "F.CrtYd")
		)
		(fp_rect
			(start -0.5 -0.25)
			(end 0.5 0.25)
			(stroke
				(width 0.15)
				(type solid)
			)
			(fill no)
			(layer "F.Fab")
		)
		(pad "1" smd roundrect
			(at -0.48 0 180)
			(size 0.59 0.64)
			(layers "F.Cu" "F.Mask" "F.Paste")
			(roundrect_rratio 0.25)
			(net 150 "/X710-AT2 10GbE/25MHZ_OSC_R.-")
			(pintype "passive")
		)
		(pad "2" smd roundrect
			(at 0.48 0 180)
			(size 0.59 0.64)
			(layers "F.Cu" "F.Mask" "F.Paste")
			(roundrect_rratio 0.25)
			(net 73 "/X710-AT2 10GbE/25MHZ_OSC_AC.-")
			(pintype "passive")
		)
	)
	(footprint "antmicro-footprints:R_0402_1005Metric"
		(layer "F.Cu")
		(at 99.35 106.15 180)
		(descr "Resistor SMD 0402")
		(tags "resistor SMD 0402")
		(property "Reference" "R82"
			(at 1.25 -15.425 0)
			(layer "F.SilkS")
			(effects
				(font
					(size 0.7 0.7)
					(thickness 0.15)
				)
				(justify left bottom)
			)
		)
		(property "Value" "R_100k_0402"
			(at -1.011843 1.772046 0)
			(layer "F.Fab")
			(hide yes)
			(effects
				(font
					(size 0.7 0.7)
					(thickness 0.15)
				)
				(justify right top)
			)
		)
		(property "Datasheet" "https://www.bourns.com/docs/product-datasheets/cr.pdf"
			(at 0 0 0)
			(layer "F.Fab")
			(hide yes)
			(effects
				(font
					(size 1.27 1.27)
					(thickness 0.15)
				)
			)
		)
		(property "Description" "SMD Chip Resistor, 100 kohm, ± 1%, 62.5 mW, 0402 [1005 Metric], Thick Film, General Purpose"
			(at 0 0 0)
			(layer "F.Fab")
			(hide yes)
			(effects
				(font
					(size 1.27 1.27)
					(thickness 0.15)
				)
			)
		)
		(property "MPN" "CR0402-FX-1003GLF"
			(at 0 0 180)
			(unlocked yes)
			(layer "F.Fab")
			(hide yes)
			(effects
				(font
					(size 1 1)
					(thickness 0.15)
				)
			)
		)
		(property "Manufacturer" "Bourns"
			(at 0 0 180)
			(unlocked yes)
			(layer "F.Fab")
			(hide yes)
			(effects
				(font
					(size 1 1)
					(thickness 0.15)
				)
			)
		)
		(property "License" "Apache-2.0"
			(at 0 0 180)
			(unlocked yes)
			(layer "F.Fab")
			(hide yes)
			(effects
				(font
					(size 1 1)
					(thickness 0.15)
				)
			)
		)
		(property "Author" "Antmicro"
			(at 0 0 180)
			(unlocked yes)
			(layer "F.Fab")
			(hide yes)
			(effects
				(font
					(size 1 1)
					(thickness 0.15)
				)
			)
		)
		(property "Val" "100k"
			(at 0 0 180)
			(unlocked yes)
			(layer "F.Fab")
			(hide yes)
			(effects
				(font
					(size 1 1)
					(thickness 0.15)
				)
			)
		)
		(property "Tolerance" "1%"
			(at 0 0 180)
			(unlocked yes)
			(layer "F.Fab")
			(hide yes)
			(effects
				(font
					(size 1 1)
					(thickness 0.15)
				)
			)
		)
		(sheetname "/X710-AT2 Misc/")
		(sheetfile "x710-at2-mics.kicad_sch")
		(attr smd exclude_from_pos_files exclude_from_bom dnp)
		(fp_rect
			(start -0.925 -0.47)
			(end 0.925 0.47)
			(stroke
				(width 0.05)
				(type default)
			)
			(fill no)
			(layer "F.CrtYd")
		)
		(fp_rect
			(start -0.5 -0.25)
			(end 0.5 0.25)
			(stroke
				(width 0.15)
				(type solid)
			)
			(fill no)
			(layer "F.Fab")
		)
		(pad "1" smd roundrect
			(at -0.48 0 180)
			(size 0.59 0.64)
			(layers "F.Cu" "F.Mask" "F.Paste")
			(roundrect_rratio 0.25)
			(net 364 "/X710-AT2 Misc/NCSI.ARB_OUT")
			(pintype "passive")
		)
		(pad "2" smd roundrect
			(at 0.48 0 180)
			(size 0.59 0.64)
			(layers "F.Cu" "F.Mask" "F.Paste")
			(roundrect_rratio 0.25)
			(net 7 "+3V3")
			(pintype "passive")
		)
	)
	(footprint "antmicro-footprints:R_0402_1005Metric"
		(layer "F.Cu")
		(at 110.35 93.45 -90)
		(descr "Resistor SMD 0402")
		(tags "resistor SMD 0402")
		(property "Reference" "R67"
			(at -3.85 -0.35 90)
			(layer "F.SilkS")
			(effects
				(font
					(size 0.7 0.7)
					(thickness 0.15)
				)
				(justify left bottom)
			)
		)
		(property "Value" "R_10R_0402"
			(at -1.011843 1.772046 90)
			(layer "F.Fab")
			(hide yes)
			(effects
				(font
					(size 0.7 0.7)
					(thickness 0.15)
				)
				(justify right top)
			)
		)
		(property "Datasheet" "https://www.bourns.com/docs/product-datasheets/cr.pdf"
			(at 0 0 90)
			(layer "F.Fab")
			(hide yes)
			(effects
				(font
					(size 1.27 1.27)
					(thickness 0.15)
				)
			)
		)
		(property "Description" "SMD Chip Resistor, 10 ohm, ± 1%, 62.5 mW, 0402 [1005 Metric], Thick Film, General Purpose"
			(at 0 0 90)
			(layer "F.Fab")
			(hide yes)
			(effects
				(font
					(size 1.27 1.27)
					(thickness 0.15)
				)
			)
		)
		(property "MPN" "CR0402-FX-10R0GLF"
			(at 0 0 270)
			(unlocked yes)
			(layer "F.Fab")
			(hide yes)
			(effects
				(font
					(size 1 1)
					(thickness 0.15)
				)
			)
		)
		(property "Manufacturer" "Bourns"
			(at 0 0 270)
			(unlocked yes)
			(layer "F.Fab")
			(hide yes)
			(effects
				(font
					(size 1 1)
					(thickness 0.15)
				)
			)
		)
		(property "License" "Apache-2.0"
			(at 0 0 270)
			(unlocked yes)
			(layer "F.Fab")
			(hide yes)
			(effects
				(font
					(size 1 1)
					(thickness 0.15)
				)
			)
		)
		(property "Author" "Antmicro"
			(at 0 0 270)
			(unlocked yes)
			(layer "F.Fab")
			(hide yes)
			(effects
				(font
					(size 1 1)
					(thickness 0.15)
				)
			)
		)
		(property "Val" "10R"
			(at 0 0 270)
			(unlocked yes)
			(layer "F.Fab")
			(hide yes)
			(effects
				(font
					(size 1 1)
					(thickness 0.15)
				)
			)
		)
		(property "Tolerance" "1%"
			(at 0 0 270)
			(unlocked yes)
			(layer "F.Fab")
			(hide yes)
			(effects
				(font
					(size 1 1)
					(thickness 0.15)
				)
			)
		)
		(sheetname "/X710-AT2 10GbE/")
		(sheetfile "x710-at2-10gbe.kicad_sch")
		(attr smd)
		(fp_rect
			(start -0.925 -0.47)
			(end 0.925 0.47)
			(stroke
				(width 0.05)
				(type default)
			)
			(fill no)
			(layer "F.CrtYd")
		)
		(fp_rect
			(start -0.5 -0.25)
			(end 0.5 0.25)
			(stroke
				(width 0.15)
				(type solid)
			)
			(fill no)
			(layer "F.Fab")
		)
		(pad "1" smd roundrect
			(at -0.48 0 270)
			(size 0.59 0.64)
			(layers "F.Cu" "F.Mask" "F.Paste")
			(roundrect_rratio 0.25)
			(net 215 "/X710-AT2 10GbE/MDIO0_I2C0.MDIO")
			(pintype "passive")
		)
		(pad "2" smd roundrect
			(at 0.48 0 270)
			(size 0.59 0.64)
			(layers "F.Cu" "F.Mask" "F.Paste")
			(roundrect_rratio 0.25)
			(net 132 "/X710-AT2 10GbE/MDIO0_SDA0")
			(pintype "passive")
		)
	)
	(footprint "antmicro-footprints:R_0402_1005Metric"
		(layer "F.Cu")
		(at 99.35 104.25 180)
		(descr "Resistor SMD 0402")
		(tags "resistor SMD 0402")
		(property "Reference" "R78"
			(at 1.25 -15.175 0)
			(layer "F.SilkS")
			(effects
				(font
					(size 0.7 0.7)
					(thickness 0.15)
				)
				(justify left bottom)
			)
		)
		(property "Value" "R_100k_0402"
			(at -1.011843 1.772046 0)
			(layer "F.Fab")
			(hide yes)
			(effects
				(font
					(size 0.7 0.7)
					(thickness 0.15)
				)
				(justify right top)
			)
		)
		(property "Datasheet" "https://www.bourns.com/docs/product-datasheets/cr.pdf"
			(at 0 0 0)
			(layer "F.Fab")
			(hide yes)
			(effects
				(font
					(size 1.27 1.27)
					(thickness 0.15)
				)
			)
		)
		(property "Description" "SMD Chip Resistor, 100 kohm, ± 1%, 62.5 mW, 0402 [1005 Metric], Thick Film, General Purpose"
			(at 0 0 0)
			(layer "F.Fab")
			(hide yes)
			(effects
				(font
					(size 1.27 1.27)
					(thickness 0.15)
				)
			)
		)
		(property "MPN" "CR0402-FX-1003GLF"
			(at 0 0 180)
			(unlocked yes)
			(layer "F.Fab")
			(hide yes)
			(effects
				(font
					(size 1 1)
					(thickness 0.15)
				)
			)
		)
		(property "Manufacturer" "Bourns"
			(at 0 0 180)
			(unlocked yes)
			(layer "F.Fab")
			(hide yes)
			(effects
				(font
					(size 1 1)
					(thickness 0.15)
				)
			)
		)
		(property "License" "Apache-2.0"
			(at 0 0 180)
			(unlocked yes)
			(layer "F.Fab")
			(hide yes)
			(effects
				(font
					(size 1 1)
					(thickness 0.15)
				)
			)
		)
		(property "Author" "Antmicro"
			(at 0 0 180)
			(unlocked yes)
			(layer "F.Fab")
			(hide yes)
			(effects
				(font
					(size 1 1)
					(thickness 0.15)
				)
			)
		)
		(property "Val" "100k"
			(at 0 0 180)
			(unlocked yes)
			(layer "F.Fab")
			(hide yes)
			(effects
				(font
					(size 1 1)
					(thickness 0.15)
				)
			)
		)
		(property "Tolerance" "1%"
			(at 0 0 180)
			(unlocked yes)
			(layer "F.Fab")
			(hide yes)
			(effects
				(font
					(size 1 1)
					(thickness 0.15)
				)
			)
		)
		(sheetname "/X710-AT2 Misc/")
		(sheetfile "x710-at2-mics.kicad_sch")
		(attr smd)
		(fp_rect
			(start -0.925 -0.47)
			(end 0.925 0.47)
			(stroke
				(width 0.05)
				(type default)
			)
			(fill no)
			(layer "F.CrtYd")
		)
		(fp_rect
			(start -0.5 -0.25)
			(end 0.5 0.25)
			(stroke
				(width 0.15)
				(type solid)
			)
			(fill no)
			(layer "F.Fab")
		)
		(pad "1" smd roundrect
			(at -0.48 0 180)
			(size 0.59 0.64)
			(layers "F.Cu" "F.Mask" "F.Paste")
			(roundrect_rratio 0.25)
			(net 360 "/X710-AT2 Misc/NCSI.RXD_1")
			(pintype "passive")
		)
		(pad "2" smd roundrect
			(at 0.48 0 180)
			(size 0.59 0.64)
			(layers "F.Cu" "F.Mask" "F.Paste")
			(roundrect_rratio 0.25)
			(net 7 "+3V3")
			(pintype "passive")
		)
	)
	(footprint "antmicro-footprints:Vishay_PowerPAK_1212-8_Single"
		(layer "F.Cu")
		(at 66.76 66 90)
		(descr "PowerPAK 1212-8 Single")
		(tags "Vishay PowerPAK 1212-8 Single")
		(property "Reference" "Q2"
			(at -1.75 -1.86 90)
			(layer "F.SilkS")
			(effects
				(font
					(size 0.7 0.7)
					(thickness 0.15)
				)
				(justify left bottom)
			)
		)
		(property "Value" "SQS401EN-T1_BE3"
			(at 0 2.7 90)
			(layer "F.Fab")
			(hide yes)
			(effects
				(font
					(size 0.7 0.7)
					(thickness 0.15)
				)
				(justify left bottom)
			)
		)
		(property "Datasheet" "https://www.vishay.com/docs/65529/sqs401en.pdf"
			(at 0 0 90)
			(layer "F.Fab")
			(hide yes)
			(effects
				(font
					(size 1.27 1.27)
					(thickness 0.15)
				)
			)
		)
		(property "Description" "MOSFET, P Channel, 40 V, 16A, 0.047 ohm, PowerPAK 1212-8, Surface Mount"
			(at 0 0 90)
			(layer "F.Fab")
			(hide yes)
			(effects
				(font
					(size 1.27 1.27)
					(thickness 0.15)
				)
			)
		)
		(property "MPN" "SQS401EN-T1_BE3"
			(at 0 0 90)
			(unlocked yes)
			(layer "F.Fab")
			(hide yes)
			(effects
				(font
					(size 1 1)
					(thickness 0.15)
				)
			)
		)
		(property "Manufacturer" "Vishay"
			(at 0 0 90)
			(unlocked yes)
			(layer "F.Fab")
			(hide yes)
			(effects
				(font
					(size 1 1)
					(thickness 0.15)
				)
			)
		)
		(property "Author" "Antmicro"
			(at 0 0 90)
			(unlocked yes)
			(layer "F.Fab")
			(hide yes)
			(effects
				(font
					(size 1 1)
					(thickness 0.15)
				)
			)
		)
		(property "License" "Apache-2.0"
			(at 0 0 90)
			(unlocked yes)
			(layer "F.Fab")
			(hide yes)
			(effects
				(font
					(size 1 1)
					(thickness 0.15)
				)
			)
		)
		(sheetname "/Power/Ideal diode 1/")
		(sheetfile "ideal-diode.kicad_sch")
		(attr smd)
		(fp_line
			(start 1.648 -1.651)
			(end 1.648 -1.317)
			(stroke
				(width 0.15)
				(type solid)
			)
			(layer "F.SilkS")
		)
		(fp_line
			(start -1.651 -1.651)
			(end 1.648 -1.651)
			(stroke
				(width 0.15)
				(type solid)
			)
			(layer "F.SilkS")
		)
		(fp_line
			(start -1.651 -1.651)
			(end -1.651 -1.317)
			(stroke
				(width 0.15)
				(type solid)
			)
			(layer "F.SilkS")
		)
		(fp_line
			(start 1.634 1.3)
			(end 1.634 1.634)
			(stroke
				(width 0.15)
				(type solid)
			)
			(layer "F.SilkS")
		)
		(fp_line
			(start -1.635 1.3)
			(end -1.635 1.634)
			(stroke
				(width 0.15)
				(type solid)
			)
			(layer "F.SilkS")
		)
		(fp_line
			(start -1.635 1.634)
			(end 1.634 1.634)
			(stroke
				(width 0.15)
				(type solid)
			)
			(layer "F.SilkS")
		)
		(fp_circle
			(center -1.9 -1.4)
			(end -1.85 -1.4)
			(stroke
				(width 0.15)
				(type solid)
			)
			(fill yes)
			(layer "F.SilkS")
		)
		(fp_rect
			(start -2 -1.8)
			(end 2 1.798)
			(stroke
				(width 0.05)
				(type solid)
			)
			(fill no)
			(layer "F.CrtYd")
		)
		(fp_line
			(start -1.6425 -1.4175)
			(end -1.4175 -1.6425)
			(stroke
				(width 0.15)
				(type solid)
			)
			(layer "F.Fab")
		)
		(fp_rect
			(start -1.651 -1.651)
			(end 1.648 1.648)
			(stroke
				(width 0.15)
				(type solid)
			)
			(fill no)
			(layer "F.Fab")
		)
		(pad "1" smd rect
			(at -1.436 -0.99 90)
			(size 0.99 0.405)
			(layers "F.Cu" "F.Mask" "F.Paste")
			(net 314 "VCC")
			(pinfunction "S")
			(pintype "passive")
		)
		(pad "2" smd rect
			(at -1.436 -0.332 90)
			(size 0.99 0.405)
			(layers "F.Cu" "F.Mask" "F.Paste")
			(net 314 "VCC")
			(pinfunction "S")
			(pintype "passive")
		)
		(pad "3" smd rect
			(at -1.436 0.33 90)
			(size 0.99 0.405)
			(layers "F.Cu" "F.Mask" "F.Paste")
			(net 314 "VCC")
			(pinfunction "S")
			(pintype "passive")
		)
		(pad "4" smd rect
			(at -1.436 0.988 90)
			(size 0.99 0.405)
			(layers "F.Cu" "F.Mask" "F.Paste")
			(net 373 "Net-(Q2-G)")
			(pinfunction "G")
			(pintype "passive")
		)
		(pad "5" smd custom
			(at 0.557 0 90)
			(size 1.725 2.235)
			(layers "F.Cu" "F.Mask" "F.Paste")
			(net 350 "/Power/+12V_IN")
			(pinfunction "D")
			(pintype "passive")
			(zone_connect 2)
			(options
				(clearance outline)
				(anchor rect)
			)
			(primitives
				(gr_poly
					(pts
						(xy 0.8625 0.1275) (xy 0.8625 -0.1275) (xy 1.3725 -0.1275) (xy 1.3725 -0.5325) (xy 0.8625 -0.5325)
						(xy 0.8625 -0.7875) (xy 1.3725 -0.7875) (xy 1.3725 -1.195) (xy 0.6125 -1.195) (xy 0.6125 1.195)
						(xy 1.3725 1.195) (xy 1.3725 0.7875) (xy 0.8625 0.7875) (xy 0.8625 0.5325) (xy 1.3725 0.5325)
						(xy 1.3725 0.1275)
					)
					(width 0)
					(fill yes)
				)
			)
		)
	)
	(footprint "antmicro-footprints:R_0402_1005Metric"
		(layer "F.Cu")
		(at 90.1 112.45 90)
		(descr "Resistor SMD 0402")
		(tags "resistor SMD 0402")
		(property "Reference" "R69"
			(at -0.85 0.475 90)
			(layer "F.SilkS")
			(effects
				(font
					(size 0.7 0.7)
					(thickness 0.15)
				)
				(justify right bottom)
			)
		)
		(property "Value" "R_0R_0402"
			(at -1.011843 1.772046 90)
			(layer "F.Fab")
			(hide yes)
			(effects
				(font
					(size 0.7 0.7)
					(thickness 0.15)
				)
				(justify left bottom)
			)
		)
		(property "Datasheet" "https://industrial.panasonic.com/cdbs/www-data/pdf/RDA0000/AOA0000C301.pdf"
			(at 0 0 90)
			(layer "F.Fab")
			(hide yes)
			(effects
				(font
					(size 1.27 1.27)
					(thickness 0.15)
				)
			)
		)
		(property "Description" "SMD Chip Resistor, Jumper, 0 ohm, 100 mW, 0402 [1005 Metric], Thick Film, General Purpose"
			(at 0 0 90)
			(layer "F.Fab")
			(hide yes)
			(effects
				(font
					(size 1.27 1.27)
					(thickness 0.15)
				)
			)
		)
		(property "MPN" "ERJ2GE0R00X"
			(at 0 0 90)
			(unlocked yes)
			(layer "F.Fab")
			(hide yes)
			(effects
				(font
					(size 1 1)
					(thickness 0.15)
				)
			)
		)
		(property "Manufacturer" "Panasonic"
			(at 0 0 90)
			(unlocked yes)
			(layer "F.Fab")
			(hide yes)
			(effects
				(font
					(size 1 1)
					(thickness 0.15)
				)
			)
		)
		(property "License" "Apache-2.0"
			(at 0 0 90)
			(unlocked yes)
			(layer "F.Fab")
			(hide yes)
			(effects
				(font
					(size 1 1)
					(thickness 0.15)
				)
			)
		)
		(property "Author" "Antmicro"
			(at 0 0 90)
			(unlocked yes)
			(layer "F.Fab")
			(hide yes)
			(effects
				(font
					(size 1 1)
					(thickness 0.15)
				)
			)
		)
		(property "Val" "0R"
			(at 0 0 90)
			(unlocked yes)
			(layer "F.Fab")
			(hide yes)
			(effects
				(font
					(size 1 1)
					(thickness 0.15)
				)
			)
		)
		(property "Tolerance" "~"
			(at 0 0 90)
			(unlocked yes)
			(layer "F.Fab")
			(hide yes)
			(effects
				(font
					(size 1 1)
					(thickness 0.15)
				)
			)
		)
		(property "Current" "1A"
			(at 0 0 90)
			(unlocked yes)
			(layer "F.Fab")
			(hide yes)
			(effects
				(font
					(size 1 1)
					(thickness 0.15)
				)
			)
		)
		(sheetname "/X710-AT2 10GbE/")
		(sheetfile "x710-at2-10gbe.kicad_sch")
		(attr smd)
		(fp_rect
			(start -0.925 -0.47)
			(end 0.925 0.47)
			(stroke
				(width 0.05)
				(type default)
			)
			(fill no)
			(layer "F.CrtYd")
		)
		(fp_rect
			(start -0.5 -0.25)
			(end 0.5 0.25)
			(stroke
				(width 0.15)
				(type solid)
			)
			(fill no)
			(layer "F.Fab")
		)
		(pad "1" smd roundrect
			(at -0.48 0 90)
			(size 0.59 0.64)
			(layers "F.Cu" "F.Mask" "F.Paste")
			(roundrect_rratio 0.25)
			(net 380 "/X710-AT2 10GbE/~{PHY_RESET_3V3}")
			(pintype "passive")
		)
		(pad "2" smd roundrect
			(at 0.48 0 90)
			(size 0.59 0.64)
			(layers "F.Cu" "F.Mask" "F.Paste")
			(roundrect_rratio 0.25)
			(net 141 "/X710-AT2 10GbE/~{PHY_RESET_3V3_R}")
			(pintype "passive")
		)
	)
	(footprint "antmicro-footprints:L_Bourns-SRP4021HMT"
		(layer "F.Cu")
		(at 60.249999 103.850001 180)
		(property "Reference" "L3"
			(at -4.030001 0.220001 0)
			(layer "F.SilkS")
			(effects
				(font
					(size 0.7 0.7)
					(thickness 0.15)
				)
				(justify right top)
			)
		)
		(property "Value" "L_1u_10A_Bourns-SRP4021HMT"
			(at -2.85 3.4 0)
			(layer "F.Fab")
			(hide yes)
			(effects
				(font
					(size 0.7 0.7)
					(thickness 0.15)
				)
				(justify right top)
			)
		)
		(property "Datasheet" "https://www.mouser.com/datasheet/2/54/Bourns_04_01_2025_SRP4021HMT_Datasheet-3580094.pdf"
			(at 0 0 0)
			(layer "F.Fab")
			(hide yes)
			(effects
				(font
					(size 0.7 0.7)
					(thickness 0.15)
				)
				(justify right top)
			)
		)
		(property "Description" "Power Inductors - SMD Ind,4.1x4.2x1.9mm,1uH+/-20%,10A, Shielded"
			(at 0 0 0)
			(layer "F.Fab")
			(hide yes)
			(effects
				(font
					(size 0.7 0.7)
					(thickness 0.15)
				)
				(justify right top)
			)
		)
		(property "Val" "1u/10A"
			(at 0 0 180)
			(unlocked yes)
			(layer "F.Fab")
			(hide yes)
			(effects
				(font
					(size 1 1)
					(thickness 0.15)
				)
			)
		)
		(property "Manufacturer" "Bourns"
			(at 0 0 180)
			(unlocked yes)
			(layer "F.Fab")
			(hide yes)
			(effects
				(font
					(size 1 1)
					(thickness 0.15)
				)
			)
		)
		(property "MPN" "SRP4021HMT-1R0M"
			(at 0 0 180)
			(unlocked yes)
			(layer "F.Fab")
			(hide yes)
			(effects
				(font
					(size 1 1)
					(thickness 0.15)
				)
			)
		)
		(property "ISat" ""
			(at 0 0 180)
			(unlocked yes)
			(layer "F.Fab")
			(hide yes)
			(effects
				(font
					(size 1 1)
					(thickness 0.15)
				)
			)
		)
		(property "Isat" "8A"
			(at 0 0 180)
			(unlocked yes)
			(layer "F.Fab")
			(hide yes)
			(effects
				(font
					(size 1 1)
					(thickness 0.15)
				)
			)
		)
		(property "IMax" ""
			(at 0 0 180)
			(unlocked yes)
			(layer "F.Fab")
			(hide yes)
			(effects
				(font
					(size 1 1)
					(thickness 0.15)
				)
			)
		)
		(property "Imax" "10A"
			(at 0 0 180)
			(unlocked yes)
			(layer "F.Fab")
			(hide yes)
			(effects
				(font
					(size 1 1)
					(thickness 0.15)
				)
			)
		)
		(property "Size" "4.2x4.1"
			(at 0 0 180)
			(unlocked yes)
			(layer "F.Fab")
			(hide yes)
			(effects
				(font
					(size 1 1)
					(thickness 0.15)
				)
			)
		)
		(property "Author" "Antmicro"
			(at 0 0 180)
			(unlocked yes)
			(layer "F.Fab")
			(hide yes)
			(effects
				(font
					(size 1 1)
					(thickness 0.15)
				)
			)
		)
		(property "License" "Apache-2.0"
			(at 0 0 180)
			(unlocked yes)
			(layer "F.Fab")
			(hide yes)
			(effects
				(font
					(size 1 1)
					(thickness 0.15)
				)
			)
		)
		(sheetname "/Power/")
		(sheetfile "power.kicad_sch")
		(attr smd)
		(fp_line
			(start -0.8 2.05)
			(end 0.8 2.05)
			(stroke
				(width 0.15)
				(type solid)
			)
			(layer "F.SilkS")
		)
		(fp_line
			(start -0.8 -2.05)
			(end 0.8 -2.05)
			(stroke
				(width 0.15)
				(type solid)
			)
			(layer "F.SilkS")
		)
		(fp_rect
			(start -2.85 -2.3)
			(end 2.85 2.3)
			(stroke
				(width 0.05)
				(type solid)
			)
			(fill no)
			(layer "F.CrtYd")
		)
		(fp_rect
			(start -2 -2.05)
			(end 2 2.05)
			(stroke
				(width 0.15)
				(type solid)
			)
			(fill no)
			(layer "F.Fab")
		)
		(pad "1" smd rect
			(at 1.85 0)
			(size 1.5 3.5)
			(layers "F.Cu" "F.Mask" "F.Paste")
			(net 335 "/Power/1V88_SW")
			(pintype "passive")
		)
		(pad "2" smd rect
			(at -1.85 0)
			(size 1.5 3.5)
			(layers "F.Cu" "F.Mask" "F.Paste")
			(net 310 "/Power/+1V88_OUT")
			(pintype "passive")
		)
	)
	(footprint "antmicro-footprints:R_0402_1005Metric"
		(layer "F.Cu")
		(at 92.85 60.6)
		(descr "Resistor SMD 0402")
		(tags "resistor SMD 0402")
		(property "Reference" "R127"
			(at -1.47 0.6 0)
			(layer "F.SilkS")
			(effects
				(font
					(size 0.7 0.7)
					(thickness 0.15)
				)
				(justify left top)
			)
		)
		(property "Value" "R_1k_0402"
			(at -1.011843 1.772047 0)
			(layer "F.Fab")
			(hide yes)
			(effects
				(font
					(size 0.7 0.7)
					(thickness 0.15)
				)
				(justify left bottom)
			)
		)
		(property "Datasheet" "https://www.bourns.com/docs/product-datasheets/cr.pdf"
			(at 0 0 0)
			(layer "F.Fab")
			(hide yes)
			(effects
				(font
					(size 1.27 1.27)
					(thickness 0.15)
				)
			)
		)
		(property "Description" "SMD Chip Resistor, 1 kohm, ± 1%, 63 mW, 0402 [1005 Metric], Thick Film, General Purpose"
			(at 0 0 0)
			(layer "F.Fab")
			(hide yes)
			(effects
				(font
					(size 1.27 1.27)
					(thickness 0.15)
				)
			)
		)
		(property "MPN" "CR0402-FX-1001GLF"
			(at 0 0 0)
			(unlocked yes)
			(layer "F.Fab")
			(hide yes)
			(effects
				(font
					(size 1 1)
					(thickness 0.15)
				)
			)
		)
		(property "Manufacturer" "Bourns"
			(at 0 0 0)
			(unlocked yes)
			(layer "F.Fab")
			(hide yes)
			(effects
				(font
					(size 1 1)
					(thickness 0.15)
				)
			)
		)
		(property "License" "Apache-2.0"
			(at 0 0 0)
			(unlocked yes)
			(layer "F.Fab")
			(hide yes)
			(effects
				(font
					(size 1 1)
					(thickness 0.15)
				)
			)
		)
		(property "Author" "Antmicro"
			(at 0 0 0)
			(unlocked yes)
			(layer "F.Fab")
			(hide yes)
			(effects
				(font
					(size 1 1)
					(thickness 0.15)
				)
			)
		)
		(property "Val" "1k"
			(at 0 0 0)
			(unlocked yes)
			(layer "F.Fab")
			(hide yes)
			(effects
				(font
					(size 1 1)
					(thickness 0.15)
				)
			)
		)
		(property "Tolerance" "1%"
			(at 0 0 0)
			(unlocked yes)
			(layer "F.Fab")
			(hide yes)
			(effects
				(font
					(size 1 1)
					(thickness 0.15)
				)
			)
		)
		(sheetname "/OCuLink/")
		(sheetfile "oculink.kicad_sch")
		(attr smd)
		(fp_rect
			(start -0.925 -0.47)
			(end 0.925 0.47)
			(stroke
				(width 0.05)
				(type default)
			)
			(fill no)
			(layer "F.CrtYd")
		)
		(fp_rect
			(start -0.5 -0.25)
			(end 0.5 0.25)
			(stroke
				(width 0.15)
				(type solid)
			)
			(fill no)
			(layer "F.Fab")
		)
		(pad "1" smd roundrect
			(at -0.48 0)
			(size 0.59 0.64)
			(layers "F.Cu" "F.Mask" "F.Paste")
			(roundrect_rratio 0.25)
			(net 410 "Net-(D15-A)")
			(pintype "passive")
		)
		(pad "2" smd roundrect
			(at 0.48 0)
			(size 0.59 0.64)
			(layers "F.Cu" "F.Mask" "F.Paste")
			(roundrect_rratio 0.25)
			(net 90 "+3V3_AUX")
			(pintype "passive")
		)
	)
	(footprint "antmicro-footprints:C_0402_1005Metric"
		(layer "F.Cu")
		(at 98.498001 62.778655 -90)
		(descr "Capacitor SMD 0402")
		(tags "capacitor SMD 0402")
		(property "Reference" "C194"
			(at 1.806345 -2.451999 270)
			(layer "F.SilkS")
			(effects
				(font
					(size 0.7 0.7)
					(thickness 0.15)
				)
				(justify left bottom)
			)
		)
		(property "Value" "C_220n_16V_0402"
			(at -1.022927 2.155213 270)
			(layer "F.Fab")
			(hide yes)
			(effects
				(font
					(size 0.7 0.7)
					(thickness 0.15)
				)
				(justify left bottom)
			)
		)
		(property "Datasheet" "https://www.murata.com/products/productdetail?partno=GRM155R71C224KA12%23"
			(at 0 0 270)
			(layer "F.Fab")
			(hide yes)
			(effects
				(font
					(size 1.27 1.27)
					(thickness 0.15)
				)
			)
		)
		(property "Description" "SMD Multilayer Ceramic Capacitor, 0.22 µF, 16 V, 0402 [1005 Metric], ± 10%, X7R, GRM Series"
			(at 0 0 270)
			(layer "F.Fab")
			(hide yes)
			(effects
				(font
					(size 1.27 1.27)
					(thickness 0.15)
				)
			)
		)
		(property "MPN" "GRM155R71C224KA12D"
			(at 0 0 270)
			(unlocked yes)
			(layer "F.Fab")
			(hide yes)
			(effects
				(font
					(size 1 1)
					(thickness 0.15)
				)
			)
		)
		(property "Manufacturer" "Murata"
			(at 0 0 270)
			(unlocked yes)
			(layer "F.Fab")
			(hide yes)
			(effects
				(font
					(size 1 1)
					(thickness 0.15)
				)
			)
		)
		(property "License" "Apache-2.0"
			(at 0 0 270)
			(unlocked yes)
			(layer "F.Fab")
			(hide yes)
			(effects
				(font
					(size 1 1)
					(thickness 0.15)
				)
			)
		)
		(property "Author" "Antmicro"
			(at 0 0 270)
			(unlocked yes)
			(layer "F.Fab")
			(hide yes)
			(effects
				(font
					(size 1 1)
					(thickness 0.15)
				)
			)
		)
		(property "Val" "220n"
			(at 0 0 270)
			(unlocked yes)
			(layer "F.Fab")
			(hide yes)
			(effects
				(font
					(size 1 1)
					(thickness 0.15)
				)
			)
		)
		(property "Voltage" "16V"
			(at 0 0 270)
			(unlocked yes)
			(layer "F.Fab")
			(hide yes)
			(effects
				(font
					(size 1 1)
					(thickness 0.15)
				)
			)
		)
		(property "Dielectric" "X7R"
			(at 0 0 270)
			(unlocked yes)
			(layer "F.Fab")
			(hide yes)
			(effects
				(font
					(size 1 1)
					(thickness 0.15)
				)
			)
		)
		(sheetname "/X710-AT2 PCIe/")
		(sheetfile "x710-at2-pcie.kicad_sch")
		(attr smd)
		(fp_rect
			(start -0.925 -0.47)
			(end 0.925 0.47)
			(stroke
				(width 0.05)
				(type default)
			)
			(fill no)
			(layer "F.CrtYd")
		)
		(fp_line
			(start -0.494 0.248)
			(end -0.494 -0.25)
			(stroke
				(width 0.15)
				(type solid)
			)
			(layer "F.Fab")
		)
		(fp_line
			(start 0.504 0.248)
			(end -0.494 0.248)
			(stroke
				(width 0.15)
				(type solid)
			)
			(layer "F.Fab")
		)
		(fp_line
			(start -0.494 -0.25)
			(end 0.504 -0.25)
			(stroke
				(width 0.15)
				(type solid)
			)
			(layer "F.Fab")
		)
		(fp_line
			(start 0.504 -0.25)
			(end 0.504 0.248)
			(stroke
				(width 0.15)
				(type solid)
			)
			(layer "F.Fab")
		)
		(pad "1" smd roundrect
			(at -0.48 0 270)
			(size 0.59 0.64)
			(layers "F.Cu" "F.Mask" "F.Paste")
			(roundrect_rratio 0.25)
			(net 21 "/OCuLink/PCIe_{x4}.TX2+")
			(pintype "passive")
		)
		(pad "2" smd roundrect
			(at 0.48 0 270)
			(size 0.59 0.64)
			(layers "F.Cu" "F.Mask" "F.Paste")
			(roundrect_rratio 0.25)
			(net 40 "/X710-AT2 PCIe/PCIe_{x4}_AC.TX2+")
			(pintype "passive")
		)
	)
	(footprint "antmicro-footprints:MP_Terminal_M3_THT_7760"
		(layer "F.Cu")
		(at 110.46 139.7)
		(property "Reference" "J5"
			(at -1.68 -1.9 0)
			(unlocked yes)
			(layer "F.SilkS")
			(effects
				(font
					(size 0.7 0.7)
					(thickness 0.15)
				)
				(justify left bottom)
			)
		)
		(property "Value" "MP_Terminal_M3_THT_7760"
			(at -1.68 11.43 0)
			(unlocked yes)
			(layer "F.Fab")
			(hide yes)
			(effects
				(font
					(size 0.7 0.7)
					(thickness 0.15)
				)
				(justify left bottom)
			)
		)
		(property "Datasheet" "https://www.mouser.com/datasheet/2/215/7760-741244.pdf"
			(at 0 0 0)
			(unlocked yes)
			(layer "F.Fab")
			(hide yes)
			(effects
				(font
					(size 0.7 0.7)
					(thickness 0.15)
				)
				(justify left bottom)
			)
		)
		(property "Description" "PCB Terminal, 90° THT, Brass, Tin"
			(at 0 0 0)
			(unlocked yes)
			(layer "F.Fab")
			(hide yes)
			(effects
				(font
					(size 0.7 0.7)
					(thickness 0.15)
				)
				(justify left bottom)
			)
		)
		(property "MPN" "7760"
			(at 0 0 0)
			(unlocked yes)
			(layer "F.Fab")
			(hide yes)
			(effects
				(font
					(size 1 1)
					(thickness 0.15)
				)
			)
		)
		(property "Manufacturer" "Keystone Electronics"
			(at 0 0 0)
			(unlocked yes)
			(layer "F.Fab")
			(hide yes)
			(effects
				(font
					(size 1 1)
					(thickness 0.15)
				)
			)
		)
		(property "Author" "Antmicro"
			(at 0 0 0)
			(unlocked yes)
			(layer "F.Fab")
			(hide yes)
			(effects
				(font
					(size 1 1)
					(thickness 0.15)
				)
			)
		)
		(property "License" "Apache-2.0"
			(at 0 0 0)
			(unlocked yes)
			(layer "F.Fab")
			(hide yes)
			(effects
				(font
					(size 1 1)
					(thickness 0.15)
				)
			)
		)
		(sheetname "/2xRJ45/")
		(sheetfile "2xrj45.kicad_sch")
		(attr through_hole allow_soldermask_bridges)
		(fp_line
			(start -0.42 3.255)
			(end -0.42 1.745)
			(stroke
				(width 0.15)
				(type solid)
			)
			(layer "F.SilkS")
		)
		(fp_line
			(start -0.42 6.745)
			(end -0.42 10.08)
			(stroke
				(width 0.15)
				(type solid)
			)
			(layer "F.SilkS")
		)
		(fp_line
			(start -0.42 10.08)
			(end 7.91 10.08)
			(stroke
				(width 0.15)
				(type solid)
			)
			(layer "F.SilkS")
		)
		(fp_line
			(start 1.745 -1.4)
			(end 5.745 -1.4)
			(stroke
				(width 0.15)
				(type solid)
			)
			(layer "F.SilkS")
		)
		(fp_line
			(start 7.91 3.255)
			(end 7.91 1.745)
			(stroke
				(width 0.15)
				(type solid)
			)
			(layer "F.SilkS")
		)
		(fp_line
			(start 7.91 10.08)
			(end 7.91 6.745)
			(stroke
				(width 0.15)
				(type solid)
			)
			(layer "F.SilkS")
		)
		(fp_rect
			(start -1.68 -1.68)
			(end 9.16 10.33)
			(stroke
				(width 0.05)
				(type solid)
			)
			(fill no)
			(layer "F.CrtYd")
		)
		(fp_rect
			(start -0.42 -1.4)
			(end 7.91 10.08)
			(stroke
				(width 0.15)
				(type solid)
			)
			(fill no)
			(layer "F.Fab")
		)
		(pad "1" thru_hole circle
			(at 0 0 90)
			(size 2.85 2.85)
			(drill 1.9)
			(layers "*.Cu" "*.Mask")
			(remove_unused_layers no)
			(net 28 "GND")
			(pintype "passive")
		)
		(pad "1" thru_hole circle
			(at 0 5 90)
			(size 2.85 2.85)
			(drill 1.9)
			(layers "*.Cu" "*.Mask")
			(remove_unused_layers no)
			(net 28 "GND")
			(pintype "passive")
		)
		(pad "1" thru_hole circle
			(at 7.49 0 90)
			(size 2.85 2.85)
			(drill 1.9)
			(layers "*.Cu" "*.Mask")
			(remove_unused_layers no)
			(net 28 "GND")
			(pintype "passive")
		)
		(pad "1" thru_hole circle
			(at 7.49 5 90)
			(size 2.85 2.85)
			(drill 1.9)
			(layers "*.Cu" "*.Mask")
			(remove_unused_layers no)
			(net 28 "GND")
			(pintype "passive")
		)
	)
	(footprint "antmicro-footprints:C_0603_1608Metric_EIA"
		(layer "F.Cu")
		(at 74.899998 83.909996 -90)
		(descr "Capacitor SMD 0603, IPC-7351 Density Level A")
		(tags "Capacitor 0603")
		(property "Reference" "C205"
			(at -3.999996 0.029998 90)
			(layer "F.SilkS")
			(effects
				(font
					(size 0.7 0.7)
					(thickness 0.15)
				)
				(justify right top)
			)
		)
		(property "Value" "C_22u_16V_0603"
			(at -1.42757 1.770288 90)
			(layer "F.Fab")
			(hide yes)
			(effects
				(font
					(size 0.7 0.7)
					(thickness 0.15)
				)
				(justify right top)
			)
		)
		(property "Datasheet" "https://product.samsungsem.com/mlcc/CL10A226MO7JZN.do"
			(at 0 0 90)
			(layer "F.Fab")
			(hide yes)
			(effects
				(font
					(size 1.27 1.27)
					(thickness 0.15)
				)
			)
		)
		(property "Description" "SMD Multilayer Ceramic Capacitor"
			(at 0 0 90)
			(layer "F.Fab")
			(hide yes)
			(effects
				(font
					(size 1.27 1.27)
					(thickness 0.15)
				)
			)
		)
		(property "MPN" "CL10A226MO7JZNC"
			(at 0 0 270)
			(unlocked yes)
			(layer "F.Fab")
			(hide yes)
			(effects
				(font
					(size 1 1)
					(thickness 0.15)
				)
			)
		)
		(property "Manufacturer" "Samsung Electro-Mechanics"
			(at 0 0 270)
			(unlocked yes)
			(layer "F.Fab")
			(hide yes)
			(effects
				(font
					(size 1 1)
					(thickness 0.15)
				)
			)
		)
		(property "License" "Apache-2.0"
			(at 0 0 270)
			(unlocked yes)
			(layer "F.Fab")
			(hide yes)
			(effects
				(font
					(size 1 1)
					(thickness 0.15)
				)
			)
		)
		(property "Author" "Antmicro"
			(at 0 0 270)
			(unlocked yes)
			(layer "F.Fab")
			(hide yes)
			(effects
				(font
					(size 1 1)
					(thickness 0.15)
				)
			)
		)
		(property "Val" "22u"
			(at 0 0 270)
			(unlocked yes)
			(layer "F.Fab")
			(hide yes)
			(effects
				(font
					(size 1 1)
					(thickness 0.15)
				)
			)
		)
		(property "Voltage" "16V"
			(at 0 0 270)
			(unlocked yes)
			(layer "F.Fab")
			(hide yes)
			(effects
				(font
					(size 1 1)
					(thickness 0.15)
				)
			)
		)
		(property "Dielectric" ""
			(at 0 0 270)
			(unlocked yes)
			(layer "F.Fab")
			(hide yes)
			(effects
				(font
					(size 1 1)
					(thickness 0.15)
				)
			)
		)
		(property "Public" "False"
			(at 0 0 270)
			(unlocked yes)
			(layer "F.Fab")
			(hide yes)
			(effects
				(font
					(size 1 1)
					(thickness 0.15)
				)
			)
		)
		(sheetname "/Power/")
		(sheetfile "power.kicad_sch")
		(attr smd)
		(fp_line
			(start -0.15 0.55)
			(end 0.15 0.55)
			(stroke
				(width 0.15)
				(type solid)
			)
			(layer "F.SilkS")
		)
		(fp_line
			(start -0.15 -0.55)
			(end 0.15 -0.55)
			(stroke
				(width 0.15)
				(type solid)
			)
			(layer "F.SilkS")
		)
		(fp_rect
			(start -1.25 -0.65)
			(end 1.25 0.65)
			(stroke
				(width 0.05)
				(type solid)
			)
			(fill no)
			(layer "F.CrtYd")
		)
		(fp_rect
			(start -0.8 -0.45)
			(end 0.8 0.45)
			(stroke
				(width 0.15)
				(type solid)
			)
			(fill no)
			(layer "F.Fab")
		)
		(pad "1" smd roundrect
			(at -0.7 0 270)
			(size 0.8 1.1)
			(layers "F.Cu" "F.Mask" "F.Paste")
			(roundrect_rratio 0.2)
			(net 28 "GND")
			(pintype "passive")
		)
		(pad "2" smd roundrect
			(at 0.7 0 270)
			(size 0.8 1.1)
			(layers "F.Cu" "F.Mask" "F.Paste")
			(roundrect_rratio 0.2)
			(net 255 "/Power/+3V3_OUT")
			(pintype "passive")
		)
	)
	(footprint "antmicro-footprints:FB_0805_2012Metric"
		(layer "F.Cu")
		(at 104.7 113.9 180)
		(descr "FERRITE BEAD 0805")
		(tags "FERRITE BEAD 0805")
		(property "Reference" "FB2"
			(at -1.1 -1 0)
			(layer "F.SilkS")
			(effects
				(font
					(size 0.7 0.7)
					(thickness 0.15)
				)
				(justify right top)
			)
		)
		(property "Value" "FB_330Z_1.5A_Murata-BLM21PG_0805"
			(at 0.001 1.801 0)
			(layer "F.Fab")
			(hide yes)
			(effects
				(font
					(size 0.7 0.7)
					(thickness 0.15)
				)
				(justify right top)
			)
		)
		(property "Datasheet" "https://www.murata.com/products/productdata/8796738977822/ENFA0005.pdf?1653276712000"
			(at 0 0 0)
			(layer "F.Fab")
			(hide yes)
			(effects
				(font
					(size 1.27 1.27)
					(thickness 0.15)
				)
			)
		)
		(property "Description" "Ferrite Bead, 0805 [2012 Metric], 330 ohm, 1.5 A, BLM21P, 0.07 ohm, ± 25%, DC power line"
			(at 0 0 0)
			(layer "F.Fab")
			(hide yes)
			(effects
				(font
					(size 1.27 1.27)
					(thickness 0.15)
				)
			)
		)
		(property "Val" "330Z/1.5A"
			(at 0 0 180)
			(unlocked yes)
			(layer "F.Fab")
			(hide yes)
			(effects
				(font
					(size 1 1)
					(thickness 0.15)
				)
			)
		)
		(property "MPN" "BLM21PG331SN1D"
			(at 0 0 180)
			(unlocked yes)
			(layer "F.Fab")
			(hide yes)
			(effects
				(font
					(size 1 1)
					(thickness 0.15)
				)
			)
		)
		(property "Manufacturer" "Murata"
			(at 0 0 180)
			(unlocked yes)
			(layer "F.Fab")
			(hide yes)
			(effects
				(font
					(size 1 1)
					(thickness 0.15)
				)
			)
		)
		(property "Current" ""
			(at 0 0 180)
			(unlocked yes)
			(layer "F.Fab")
			(hide yes)
			(effects
				(font
					(size 1 1)
					(thickness 0.15)
				)
			)
		)
		(property "Author" "Antmicro"
			(at 0 0 180)
			(unlocked yes)
			(layer "F.Fab")
			(hide yes)
			(effects
				(font
					(size 1 1)
					(thickness 0.15)
				)
			)
		)
		(property "License" "Apache-2.0"
			(at 0 0 180)
			(unlocked yes)
			(layer "F.Fab")
			(hide yes)
			(effects
				(font
					(size 1 1)
					(thickness 0.15)
				)
			)
		)
		(sheetname "/X710-AT2 10GbE/")
		(sheetfile "x710-at2-10gbe.kicad_sch")
		(attr smd)
		(fp_line
			(start -0.299 -0.698)
			(end 0.299 -0.698)
			(stroke
				(width 0.15)
				(type solid)
			)
			(layer "F.SilkS")
		)
		(fp_line
			(start -0.319 0.698)
			(end 0.281 0.698)
			(stroke
				(width 0.15)
				(type solid)
			)
			(layer "F.SilkS")
		)
		(fp_rect
			(start 1.95 -0.9)
			(end -1.95 0.9)
			(stroke
				(width 0.05)
				(type default)
			)
			(fill no)
			(layer "F.CrtYd")
		)
		(fp_line
			(start 0.948 -0.676)
			(end 0.948 0.676)
			(stroke
				(width 0.15)
				(type solid)
			)
			(layer "F.Fab")
		)
		(fp_line
			(start -0.948 0.681)
			(end 0.948 0.681)
			(stroke
				(width 0.15)
				(type solid)
			)
			(layer "F.Fab")
		)
		(fp_line
			(start -0.948 -0.676)
			(end -0.948 0.676)
			(stroke
				(width 0.15)
				(type solid)
			)
			(layer "F.Fab")
		)
		(fp_line
			(start -0.948 -0.681)
			(end 0.948 -0.681)
			(stroke
				(width 0.15)
				(type solid)
			)
			(layer "F.Fab")
		)
		(pad "1" smd roundrect
			(at -1.1 0 180)
			(size 1.2 1.3)
			(layers "F.Cu" "F.Mask" "F.Paste")
			(roundrect_rratio 0.25)
			(net 7 "+3V3")
			(pintype "passive")
		)
		(pad "2" smd roundrect
			(at 1.1 0 180)
			(size 1.2 1.3)
			(layers "F.Cu" "F.Mask" "F.Paste")
			(roundrect_rratio 0.25)
			(net 74 "/X710-AT2 10GbE/3V3_OSC")
			(pintype "passive")
		)
	)
	(footprint "antmicro-footprints:MP_Terminal_M3_THT_7760"
		(layer "F.Cu")
		(at 52.06 139.7)
		(property "Reference" "J4"
			(at -1.68 -1.85 0)
			(unlocked yes)
			(layer "F.SilkS")
			(effects
				(font
					(size 0.7 0.7)
					(thickness 0.15)
				)
				(justify left bottom)
			)
		)
		(property "Value" "MP_Terminal_M3_THT_7760"
			(at -1.68 11.43 0)
			(unlocked yes)
			(layer "F.Fab")
			(hide yes)
			(effects
				(font
					(size 0.7 0.7)
					(thickness 0.15)
				)
				(justify left bottom)
			)
		)
		(property "Datasheet" "https://www.mouser.com/datasheet/2/215/7760-741244.pdf"
			(at 0 0 0)
			(unlocked yes)
			(layer "F.Fab")
			(hide yes)
			(effects
				(font
					(size 0.7 0.7)
					(thickness 0.15)
				)
				(justify left bottom)
			)
		)
		(property "Description" "PCB Terminal, 90° THT, Brass, Tin"
			(at 0 0 0)
			(unlocked yes)
			(layer "F.Fab")
			(hide yes)
			(effects
				(font
					(size 0.7 0.7)
					(thickness 0.15)
				)
				(justify left bottom)
			)
		)
		(property "MPN" "7760"
			(at 0 0 0)
			(unlocked yes)
			(layer "F.Fab")
			(hide yes)
			(effects
				(font
					(size 1 1)
					(thickness 0.15)
				)
			)
		)
		(property "Manufacturer" "Keystone Electronics"
			(at 0 0 0)
			(unlocked yes)
			(layer "F.Fab")
			(hide yes)
			(effects
				(font
					(size 1 1)
					(thickness 0.15)
				)
			)
		)
		(property "Author" "Antmicro"
			(at 0 0 0)
			(unlocked yes)
			(layer "F.Fab")
			(hide yes)
			(effects
				(font
					(size 1 1)
					(thickness 0.15)
				)
			)
		)
		(property "License" "Apache-2.0"
			(at 0 0 0)
			(unlocked yes)
			(layer "F.Fab")
			(hide yes)
			(effects
				(font
					(size 1 1)
					(thickness 0.15)
				)
			)
		)
		(sheetname "/2xRJ45/")
		(sheetfile "2xrj45.kicad_sch")
		(attr through_hole allow_soldermask_bridges)
		(fp_line
			(start -0.42 3.255)
			(end -0.42 1.745)
			(stroke
				(width 0.15)
				(type solid)
			)
			(layer "F.SilkS")
		)
		(fp_line
			(start -0.42 6.745)
			(end -0.42 10.08)
			(stroke
				(width 0.15)
				(type solid)
			)
			(layer "F.SilkS")
		)
		(fp_line
			(start -0.42 10.08)
			(end 7.91 10.08)
			(stroke
				(width 0.15)
				(type solid)
			)
			(layer "F.SilkS")
		)
		(fp_line
			(start 1.745 -1.4)
			(end 5.745 -1.4)
			(stroke
				(width 0.15)
				(type solid)
			)
			(layer "F.SilkS")
		)
		(fp_line
			(start 7.91 3.255)
			(end 7.91 1.745)
			(stroke
				(width 0.15)
				(type solid)
			)
			(layer "F.SilkS")
		)
		(fp_line
			(start 7.91 10.08)
			(end 7.91 6.745)
			(stroke
				(width 0.15)
				(type solid)
			)
			(layer "F.SilkS")
		)
		(fp_rect
			(start -1.68 -1.68)
			(end 9.16 10.33)
			(stroke
				(width 0.05)
				(type solid)
			)
			(fill no)
			(layer "F.CrtYd")
		)
		(fp_rect
			(start -0.42 -1.4)
			(end 7.91 10.08)
			(stroke
				(width 0.15)
				(type solid)
			)
			(fill no)
			(layer "F.Fab")
		)
		(pad "1" thru_hole circle
			(at 0 0 90)
			(size 2.85 2.85)
			(drill 1.9)
			(layers "*.Cu" "*.Mask")
			(remove_unused_layers no)
			(net 28 "GND")
			(pintype "passive")
		)
		(pad "1" thru_hole circle
			(at 0 5 90)
			(size 2.85 2.85)
			(drill 1.9)
			(layers "*.Cu" "*.Mask")
			(remove_unused_layers no)
			(net 28 "GND")
			(pintype "passive")
		)
		(pad "1" thru_hole circle
			(at 7.49 0 90)
			(size 2.85 2.85)
			(drill 1.9)
			(layers "*.Cu" "*.Mask")
			(remove_unused_layers no)
			(net 28 "GND")
			(pintype "passive")
		)
		(pad "1" thru_hole circle
			(at 7.49 5 90)
			(size 2.85 2.85)
			(drill 1.9)
			(layers "*.Cu" "*.Mask")
			(remove_unused_layers no)
			(net 28 "GND")
			(pintype "passive")
		)
	)
	(footprint "antmicro-footprints:L_Bourns-SRP2512A"
		(layer "F.Cu")
		(at 70.09 103.67)
		(property "Reference" "L11"
			(at -3.68 2.26 180)
			(layer "F.SilkS")
			(effects
				(font
					(size 0.7 0.7)
					(thickness 0.15)
				)
				(justify left bottom)
			)
		)
		(property "Value" "L_4u7_1.55A_Bourns-SRP2512A"
			(at 0 2.25 180)
			(layer "F.Fab")
			(hide yes)
			(effects
				(font
					(size 0.7 0.7)
					(thickness 0.15)
				)
				(justify left bottom)
			)
		)
		(property "Datasheet" "https://www.bourns.com/docs/Product-Datasheets/srp2512a.pdf"
			(at 0 0 0)
			(layer "F.Fab")
			(hide yes)
			(effects
				(font
					(size 1.27 1.27)
					(thickness 0.15)
				)
			)
		)
		(property "Description" "4.7 µH Shielded Drum Core, Wirewound Inductor 1.55 A 235mOhm Max 1008 (2520 Metric)"
			(at 0 0 0)
			(layer "F.Fab")
			(hide yes)
			(effects
				(font
					(size 1.27 1.27)
					(thickness 0.15)
				)
			)
		)
		(property "Val" "4u7/1.55A"
			(at 0 0 0)
			(unlocked yes)
			(layer "F.Fab")
			(hide yes)
			(effects
				(font
					(size 1 1)
					(thickness 0.15)
				)
			)
		)
		(property "Manufacturer" "Bourns"
			(at 0 0 0)
			(unlocked yes)
			(layer "F.Fab")
			(hide yes)
			(effects
				(font
					(size 1 1)
					(thickness 0.15)
				)
			)
		)
		(property "MPN" "SRP2512A-4R7M"
			(at 0 0 0)
			(unlocked yes)
			(layer "F.Fab")
			(hide yes)
			(effects
				(font
					(size 1 1)
					(thickness 0.15)
				)
			)
		)
		(property "ISat" "1.9 A"
			(at 0 0 0)
			(unlocked yes)
			(layer "F.Fab")
			(hide yes)
			(effects
				(font
					(size 1 1)
					(thickness 0.15)
				)
			)
		)
		(property "IMax" "1.55 A"
			(at 0 0 0)
			(unlocked yes)
			(layer "F.Fab")
			(hide yes)
			(effects
				(font
					(size 1 1)
					(thickness 0.15)
				)
			)
		)
		(property "Size" "2.5x2.0"
			(at 0 0 0)
			(unlocked yes)
			(layer "F.Fab")
			(hide yes)
			(effects
				(font
					(size 1 1)
					(thickness 0.15)
				)
			)
		)
		(property "Author" "Antmicro"
			(at 0 0 0)
			(unlocked yes)
			(layer "F.Fab")
			(hide yes)
			(effects
				(font
					(size 1 1)
					(thickness 0.15)
				)
			)
		)
		(property "License" "Apache-2.0"
			(at 0 0 0)
			(unlocked yes)
			(layer "F.Fab")
			(hide yes)
			(effects
				(font
					(size 1 1)
					(thickness 0.15)
				)
			)
		)
		(sheetname "/X710-AT2 power/")
		(sheetfile "x710-at2-power.kicad_sch")
		(attr smd)
		(fp_line
			(start -0.351 1)
			(end 0.349 1)
			(stroke
				(width 0.15)
				(type solid)
			)
			(layer "F.SilkS")
		)
		(fp_line
			(start -0.35 -1)
			(end 0.35 -1)
			(stroke
				(width 0.15)
				(type solid)
			)
			(layer "F.SilkS")
		)
		(fp_rect
			(start -1.65 -1.3)
			(end 1.65 1.3)
			(stroke
				(width 0.05)
				(type solid)
			)
			(fill no)
			(layer "F.CrtYd")
		)
		(pad "1" smd roundrect
			(at -1 0 90)
			(size 2 0.8)
			(layers "F.Cu" "F.Mask" "F.Paste")
			(roundrect_rratio 0.1)
			(net 302 "+1V0")
			(pintype "passive")
		)
		(pad "2" smd roundrect
			(at 1 0 90)
			(size 2 0.8)
			(layers "F.Cu" "F.Mask" "F.Paste")
			(roundrect_rratio 0.1)
			(net 24 "XFI_PVDD")
			(pintype "passive")
		)
	)
	(footprint "antmicro-footprints:R_0402_1005Metric"
		(layer "F.Cu")
		(at 97.4 106.15)
		(descr "Resistor SMD 0402")
		(tags "resistor SMD 0402")
		(property "Reference" "R100"
			(at -2.25 15.425 0)
			(layer "F.SilkS")
			(effects
				(font
					(size 0.7 0.7)
					(thickness 0.15)
				)
				(justify left bottom)
			)
		)
		(property "Value" "R_10k_0402"
			(at -1.011843 1.772046 0)
			(layer "F.Fab")
			(hide yes)
			(effects
				(font
					(size 0.7 0.7)
					(thickness 0.15)
				)
				(justify left bottom)
			)
		)
		(property "Datasheet" "https://www.bourns.com/docs/product-datasheets/cr.pdf"
			(at 0 0 0)
			(layer "F.Fab")
			(hide yes)
			(effects
				(font
					(size 1.27 1.27)
					(thickness 0.15)
				)
			)
		)
		(property "Description" "SMD Chip Resistor, 10 kohm, ± 1%, 62.5 mW, 0402 [1005 Metric], Thick Film, General Purpose"
			(at 0 0 0)
			(layer "F.Fab")
			(hide yes)
			(effects
				(font
					(size 1.27 1.27)
					(thickness 0.15)
				)
			)
		)
		(property "MPN" "CR0402-FX-1002GLF"
			(at 0 0 0)
			(unlocked yes)
			(layer "F.Fab")
			(hide yes)
			(effects
				(font
					(size 1 1)
					(thickness 0.15)
				)
			)
		)
		(property "Manufacturer" "Bourns"
			(at 0 0 0)
			(unlocked yes)
			(layer "F.Fab")
			(hide yes)
			(effects
				(font
					(size 1 1)
					(thickness 0.15)
				)
			)
		)
		(property "License" "Apache-2.0"
			(at 0 0 0)
			(unlocked yes)
			(layer "F.Fab")
			(hide yes)
			(effects
				(font
					(size 1 1)
					(thickness 0.15)
				)
			)
		)
		(property "Author" "Antmicro"
			(at 0 0 0)
			(unlocked yes)
			(layer "F.Fab")
			(hide yes)
			(effects
				(font
					(size 1 1)
					(thickness 0.15)
				)
			)
		)
		(property "Val" "10k"
			(at 0 0 0)
			(unlocked yes)
			(layer "F.Fab")
			(hide yes)
			(effects
				(font
					(size 1 1)
					(thickness 0.15)
				)
			)
		)
		(property "Tolerance" "1%"
			(at 0 0 0)
			(unlocked yes)
			(layer "F.Fab")
			(hide yes)
			(effects
				(font
					(size 1 1)
					(thickness 0.15)
				)
			)
		)
		(sheetname "/X710-AT2 Misc/")
		(sheetfile "x710-at2-mics.kicad_sch")
		(attr smd)
		(fp_rect
			(start -0.925 -0.47)
			(end 0.925 0.47)
			(stroke
				(width 0.05)
				(type default)
			)
			(fill no)
			(layer "F.CrtYd")
		)
		(fp_rect
			(start -0.5 -0.25)
			(end 0.5 0.25)
			(stroke
				(width 0.15)
				(type solid)
			)
			(fill no)
			(layer "F.Fab")
		)
		(pad "1" smd roundrect
			(at -0.48 0)
			(size 0.59 0.64)
			(layers "F.Cu" "F.Mask" "F.Paste")
			(roundrect_rratio 0.25)
			(net 290 "/X710-AT2 Misc/~{DEV_DIS}")
			(pintype "passive")
		)
		(pad "2" smd roundrect
			(at 0.48 0)
			(size 0.59 0.64)
			(layers "F.Cu" "F.Mask" "F.Paste")
			(roundrect_rratio 0.25)
			(net 7 "+3V3")
			(pintype "passive")
		)
	)
	(footprint "antmicro-footprints:C_0603_1608Metric_EIA"
		(layer "F.Cu")
		(at 53.25 111.6 -90)
		(descr "Capacitor SMD 0603, IPC-7351 Density Level A")
		(tags "Capacitor 0603")
		(property "Reference" "C31"
			(at 1.01 0.47 90)
			(layer "F.SilkS")
			(effects
				(font
					(size 0.7 0.7)
					(thickness 0.15)
				)
				(justify right top)
			)
		)
		(property "Value" "C_22u_16V_0603"
			(at -1.42757 1.770288 90)
			(layer "F.Fab")
			(hide yes)
			(effects
				(font
					(size 0.7 0.7)
					(thickness 0.15)
				)
				(justify right top)
			)
		)
		(property "Datasheet" "https://product.samsungsem.com/mlcc/CL10A226MO7JZN.do"
			(at 0 0 90)
			(layer "F.Fab")
			(hide yes)
			(effects
				(font
					(size 1.27 1.27)
					(thickness 0.15)
				)
			)
		)
		(property "Description" "SMD Multilayer Ceramic Capacitor"
			(at 0 0 90)
			(layer "F.Fab")
			(hide yes)
			(effects
				(font
					(size 1.27 1.27)
					(thickness 0.15)
				)
			)
		)
		(property "MPN" "CL10A226MO7JZNC"
			(at 0 0 270)
			(unlocked yes)
			(layer "F.Fab")
			(hide yes)
			(effects
				(font
					(size 1 1)
					(thickness 0.15)
				)
			)
		)
		(property "Manufacturer" "Samsung Electro-Mechanics"
			(at 0 0 270)
			(unlocked yes)
			(layer "F.Fab")
			(hide yes)
			(effects
				(font
					(size 1 1)
					(thickness 0.15)
				)
			)
		)
		(property "License" "Apache-2.0"
			(at 0 0 270)
			(unlocked yes)
			(layer "F.Fab")
			(hide yes)
			(effects
				(font
					(size 1 1)
					(thickness 0.15)
				)
			)
		)
		(property "Author" "Antmicro"
			(at 0 0 270)
			(unlocked yes)
			(layer "F.Fab")
			(hide yes)
			(effects
				(font
					(size 1 1)
					(thickness 0.15)
				)
			)
		)
		(property "Val" "22u"
			(at 0 0 270)
			(unlocked yes)
			(layer "F.Fab")
			(hide yes)
			(effects
				(font
					(size 1 1)
					(thickness 0.15)
				)
			)
		)
		(property "Voltage" "16V"
			(at 0 0 270)
			(unlocked yes)
			(layer "F.Fab")
			(hide yes)
			(effects
				(font
					(size 1 1)
					(thickness 0.15)
				)
			)
		)
		(property "Dielectric" ""
			(at 0 0 270)
			(unlocked yes)
			(layer "F.Fab")
			(hide yes)
			(effects
				(font
					(size 1 1)
					(thickness 0.15)
				)
			)
		)
		(property "Public" "False"
			(at 0 0 270)
			(unlocked yes)
			(layer "F.Fab")
			(hide yes)
			(effects
				(font
					(size 1 1)
					(thickness 0.15)
				)
			)
		)
		(sheetname "/Power/")
		(sheetfile "power.kicad_sch")
		(attr smd)
		(fp_line
			(start -0.15 0.55)
			(end 0.15 0.55)
			(stroke
				(width 0.15)
				(type solid)
			)
			(layer "F.SilkS")
		)
		(fp_line
			(start -0.15 -0.55)
			(end 0.15 -0.55)
			(stroke
				(width 0.15)
				(type solid)
			)
			(layer "F.SilkS")
		)
		(fp_rect
			(start -1.25 -0.65)
			(end 1.25 0.65)
			(stroke
				(width 0.05)
				(type solid)
			)
			(fill no)
			(layer "F.CrtYd")
		)
		(fp_rect
			(start -0.8 -0.45)
			(end 0.8 0.45)
			(stroke
				(width 0.15)
				(type solid)
			)
			(fill no)
			(layer "F.Fab")
		)
		(pad "1" smd roundrect
			(at -0.7 0 270)
			(size 0.8 1.1)
			(layers "F.Cu" "F.Mask" "F.Paste")
			(roundrect_rratio 0.2)
			(net 28 "GND")
			(pintype "passive")
		)
		(pad "2" smd roundrect
			(at 0.7 0 270)
			(size 0.8 1.1)
			(layers "F.Cu" "F.Mask" "F.Paste")
			(roundrect_rratio 0.2)
			(net 314 "VCC")
			(pintype "passive")
		)
	)
	(footprint "antmicro-footprints:C_0603_1608Metric_EIA"
		(layer "F.Cu")
		(at 77.2 87.7 180)
		(descr "Capacitor SMD 0603, IPC-7351 Density Level A")
		(tags "Capacitor 0603")
		(property "Reference" "C150"
			(at -1.4 8.33 0)
			(layer "F.SilkS")
			(effects
				(font
					(size 0.7 0.7)
					(thickness 0.15)
				)
				(justify right top)
			)
		)
		(property "Value" "C_22u_16V_0603"
			(at -1.42757 1.770288 0)
			(layer "F.Fab")
			(hide yes)
			(effects
				(font
					(size 0.7 0.7)
					(thickness 0.15)
				)
				(justify right top)
			)
		)
		(property "Datasheet" "https://product.samsungsem.com/mlcc/CL10A226MO7JZN.do"
			(at 0 0 0)
			(layer "F.Fab")
			(hide yes)
			(effects
				(font
					(size 1.27 1.27)
					(thickness 0.15)
				)
			)
		)
		(property "Description" "SMD Multilayer Ceramic Capacitor"
			(at 0 0 0)
			(layer "F.Fab")
			(hide yes)
			(effects
				(font
					(size 1.27 1.27)
					(thickness 0.15)
				)
			)
		)
		(property "MPN" "CL10A226MO7JZNC"
			(at 0 0 180)
			(unlocked yes)
			(layer "F.Fab")
			(hide yes)
			(effects
				(font
					(size 1 1)
					(thickness 0.15)
				)
			)
		)
		(property "Manufacturer" "Samsung Electro-Mechanics"
			(at 0 0 180)
			(unlocked yes)
			(layer "F.Fab")
			(hide yes)
			(effects
				(font
					(size 1 1)
					(thickness 0.15)
				)
			)
		)
		(property "License" "Apache-2.0"
			(at 0 0 180)
			(unlocked yes)
			(layer "F.Fab")
			(hide yes)
			(effects
				(font
					(size 1 1)
					(thickness 0.15)
				)
			)
		)
		(property "Author" "Antmicro"
			(at 0 0 180)
			(unlocked yes)
			(layer "F.Fab")
			(hide yes)
			(effects
				(font
					(size 1 1)
					(thickness 0.15)
				)
			)
		)
		(property "Val" "22u"
			(at 0 0 180)
			(unlocked yes)
			(layer "F.Fab")
			(hide yes)
			(effects
				(font
					(size 1 1)
					(thickness 0.15)
				)
			)
		)
		(property "Voltage" "16V"
			(at 0 0 180)
			(unlocked yes)
			(layer "F.Fab")
			(hide yes)
			(effects
				(font
					(size 1 1)
					(thickness 0.15)
				)
			)
		)
		(property "Dielectric" ""
			(at 0 0 180)
			(unlocked yes)
			(layer "F.Fab")
			(hide yes)
			(effects
				(font
					(size 1 1)
					(thickness 0.15)
				)
			)
		)
		(sheetname "/X710-AT2 power/")
		(sheetfile "x710-at2-power.kicad_sch")
		(attr smd)
		(fp_line
			(start -0.15 0.55)
			(end 0.15 0.55)
			(stroke
				(width 0.15)
				(type solid)
			)
			(layer "F.SilkS")
		)
		(fp_line
			(start -0.15 -0.55)
			(end 0.15 -0.55)
			(stroke
				(width 0.15)
				(type solid)
			)
			(layer "F.SilkS")
		)
		(fp_rect
			(start -1.25 -0.65)
			(end 1.25 0.65)
			(stroke
				(width 0.05)
				(type solid)
			)
			(fill no)
			(layer "F.CrtYd")
		)
		(fp_rect
			(start -0.8 -0.45)
			(end 0.8 0.45)
			(stroke
				(width 0.15)
				(type solid)
			)
			(fill no)
			(layer "F.Fab")
		)
		(pad "1" smd roundrect
			(at -0.7 0 180)
			(size 0.8 1.1)
			(layers "F.Cu" "F.Mask" "F.Paste")
			(roundrect_rratio 0.2)
			(net 28 "GND")
			(pintype "passive")
		)
		(pad "2" smd roundrect
			(at 0.7 0 180)
			(size 0.8 1.1)
			(layers "F.Cu" "F.Mask" "F.Paste")
			(roundrect_rratio 0.2)
			(net 7 "+3V3")
			(pintype "passive")
		)
	)
	(footprint "antmicro-footprints:C_0603_1608Metric"
		(layer "F.Cu")
		(at 100.45 100.65)
		(descr "Capacitor SMD 0603")
		(tags "capacitor 0603")
		(property "Reference" "C158"
			(at 4.25 0.5 0)
			(layer "F.SilkS")
			(effects
				(font
					(size 0.7 0.7)
					(thickness 0.15)
				)
				(justify left bottom)
			)
		)
		(property "Value" "C_10u_10V_X7R_0603"
			(at -1.42757 1.770288 0)
			(layer "F.Fab")
			(hide yes)
			(effects
				(font
					(size 0.7 0.7)
					(thickness 0.15)
				)
				(justify left bottom)
			)
		)
		(property "Datasheet" "https://www.murata.com/products/productdetail?partno=GRM188Z71A106KA73%23"
			(at 0 0 0)
			(layer "F.Fab")
			(hide yes)
			(effects
				(font
					(size 1.27 1.27)
					(thickness 0.15)
				)
			)
		)
		(property "Description" "SMD Multilayer Ceramic Capacitor,  10µF, 10V, 0603, ±10%, X7R"
			(at 0 0 0)
			(layer "F.Fab")
			(hide yes)
			(effects
				(font
					(size 1.27 1.27)
					(thickness 0.15)
				)
			)
		)
		(property "MPN" "GRM188Z71A106KA73D"
			(at 0 0 0)
			(unlocked yes)
			(layer "F.Fab")
			(hide yes)
			(effects
				(font
					(size 1 1)
					(thickness 0.15)
				)
			)
		)
		(property "Val" "10u"
			(at 0 0 0)
			(unlocked yes)
			(layer "F.Fab")
			(hide yes)
			(effects
				(font
					(size 1 1)
					(thickness 0.15)
				)
			)
		)
		(property "Voltage" "10V"
			(at 0 0 0)
			(unlocked yes)
			(layer "F.Fab")
			(hide yes)
			(effects
				(font
					(size 1 1)
					(thickness 0.15)
				)
			)
		)
		(property "Dielectric" "X7R"
			(at 0 0 0)
			(unlocked yes)
			(layer "F.Fab")
			(hide yes)
			(effects
				(font
					(size 1 1)
					(thickness 0.15)
				)
			)
		)
		(property "Manufacturer" "Murata"
			(at 0 0 0)
			(unlocked yes)
			(layer "F.Fab")
			(hide yes)
			(effects
				(font
					(size 1 1)
					(thickness 0.15)
				)
			)
		)
		(property "License" "Apache-2.0"
			(at 0 0 0)
			(unlocked yes)
			(layer "F.Fab")
			(hide yes)
			(effects
				(font
					(size 1 1)
					(thickness 0.15)
				)
			)
		)
		(property "Author" "Antmicro"
			(at 0 0 0)
			(unlocked yes)
			(layer "F.Fab")
			(hide yes)
			(effects
				(font
					(size 1 1)
					(thickness 0.15)
				)
			)
		)
		(sheetname "/X710-AT2 power/")
		(sheetfile "x710-at2-power.kicad_sch")
		(attr smd)
		(fp_line
			(start -0.15 -0.4)
			(end 0.15 -0.4)
			(stroke
				(width 0.15)
				(type solid)
			)
			(layer "F.SilkS")
		)
		(fp_line
			(start -0.15 0.4)
			(end 0.15 0.4)
			(stroke
				(width 0.15)
				(type solid)
			)
			(layer "F.SilkS")
		)
		(fp_rect
			(start -1.25 -0.65)
			(end 1.25 0.65)
			(stroke
				(width 0.05)
				(type solid)
			)
			(fill no)
			(layer "F.CrtYd")
		)
		(fp_rect
			(start -0.8 -0.4)
			(end 0.8 0.4)
			(stroke
				(width 0.15)
				(type solid)
			)
			(fill no)
			(layer "F.Fab")
		)
		(pad "1" smd roundrect
			(at -0.7 0)
			(size 0.8 1)
			(layers "F.Cu" "F.Mask" "F.Paste")
			(roundrect_rratio 0.2)
			(net 28 "GND")
			(pintype "passive")
		)
		(pad "2" smd roundrect
			(at 0.7 0)
			(size 0.8 1)
			(layers "F.Cu" "F.Mask" "F.Paste")
			(roundrect_rratio 0.2)
			(net 1 "VCCA")
			(pintype "passive")
		)
	)
	(footprint "antmicro-footprints:C_0402_1005Metric"
		(layer "F.Cu")
		(at 103.7 112.5 180)
		(descr "Capacitor SMD 0402")
		(tags "capacitor SMD 0402")
		(property "Reference" "C71"
			(at 0.85 0.35 0)
			(layer "F.SilkS")
			(effects
				(font
					(size 0.7 0.7)
					(thickness 0.15)
				)
				(justify right top)
			)
		)
		(property "Value" "C_100n_0402"
			(at -1.022927 2.155213 0)
			(layer "F.Fab")
			(hide yes)
			(effects
				(font
					(size 0.7 0.7)
					(thickness 0.15)
				)
				(justify right top)
			)
		)
		(property "Datasheet" "https://www.murata.com/products/productdetail?partno=GRM155R61H104KE14%23"
			(at 0 0 0)
			(layer "F.Fab")
			(hide yes)
			(effects
				(font
					(size 1.27 1.27)
					(thickness 0.15)
				)
			)
		)
		(property "Description" "SMD Multilayer Ceramic Capacitor, 0.1 µF, 50 V, 0402 [1005 Metric], ± 10%, X5R, GRM Series"
			(at 0 0 0)
			(layer "F.Fab")
			(hide yes)
			(effects
				(font
					(size 1.27 1.27)
					(thickness 0.15)
				)
			)
		)
		(property "MPN" "GRM155R61H104KE14D"
			(at 0 0 180)
			(unlocked yes)
			(layer "F.Fab")
			(hide yes)
			(effects
				(font
					(size 1 1)
					(thickness 0.15)
				)
			)
		)
		(property "Val" "100n"
			(at 0 0 180)
			(unlocked yes)
			(layer "F.Fab")
			(hide yes)
			(effects
				(font
					(size 1 1)
					(thickness 0.15)
				)
			)
		)
		(property "Voltage" "50V"
			(at 0 0 180)
			(unlocked yes)
			(layer "F.Fab")
			(hide yes)
			(effects
				(font
					(size 1 1)
					(thickness 0.15)
				)
			)
		)
		(property "Dielectric" "X5R"
			(at 0 0 180)
			(unlocked yes)
			(layer "F.Fab")
			(hide yes)
			(effects
				(font
					(size 1 1)
					(thickness 0.15)
				)
			)
		)
		(property "Manufacturer" "Murata"
			(at 0 0 180)
			(unlocked yes)
			(layer "F.Fab")
			(hide yes)
			(effects
				(font
					(size 1 1)
					(thickness 0.15)
				)
			)
		)
		(property "License" "Apache-2.0"
			(at 0 0 180)
			(unlocked yes)
			(layer "F.Fab")
			(hide yes)
			(effects
				(font
					(size 1 1)
					(thickness 0.15)
				)
			)
		)
		(property "Author" "Antmicro"
			(at 0 0 180)
			(unlocked yes)
			(layer "F.Fab")
			(hide yes)
			(effects
				(font
					(size 1 1)
					(thickness 0.15)
				)
			)
		)
		(sheetname "/X710-AT2 10GbE/")
		(sheetfile "x710-at2-10gbe.kicad_sch")
		(attr smd)
		(fp_rect
			(start -0.925 -0.47)
			(end 0.925 0.47)
			(stroke
				(width 0.05)
				(type default)
			)
			(fill no)
			(layer "F.CrtYd")
		)
		(fp_line
			(start 0.504 0.248)
			(end -0.494 0.248)
			(stroke
				(width 0.15)
				(type solid)
			)
			(layer "F.Fab")
		)
		(fp_line
			(start 0.504 -0.25)
			(end 0.504 0.248)
			(stroke
				(width 0.15)
				(type solid)
			)
			(layer "F.Fab")
		)
		(fp_line
			(start -0.494 0.248)
			(end -0.494 -0.25)
			(stroke
				(width 0.15)
				(type solid)
			)
			(layer "F.Fab")
		)
		(fp_line
			(start -0.494 -0.25)
			(end 0.504 -0.25)
			(stroke
				(width 0.15)
				(type solid)
			)
			(layer "F.Fab")
		)
		(pad "1" smd roundrect
			(at -0.48 0 180)
			(size 0.59 0.64)
			(layers "F.Cu" "F.Mask" "F.Paste")
			(roundrect_rratio 0.25)
			(net 28 "GND")
			(pintype "passive")
		)
		(pad "2" smd roundrect
			(at 0.48 0 180)
			(size 0.59 0.64)
			(layers "F.Cu" "F.Mask" "F.Paste")
			(roundrect_rratio 0.25)
			(net 74 "/X710-AT2 10GbE/3V3_OSC")
			(pintype "passive")
		)
	)
	(footprint "antmicro-footprints:LED_0603_1608Metric_G"
		(layer "F.Cu")
		(at 54.350001 120.4 180)
		(descr "LED SMD 0603 Green")
		(tags "LED SMD 0603 Green")
		(property "Reference" "D19"
			(at -1.099999 -0.75 0)
			(layer "F.SilkS")
			(effects
				(font
					(size 0.7 0.7)
					(thickness 0.15)
				)
				(justify right top)
			)
		)
		(property "Value" "LED_G_0603_LG_L29K-G2J1-24-Z"
			(at -0.001 1.599 0)
			(layer "F.Fab")
			(hide yes)
			(effects
				(font
					(size 0.7 0.7)
					(thickness 0.15)
				)
				(justify right top)
			)
		)
		(property "Datasheet" "https://look.ams-osram.com/m/19ee86b3ae0ee95b/original/LG-L29K.pdf"
			(at 0 0 0)
			(layer "F.Fab")
			(hide yes)
			(effects
				(font
					(size 1.27 1.27)
					(thickness 0.15)
				)
			)
		)
		(property "Description" "LED, Green, SMD, 0603, 20 mA, 1.7 V, 570 nm"
			(at 0 0 0)
			(layer "F.Fab")
			(hide yes)
			(effects
				(font
					(size 1.27 1.27)
					(thickness 0.15)
				)
			)
		)
		(property "MPN" "LG L29K-G2J1-24-Z"
			(at 0 0 180)
			(unlocked yes)
			(layer "F.Fab")
			(hide yes)
			(effects
				(font
					(size 1 1)
					(thickness 0.15)
				)
			)
		)
		(property "Manufacturer" "OSRAM"
			(at 0 0 180)
			(unlocked yes)
			(layer "F.Fab")
			(hide yes)
			(effects
				(font
					(size 1 1)
					(thickness 0.15)
				)
			)
		)
		(property "Color" "Green"
			(at 0 0 180)
			(unlocked yes)
			(layer "F.Fab")
			(hide yes)
			(effects
				(font
					(size 1 1)
					(thickness 0.15)
				)
			)
		)
		(property "Author" "Antmicro"
			(at 0 0 180)
			(unlocked yes)
			(layer "F.Fab")
			(hide yes)
			(effects
				(font
					(size 1 1)
					(thickness 0.15)
				)
			)
		)
		(property "License" "Apache-2.0"
			(at 0 0 180)
			(unlocked yes)
			(layer "F.Fab")
			(hide yes)
			(effects
				(font
					(size 1 1)
					(thickness 0.15)
				)
			)
		)
		(sheetname "/Power/")
		(sheetfile "power.kicad_sch")
		(attr smd)
		(fp_line
			(start 0.22 0.35)
			(end -0.22 0.35)
			(stroke
				(width 0.15)
				(type solid)
			)
			(layer "F.SilkS")
		)
		(fp_line
			(start 0.22 -0.35)
			(end -0.22 -0.35)
			(stroke
				(width 0.15)
				(type solid)
			)
			(layer "F.SilkS")
		)
		(fp_line
			(start 0.105328 0.201008)
			(end 0.105328 -0.198992)
			(stroke
				(width 0.1)
				(type solid)
			)
			(layer "F.SilkS")
		)
		(fp_line
			(start 0.105328 0.201008)
			(end -0.094672 0.001008)
			(stroke
				(width 0.1)
				(type solid)
			)
			(layer "F.SilkS")
		)
		(fp_line
			(start 0.105328 0.001008)
			(end 0.24 0.001)
			(stroke
				(width 0.1)
				(type solid)
			)
			(layer "F.SilkS")
		)
		(fp_line
			(start -0.094672 0.201008)
			(end -0.094672 -0.198992)
			(stroke
				(width 0.1)
				(type solid)
			)
			(layer "F.SilkS")
		)
		(fp_line
			(start -0.094672 0.001008)
			(end 0.105328 -0.198992)
			(stroke
				(width 0.1)
				(type solid)
			)
			(layer "F.SilkS")
		)
		(fp_line
			(start -0.094672 0.001008)
			(end -0.24 0.001008)
			(stroke
				(width 0.1)
				(type solid)
			)
			(layer "F.SilkS")
		)
		(fp_line
			(start -1.18 -0.319)
			(end -1.18 0.321)
			(stroke
				(width 0.15)
				(type solid)
			)
			(layer "F.SilkS")
		)
		(fp_rect
			(start 1.25 0.65)
			(end -1.25 -0.65)
			(stroke
				(width 0.05)
				(type solid)
			)
			(fill no)
			(layer "F.CrtYd")
		)
		(fp_line
			(start 0.599 0)
			(end 0.201 0)
			(stroke
				(width 0.15)
				(type solid)
			)
			(layer "F.Fab")
		)
		(fp_line
			(start 0.201 0.2)
			(end 0.201 0)
			(stroke
				(width 0.15)
				(type solid)
			)
			(layer "F.Fab")
		)
		(fp_line
			(start 0.201 0)
			(end 0.201 -0.202)
			(stroke
				(width 0.15)
				(type solid)
			)
			(layer "F.Fab")
		)
		(fp_line
			(start 0.201 -0.202)
			(end -0.101 0)
			(stroke
				(width 0.15)
				(type solid)
			)
			(layer "F.Fab")
		)
		(fp_line
			(start -0.101 0)
			(end 0.201 0.2)
			(stroke
				(width 0.15)
				(type solid)
			)
			(layer "F.Fab")
		)
		(fp_line
			(start -0.199 0.2)
			(end -0.199 0.1)
			(stroke
				(width 0.15)
				(type solid)
			)
			(layer "F.Fab")
		)
		(fp_line
			(start -0.199 0)
			(end -0.597 0)
			(stroke
				(width 0.15)
				(type solid)
			)
			(layer "F.Fab")
		)
		(fp_line
			(start -0.199 -0.202)
			(end -0.199 0.1)
			(stroke
				(width 0.15)
				(type solid)
			)
			(layer "F.Fab")
		)
		(fp_rect
			(start 0.848 0.4)
			(end -0.85 -0.402)
			(stroke
				(width 0.15)
				(type solid)
			)
			(fill no)
			(layer "F.Fab")
		)
		(fp_text user "License: Apache-2.0"
			(at -1.4224 3.599 180)
			(layer "F.Fab")
			(effects
				(font
					(size 0.7 0.7)
					(thickness 0.15)
				)
				(justify left bottom)
			)
		)
		(fp_text user "Author: Antmicro"
			(at -1.4224 4.799 180)
			(layer "F.Fab")
			(effects
				(font
					(size 0.7 0.7)
					(thickness 0.15)
				)
				(justify left bottom)
			)
		)
		(fp_text user "${REFERENCE}"
			(at -1.4224 5.999 180)
			(layer "F.Fab")
			(effects
				(font
					(size 0.7 0.7)
					(thickness 0.15)
				)
				(justify left bottom)
			)
		)
		(pad "1" smd roundrect
			(at -0.7 0)
			(size 0.8 1)
			(layers "F.Cu" "F.Mask" "F.Paste")
			(roundrect_rratio 0.2)
			(net 413 "Net-(D19-C)")
			(pinfunction "C")
			(pintype "passive")
		)
		(pad "2" smd roundrect
			(at 0.7 0)
			(size 0.8 1)
			(layers "F.Cu" "F.Mask" "F.Paste")
			(roundrect_rratio 0.2)
			(net 255 "/Power/+3V3_OUT")
			(pinfunction "A")
			(pintype "passive")
		)
	)
	(footprint "antmicro-footprints:R_0603_1608Metric"
		(layer "F.Cu")
		(at 63.2 99.500001)
		(descr "Resistor SMD 0603")
		(tags "resistor SMD 0603")
		(property "Reference" "R14"
			(at -0.04 -0.660001 0)
			(layer "F.SilkS")
			(effects
				(font
					(size 0.7 0.7)
					(thickness 0.15)
				)
				(justify left bottom)
			)
		)
		(property "Value" "R_0R_22.4A_0603"
			(at 0 1.6 0)
			(layer "F.Fab")
			(hide yes)
			(effects
				(font
					(size 0.7 0.7)
					(thickness 0.15)
				)
				(justify left bottom)
			)
		)
		(property "Datasheet" "https://fscdn.rohm.com/en/products/databook/datasheet/passive/resistor/chip_resistor/pmr-jpw-e.pdf"
			(at 0 0 0)
			(layer "F.Fab")
			(hide yes)
			(effects
				(font
					(size 1.27 1.27)
					(thickness 0.15)
				)
			)
		)
		(property "Description" "SMD Chip Resistor"
			(at 0 0 0)
			(layer "F.Fab")
			(hide yes)
			(effects
				(font
					(size 1.27 1.27)
					(thickness 0.15)
				)
			)
		)
		(property "MPN" "PMR03EZPJ000"
			(at 0 0 0)
			(unlocked yes)
			(layer "F.Fab")
			(hide yes)
			(effects
				(font
					(size 1 1)
					(thickness 0.15)
				)
			)
		)
		(property "Manufacturer" "ROHM Semiconductor"
			(at 0 0 0)
			(unlocked yes)
			(layer "F.Fab")
			(hide yes)
			(effects
				(font
					(size 1 1)
					(thickness 0.15)
				)
			)
		)
		(property "Val" "0R"
			(at 0 0 0)
			(unlocked yes)
			(layer "F.Fab")
			(hide yes)
			(effects
				(font
					(size 1 1)
					(thickness 0.15)
				)
			)
		)
		(property "Max. Curr." "22.4A"
			(at 0 0 0)
			(unlocked yes)
			(layer "F.Fab")
			(hide yes)
			(effects
				(font
					(size 1 1)
					(thickness 0.15)
				)
			)
		)
		(property "Author" "Antmicro"
			(at 0 0 0)
			(unlocked yes)
			(layer "F.Fab")
			(hide yes)
			(effects
				(font
					(size 1 1)
					(thickness 0.15)
				)
			)
		)
		(property "License" "Apache-2.0"
			(at 0 0 0)
			(unlocked yes)
			(layer "F.Fab")
			(hide yes)
			(effects
				(font
					(size 1 1)
					(thickness 0.15)
				)
			)
		)
		(property "Tolerance" "template_tolerance"
			(at 0 0 0)
			(unlocked yes)
			(layer "F.Fab")
			(hide yes)
			(effects
				(font
					(size 1 1)
					(thickness 0.15)
				)
			)
		)
		(sheetname "/Power/")
		(sheetfile "power.kicad_sch")
		(attr smd)
		(fp_line
			(start -0.15 -0.4)
			(end 0.15 -0.4)
			(stroke
				(width 0.15)
				(type solid)
			)
			(layer "F.SilkS")
		)
		(fp_line
			(start -0.15 0.4)
			(end 0.15 0.4)
			(stroke
				(width 0.15)
				(type solid)
			)
			(layer "F.SilkS")
		)
		(fp_rect
			(start -1.25 -0.65)
			(end 1.25 0.65)
			(stroke
				(width 0.05)
				(type solid)
			)
			(fill no)
			(layer "F.CrtYd")
		)
		(fp_rect
			(start -0.8 -0.4)
			(end 0.8 0.4)
			(stroke
				(width 0.15)
				(type solid)
			)
			(fill no)
			(layer "F.Fab")
		)
		(pad "1" smd roundrect
			(at -0.7 0)
			(size 0.8 1)
			(layers "F.Cu" "F.Mask" "F.Paste")
			(roundrect_rratio 0.2)
			(net 310 "/Power/+1V88_OUT")
			(pintype "passive")
		)
		(pad "2" smd roundrect
			(at 0.7 0)
			(size 0.8 1)
			(layers "F.Cu" "F.Mask" "F.Paste")
			(roundrect_rratio 0.2)
			(net 18 "+1V88")
			(pintype "passive")
		)
	)
	(footprint "antmicro-footprints:C_0402_1005Metric"
		(layer "F.Cu")
		(at 55.1 108.249996 90)
		(descr "Capacitor SMD 0402")
		(tags "capacitor SMD 0402")
		(property "Reference" "C29"
			(at -1.100004 -2.34 90)
			(layer "F.SilkS")
			(effects
				(font
					(size 0.7 0.7)
					(thickness 0.15)
				)
				(justify left bottom)
			)
		)
		(property "Value" "C_33p_0402"
			(at -1.022927 2.155213 90)
			(layer "F.Fab")
			(hide yes)
			(effects
				(font
					(size 0.7 0.7)
					(thickness 0.15)
				)
				(justify left bottom)
			)
		)
		(property "Datasheet" "https://spicat.kyocera-avx.com/product/mlcc/chartview/04025A330FAT2A/"
			(at 0 0 90)
			(layer "F.Fab")
			(hide yes)
			(effects
				(font
					(size 1.27 1.27)
					(thickness 0.15)
				)
			)
		)
		(property "Description" "SMD Multilayer Ceramic Capacitor, 33 pF, 50 V, 0402 [1005 Metric], ± 5%, C0G / NP0, MC"
			(at 0 0 90)
			(layer "F.Fab")
			(hide yes)
			(effects
				(font
					(size 1.27 1.27)
					(thickness 0.15)
				)
			)
		)
		(property "MPN" "04025A330FAT2A"
			(at 0 0 90)
			(unlocked yes)
			(layer "F.Fab")
			(hide yes)
			(effects
				(font
					(size 1 1)
					(thickness 0.15)
				)
			)
		)
		(property "Manufacturer" "KYOCERA AVX"
			(at 0 0 90)
			(unlocked yes)
			(layer "F.Fab")
			(hide yes)
			(effects
				(font
					(size 1 1)
					(thickness 0.15)
				)
			)
		)
		(property "License" "Apache-2.0"
			(at 0 0 90)
			(unlocked yes)
			(layer "F.Fab")
			(hide yes)
			(effects
				(font
					(size 1 1)
					(thickness 0.15)
				)
			)
		)
		(property "Author" "Antmicro"
			(at 0 0 90)
			(unlocked yes)
			(layer "F.Fab")
			(hide yes)
			(effects
				(font
					(size 1 1)
					(thickness 0.15)
				)
			)
		)
		(property "Val" "33p"
			(at 0 0 90)
			(unlocked yes)
			(layer "F.Fab")
			(hide yes)
			(effects
				(font
					(size 1 1)
					(thickness 0.15)
				)
			)
		)
		(property "Voltage" ""
			(at 0 0 90)
			(unlocked yes)
			(layer "F.Fab")
			(hide yes)
			(effects
				(font
					(size 1 1)
					(thickness 0.15)
				)
			)
		)
		(property "Dielectric" ""
			(at 0 0 90)
			(unlocked yes)
			(layer "F.Fab")
			(hide yes)
			(effects
				(font
					(size 1 1)
					(thickness 0.15)
				)
			)
		)
		(sheetname "/Power/")
		(sheetfile "power.kicad_sch")
		(attr smd exclude_from_pos_files exclude_from_bom dnp)
		(fp_rect
			(start -0.925 -0.47)
			(end 0.925 0.47)
			(stroke
				(width 0.05)
				(type default)
			)
			(fill no)
			(layer "F.CrtYd")
		)
		(fp_line
			(start 0.504 -0.25)
			(end 0.504 0.248)
			(stroke
				(width 0.15)
				(type solid)
			)
			(layer "F.Fab")
		)
		(fp_line
			(start -0.494 -0.25)
			(end 0.504 -0.25)
			(stroke
				(width 0.15)
				(type solid)
			)
			(layer "F.Fab")
		)
		(fp_line
			(start 0.504 0.248)
			(end -0.494 0.248)
			(stroke
				(width 0.15)
				(type solid)
			)
			(layer "F.Fab")
		)
		(fp_line
			(start -0.494 0.248)
			(end -0.494 -0.25)
			(stroke
				(width 0.15)
				(type solid)
			)
			(layer "F.Fab")
		)
		(pad "1" smd roundrect
			(at -0.48 0 90)
			(size 0.59 0.64)
			(layers "F.Cu" "F.Mask" "F.Paste")
			(roundrect_rratio 0.25)
			(net 332 "/Power/1V0_FB")
			(pintype "passive")
		)
		(pad "2" smd roundrect
			(at 0.48 0 90)
			(size 0.59 0.64)
			(layers "F.Cu" "F.Mask" "F.Paste")
			(roundrect_rratio 0.25)
			(net 312 "/Power/+1V0_OUT")
			(pintype "passive")
		)
	)
	(footprint "antmicro-footprints:R_0402_1005Metric"
		(layer "F.Cu")
		(at 53.1 108.25 -90)
		(descr "Resistor SMD 0402")
		(tags "resistor SMD 0402")
		(property "Reference" "R24"
			(at -1.09 2.88 90)
			(layer "F.SilkS")
			(effects
				(font
					(size 0.7 0.7)
					(thickness 0.15)
				)
				(justify right top)
			)
		)
		(property "Value" "R_0R_0402"
			(at -1.011843 1.772046 90)
			(layer "F.Fab")
			(hide yes)
			(effects
				(font
					(size 0.7 0.7)
					(thickness 0.15)
				)
				(justify right top)
			)
		)
		(property "Datasheet" "https://industrial.panasonic.com/cdbs/www-data/pdf/RDA0000/AOA0000C301.pdf"
			(at 0 0 90)
			(layer "F.Fab")
			(hide yes)
			(effects
				(font
					(size 1.27 1.27)
					(thickness 0.15)
				)
			)
		)
		(property "Description" "SMD Chip Resistor, Jumper, 0 ohm, 100 mW, 0402 [1005 Metric], Thick Film, General Purpose"
			(at 0 0 90)
			(layer "F.Fab")
			(hide yes)
			(effects
				(font
					(size 1.27 1.27)
					(thickness 0.15)
				)
			)
		)
		(property "MPN" "ERJ2GE0R00X"
			(at 0 0 270)
			(unlocked yes)
			(layer "F.Fab")
			(hide yes)
			(effects
				(font
					(size 1 1)
					(thickness 0.15)
				)
			)
		)
		(property "Manufacturer" "Panasonic"
			(at 0 0 270)
			(unlocked yes)
			(layer "F.Fab")
			(hide yes)
			(effects
				(font
					(size 1 1)
					(thickness 0.15)
				)
			)
		)
		(property "License" "Apache-2.0"
			(at 0 0 270)
			(unlocked yes)
			(layer "F.Fab")
			(hide yes)
			(effects
				(font
					(size 1 1)
					(thickness 0.15)
				)
			)
		)
		(property "Author" "Antmicro"
			(at 0 0 270)
			(unlocked yes)
			(layer "F.Fab")
			(hide yes)
			(effects
				(font
					(size 1 1)
					(thickness 0.15)
				)
			)
		)
		(property "Val" "0R"
			(at 0 0 270)
			(unlocked yes)
			(layer "F.Fab")
			(hide yes)
			(effects
				(font
					(size 1 1)
					(thickness 0.15)
				)
			)
		)
		(property "Tolerance" "~"
			(at 0 0 270)
			(unlocked yes)
			(layer "F.Fab")
			(hide yes)
			(effects
				(font
					(size 1 1)
					(thickness 0.15)
				)
			)
		)
		(property "Current" "1A"
			(at 0 0 270)
			(unlocked yes)
			(layer "F.Fab")
			(hide yes)
			(effects
				(font
					(size 1 1)
					(thickness 0.15)
				)
			)
		)
		(sheetname "/Power/")
		(sheetfile "power.kicad_sch")
		(attr smd)
		(fp_rect
			(start -0.925 -0.47)
			(end 0.925 0.47)
			(stroke
				(width 0.05)
				(type default)
			)
			(fill no)
			(layer "F.CrtYd")
		)
		(fp_rect
			(start -0.5 -0.25)
			(end 0.5 0.25)
			(stroke
				(width 0.15)
				(type solid)
			)
			(fill no)
			(layer "F.Fab")
		)
		(pad "1" smd roundrect
			(at -0.48 0 270)
			(size 0.59 0.64)
			(layers "F.Cu" "F.Mask" "F.Paste")
			(roundrect_rratio 0.25)
			(net 369 "/Power/1V88_PG")
			(pintype "passive")
		)
		(pad "2" smd roundrect
			(at 0.48 0 270)
			(size 0.59 0.64)
			(layers "F.Cu" "F.Mask" "F.Paste")
			(roundrect_rratio 0.25)
			(net 377 "/Power/1V0_EN")
			(pintype "passive")
		)
	)
	(footprint "antmicro-footprints:LED_0603_1608Metric_G"
		(layer "F.Cu")
		(at 54.35 127.449999 180)
		(descr "LED SMD 0603 Green")
		(tags "LED SMD 0603 Green")
		(property "Reference" "D16"
			(at -1.1 -0.750001 0)
			(layer "F.SilkS")
			(effects
				(font
					(size 0.7 0.7)
					(thickness 0.15)
				)
				(justify right top)
			)
		)
		(property "Value" "LED_G_0603_LG_L29K-G2J1-24-Z"
			(at -0.001 1.599 0)
			(layer "F.Fab")
			(hide yes)
			(effects
				(font
					(size 0.7 0.7)
					(thickness 0.15)
				)
				(justify right top)
			)
		)
		(property "Datasheet" "https://look.ams-osram.com/m/19ee86b3ae0ee95b/original/LG-L29K.pdf"
			(at 0 0 0)
			(layer "F.Fab")
			(hide yes)
			(effects
				(font
					(size 1.27 1.27)
					(thickness 0.15)
				)
			)
		)
		(property "Description" "LED, Green, SMD, 0603, 20 mA, 1.7 V, 570 nm"
			(at 0 0 0)
			(layer "F.Fab")
			(hide yes)
			(effects
				(font
					(size 1.27 1.27)
					(thickness 0.15)
				)
			)
		)
		(property "MPN" "LG L29K-G2J1-24-Z"
			(at 0 0 180)
			(unlocked yes)
			(layer "F.Fab")
			(hide yes)
			(effects
				(font
					(size 1 1)
					(thickness 0.15)
				)
			)
		)
		(property "Manufacturer" "OSRAM"
			(at 0 0 180)
			(unlocked yes)
			(layer "F.Fab")
			(hide yes)
			(effects
				(font
					(size 1 1)
					(thickness 0.15)
				)
			)
		)
		(property "Color" "Green"
			(at 0 0 180)
			(unlocked yes)
			(layer "F.Fab")
			(hide yes)
			(effects
				(font
					(size 1 1)
					(thickness 0.15)
				)
			)
		)
		(property "Author" "Antmicro"
			(at 0 0 180)
			(unlocked yes)
			(layer "F.Fab")
			(hide yes)
			(effects
				(font
					(size 1 1)
					(thickness 0.15)
				)
			)
		)
		(property "License" "Apache-2.0"
			(at 0 0 180)
			(unlocked yes)
			(layer "F.Fab")
			(hide yes)
			(effects
				(font
					(size 1 1)
					(thickness 0.15)
				)
			)
		)
		(sheetname "/Power/")
		(sheetfile "power.kicad_sch")
		(attr smd)
		(fp_line
			(start 0.22 0.35)
			(end -0.22 0.35)
			(stroke
				(width 0.15)
				(type solid)
			)
			(layer "F.SilkS")
		)
		(fp_line
			(start 0.22 -0.35)
			(end -0.22 -0.35)
			(stroke
				(width 0.15)
				(type solid)
			)
			(layer "F.SilkS")
		)
		(fp_line
			(start 0.105328 0.201008)
			(end 0.105328 -0.198992)
			(stroke
				(width 0.1)
				(type solid)
			)
			(layer "F.SilkS")
		)
		(fp_line
			(start 0.105328 0.201008)
			(end -0.094672 0.001008)
			(stroke
				(width 0.1)
				(type solid)
			)
			(layer "F.SilkS")
		)
		(fp_line
			(start 0.105328 0.001008)
			(end 0.24 0.001)
			(stroke
				(width 0.1)
				(type solid)
			)
			(layer "F.SilkS")
		)
		(fp_line
			(start -0.094672 0.201008)
			(end -0.094672 -0.198992)
			(stroke
				(width 0.1)
				(type solid)
			)
			(layer "F.SilkS")
		)
		(fp_line
			(start -0.094672 0.001008)
			(end 0.105328 -0.198992)
			(stroke
				(width 0.1)
				(type solid)
			)
			(layer "F.SilkS")
		)
		(fp_line
			(start -0.094672 0.001008)
			(end -0.24 0.001008)
			(stroke
				(width 0.1)
				(type solid)
			)
			(layer "F.SilkS")
		)
		(fp_line
			(start -1.18 -0.319)
			(end -1.18 0.321)
			(stroke
				(width 0.15)
				(type solid)
			)
			(layer "F.SilkS")
		)
		(fp_rect
			(start 1.25 0.65)
			(end -1.25 -0.65)
			(stroke
				(width 0.05)
				(type solid)
			)
			(fill no)
			(layer "F.CrtYd")
		)
		(fp_line
			(start 0.599 0)
			(end 0.201 0)
			(stroke
				(width 0.15)
				(type solid)
			)
			(layer "F.Fab")
		)
		(fp_line
			(start 0.201 0.2)
			(end 0.201 0)
			(stroke
				(width 0.15)
				(type solid)
			)
			(layer "F.Fab")
		)
		(fp_line
			(start 0.201 0)
			(end 0.201 -0.202)
			(stroke
				(width 0.15)
				(type solid)
			)
			(layer "F.Fab")
		)
		(fp_line
			(start 0.201 -0.202)
			(end -0.101 0)
			(stroke
				(width 0.15)
				(type solid)
			)
			(layer "F.Fab")
		)
		(fp_line
			(start -0.101 0)
			(end 0.201 0.2)
			(stroke
				(width 0.15)
				(type solid)
			)
			(layer "F.Fab")
		)
		(fp_line
			(start -0.199 0.2)
			(end -0.199 0.1)
			(stroke
				(width 0.15)
				(type solid)
			)
			(layer "F.Fab")
		)
		(fp_line
			(start -0.199 0)
			(end -0.597 0)
			(stroke
				(width 0.15)
				(type solid)
			)
			(layer "F.Fab")
		)
		(fp_line
			(start -0.199 -0.202)
			(end -0.199 0.1)
			(stroke
				(width 0.15)
				(type solid)
			)
			(layer "F.Fab")
		)
		(fp_rect
			(start 0.848 0.4)
			(end -0.85 -0.402)
			(stroke
				(width 0.15)
				(type solid)
			)
			(fill no)
			(layer "F.Fab")
		)
		(fp_text user "License: Apache-2.0"
			(at -1.4224 3.599 180)
			(layer "F.Fab")
			(effects
				(font
					(size 0.7 0.7)
					(thickness 0.15)
				)
				(justify left bottom)
			)
		)
		(fp_text user "${REFERENCE}"
			(at -1.4224 5.999 180)
			(layer "F.Fab")
			(effects
				(font
					(size 0.7 0.7)
					(thickness 0.15)
				)
				(justify left bottom)
			)
		)
		(fp_text user "Author: Antmicro"
			(at -1.4224 4.799 180)
			(layer "F.Fab")
			(effects
				(font
					(size 0.7 0.7)
					(thickness 0.15)
				)
				(justify left bottom)
			)
		)
		(pad "1" smd roundrect
			(at -0.7 0)
			(size 0.8 1)
			(layers "F.Cu" "F.Mask" "F.Paste")
			(roundrect_rratio 0.2)
			(net 415 "Net-(D16-C)")
			(pinfunction "C")
			(pintype "passive")
		)
		(pad "2" smd roundrect
			(at 0.7 0)
			(size 0.8 1)
			(layers "F.Cu" "F.Mask" "F.Paste")
			(roundrect_rratio 0.2)
			(net 255 "/Power/+3V3_OUT")
			(pinfunction "A")
			(pintype "passive")
		)
	)
	(footprint "antmicro-footprints:R_0402_1005Metric"
		(layer "F.Cu")
		(at 72.42 106.35)
		(descr "Resistor SMD 0402")
		(tags "resistor SMD 0402")
		(property "Reference" "R48"
			(at -1.08 -0.42 0)
			(layer "F.SilkS")
			(effects
				(font
					(size 0.7 0.7)
					(thickness 0.15)
				)
				(justify left bottom)
			)
		)
		(property "Value" "R_10R_0402"
			(at -1.011843 1.772047 0)
			(layer "F.Fab")
			(hide yes)
			(effects
				(font
					(size 0.7 0.7)
					(thickness 0.15)
				)
				(justify left bottom)
			)
		)
		(property "Datasheet" "https://www.bourns.com/docs/product-datasheets/cr.pdf"
			(at 0 0 0)
			(layer "F.Fab")
			(hide yes)
			(effects
				(font
					(size 1.27 1.27)
					(thickness 0.15)
				)
			)
		)
		(property "Description" "SMD Chip Resistor, 10 ohm, ± 1%, 62.5 mW, 0402 [1005 Metric], Thick Film, General Purpose"
			(at 0 0 0)
			(layer "F.Fab")
			(hide yes)
			(effects
				(font
					(size 1.27 1.27)
					(thickness 0.15)
				)
			)
		)
		(property "MPN" "CR0402-FX-10R0GLF"
			(at 0 0 0)
			(unlocked yes)
			(layer "F.Fab")
			(hide yes)
			(effects
				(font
					(size 1 1)
					(thickness 0.15)
				)
			)
		)
		(property "Manufacturer" "Bourns"
			(at 0 0 0)
			(unlocked yes)
			(layer "F.Fab")
			(hide yes)
			(effects
				(font
					(size 1 1)
					(thickness 0.15)
				)
			)
		)
		(property "License" "Apache-2.0"
			(at 0 0 0)
			(unlocked yes)
			(layer "F.Fab")
			(hide yes)
			(effects
				(font
					(size 1 1)
					(thickness 0.15)
				)
			)
		)
		(property "Author" "Antmicro"
			(at 0 0 0)
			(unlocked yes)
			(layer "F.Fab")
			(hide yes)
			(effects
				(font
					(size 1 1)
					(thickness 0.15)
				)
			)
		)
		(property "Val" "10R"
			(at 0 0 0)
			(unlocked yes)
			(layer "F.Fab")
			(hide yes)
			(effects
				(font
					(size 1 1)
					(thickness 0.15)
				)
			)
		)
		(property "Tolerance" "1%"
			(at 0 0 0)
			(unlocked yes)
			(layer "F.Fab")
			(hide yes)
			(effects
				(font
					(size 1 1)
					(thickness 0.15)
				)
			)
		)
		(sheetname "/X710-AT2 Misc/")
		(sheetfile "x710-at2-mics.kicad_sch")
		(attr smd)
		(fp_rect
			(start -0.925 -0.47)
			(end 0.925 0.47)
			(stroke
				(width 0.05)
				(type default)
			)
			(fill no)
			(layer "F.CrtYd")
		)
		(fp_rect
			(start -0.5 -0.25)
			(end 0.5 0.25)
			(stroke
				(width 0.15)
				(type solid)
			)
			(fill no)
			(layer "F.Fab")
		)
		(pad "1" smd roundrect
			(at -0.48 0)
			(size 0.59 0.64)
			(layers "F.Cu" "F.Mask" "F.Paste")
			(roundrect_rratio 0.25)
			(net 77 "/X710-AT2 Misc/50MHZ_XTAL_R.-")
			(pintype "passive")
		)
		(pad "2" smd roundrect
			(at 0.48 0)
			(size 0.59 0.64)
			(layers "F.Cu" "F.Mask" "F.Paste")
			(roundrect_rratio 0.25)
			(net 191 "/X710-AT2 Misc/50MHZ_XTAL.-")
			(pintype "passive")
		)
	)
	(footprint "antmicro-footprints:C_0603_1608Metric"
		(layer "F.Cu")
		(at 97.9 99.3 180)
		(descr "Capacitor SMD 0603")
		(tags "capacitor 0603")
		(property "Reference" "C147"
			(at -3.75 0.35 0)
			(layer "F.SilkS")
			(effects
				(font
					(size 0.7 0.7)
					(thickness 0.15)
				)
				(justify left top)
			)
		)
		(property "Value" "C_10u_10V_X7R_0603"
			(at -1.42757 1.770288 0)
			(layer "F.Fab")
			(hide yes)
			(effects
				(font
					(size 0.7 0.7)
					(thickness 0.15)
				)
				(justify right top)
			)
		)
		(property "Datasheet" "https://www.murata.com/products/productdetail?partno=GRM188Z71A106KA73%23"
			(at 0 0 0)
			(layer "F.Fab")
			(hide yes)
			(effects
				(font
					(size 1.27 1.27)
					(thickness 0.15)
				)
			)
		)
		(property "Description" "SMD Multilayer Ceramic Capacitor,  10µF, 10V, 0603, ±10%, X7R"
			(at 0 0 0)
			(layer "F.Fab")
			(hide yes)
			(effects
				(font
					(size 1.27 1.27)
					(thickness 0.15)
				)
			)
		)
		(property "MPN" "GRM188Z71A106KA73D"
			(at 0 0 180)
			(unlocked yes)
			(layer "F.Fab")
			(hide yes)
			(effects
				(font
					(size 1 1)
					(thickness 0.15)
				)
			)
		)
		(property "Val" "10u"
			(at 0 0 180)
			(unlocked yes)
			(layer "F.Fab")
			(hide yes)
			(effects
				(font
					(size 1 1)
					(thickness 0.15)
				)
			)
		)
		(property "Voltage" "10V"
			(at 0 0 180)
			(unlocked yes)
			(layer "F.Fab")
			(hide yes)
			(effects
				(font
					(size 1 1)
					(thickness 0.15)
				)
			)
		)
		(property "Dielectric" "X7R"
			(at 0 0 180)
			(unlocked yes)
			(layer "F.Fab")
			(hide yes)
			(effects
				(font
					(size 1 1)
					(thickness 0.15)
				)
			)
		)
		(property "Manufacturer" "Murata"
			(at 0 0 180)
			(unlocked yes)
			(layer "F.Fab")
			(hide yes)
			(effects
				(font
					(size 1 1)
					(thickness 0.15)
				)
			)
		)
		(property "License" "Apache-2.0"
			(at 0 0 180)
			(unlocked yes)
			(layer "F.Fab")
			(hide yes)
			(effects
				(font
					(size 1 1)
					(thickness 0.15)
				)
			)
		)
		(property "Author" "Antmicro"
			(at 0 0 180)
			(unlocked yes)
			(layer "F.Fab")
			(hide yes)
			(effects
				(font
					(size 1 1)
					(thickness 0.15)
				)
			)
		)
		(sheetname "/X710-AT2 power/")
		(sheetfile "x710-at2-power.kicad_sch")
		(attr smd)
		(fp_line
			(start -0.15 0.4)
			(end 0.15 0.4)
			(stroke
				(width 0.15)
				(type solid)
			)
			(layer "F.SilkS")
		)
		(fp_line
			(start -0.15 -0.4)
			(end 0.15 -0.4)
			(stroke
				(width 0.15)
				(type solid)
			)
			(layer "F.SilkS")
		)
		(fp_rect
			(start -1.25 -0.65)
			(end 1.25 0.65)
			(stroke
				(width 0.05)
				(type solid)
			)
			(fill no)
			(layer "F.CrtYd")
		)
		(fp_rect
			(start -0.8 -0.4)
			(end 0.8 0.4)
			(stroke
				(width 0.15)
				(type solid)
			)
			(fill no)
			(layer "F.Fab")
		)
		(pad "1" smd roundrect
			(at -0.7 0 180)
			(size 0.8 1)
			(layers "F.Cu" "F.Mask" "F.Paste")
			(roundrect_rratio 0.2)
			(net 28 "GND")
			(pintype "passive")
		)
		(pad "2" smd roundrect
			(at 0.7 0 180)
			(size 0.8 1)
			(layers "F.Cu" "F.Mask" "F.Paste")
			(roundrect_rratio 0.2)
			(net 7 "+3V3")
			(pintype "passive")
		)
	)
	(footprint "antmicro-footprints:C_0603_1608Metric_EIA"
		(layer "F.Cu")
		(at 51.9 103.900001 -90)
		(descr "Capacitor SMD 0603, IPC-7351 Density Level A")
		(tags "Capacitor 0603")
		(property "Reference" "C21"
			(at -0.890001 1.56 90)
			(layer "F.SilkS")
			(effects
				(font
					(size 0.7 0.7)
					(thickness 0.15)
				)
				(justify right top)
			)
		)
		(property "Value" "C_22u_16V_0603"
			(at -1.42757 1.770288 90)
			(layer "F.Fab")
			(hide yes)
			(effects
				(font
					(size 0.7 0.7)
					(thickness 0.15)
				)
				(justify right top)
			)
		)
		(property "Datasheet" "https://product.samsungsem.com/mlcc/CL10A226MO7JZN.do"
			(at 0 0 90)
			(layer "F.Fab")
			(hide yes)
			(effects
				(font
					(size 1.27 1.27)
					(thickness 0.15)
				)
			)
		)
		(property "Description" "SMD Multilayer Ceramic Capacitor"
			(at 0 0 90)
			(layer "F.Fab")
			(hide yes)
			(effects
				(font
					(size 1.27 1.27)
					(thickness 0.15)
				)
			)
		)
		(property "MPN" "CL10A226MO7JZNC"
			(at 0 0 270)
			(unlocked yes)
			(layer "F.Fab")
			(hide yes)
			(effects
				(font
					(size 1 1)
					(thickness 0.15)
				)
			)
		)
		(property "Manufacturer" "Samsung Electro-Mechanics"
			(at 0 0 270)
			(unlocked yes)
			(layer "F.Fab")
			(hide yes)
			(effects
				(font
					(size 1 1)
					(thickness 0.15)
				)
			)
		)
		(property "License" "Apache-2.0"
			(at 0 0 270)
			(unlocked yes)
			(layer "F.Fab")
			(hide yes)
			(effects
				(font
					(size 1 1)
					(thickness 0.15)
				)
			)
		)
		(property "Author" "Antmicro"
			(at 0 0 270)
			(unlocked yes)
			(layer "F.Fab")
			(hide yes)
			(effects
				(font
					(size 1 1)
					(thickness 0.15)
				)
			)
		)
		(property "Val" "22u"
			(at 0 0 270)
			(unlocked yes)
			(layer "F.Fab")
			(hide yes)
			(effects
				(font
					(size 1 1)
					(thickness 0.15)
				)
			)
		)
		(property "Voltage" "16V"
			(at 0 0 270)
			(unlocked yes)
			(layer "F.Fab")
			(hide yes)
			(effects
				(font
					(size 1 1)
					(thickness 0.15)
				)
			)
		)
		(property "Dielectric" ""
			(at 0 0 270)
			(unlocked yes)
			(layer "F.Fab")
			(hide yes)
			(effects
				(font
					(size 1 1)
					(thickness 0.15)
				)
			)
		)
		(property "Public" "False"
			(at 0 0 270)
			(unlocked yes)
			(layer "F.Fab")
			(hide yes)
			(effects
				(font
					(size 1 1)
					(thickness 0.15)
				)
			)
		)
		(sheetname "/Power/")
		(sheetfile "power.kicad_sch")
		(attr smd)
		(fp_line
			(start -0.15 0.55)
			(end 0.15 0.55)
			(stroke
				(width 0.15)
				(type solid)
			)
			(layer "F.SilkS")
		)
		(fp_line
			(start -0.15 -0.55)
			(end 0.15 -0.55)
			(stroke
				(width 0.15)
				(type solid)
			)
			(layer "F.SilkS")
		)
		(fp_rect
			(start -1.25 -0.65)
			(end 1.25 0.65)
			(stroke
				(width 0.05)
				(type solid)
			)
			(fill no)
			(layer "F.CrtYd")
		)
		(fp_rect
			(start -0.8 -0.45)
			(end 0.8 0.45)
			(stroke
				(width 0.15)
				(type solid)
			)
			(fill no)
			(layer "F.Fab")
		)
		(pad "1" smd roundrect
			(at -0.7 0 270)
			(size 0.8 1.1)
			(layers "F.Cu" "F.Mask" "F.Paste")
			(roundrect_rratio 0.2)
			(net 28 "GND")
			(pintype "passive")
		)
		(pad "2" smd roundrect
			(at 0.7 0 270)
			(size 0.8 1.1)
			(layers "F.Cu" "F.Mask" "F.Paste")
			(roundrect_rratio 0.2)
			(net 314 "VCC")
			(pintype "passive")
		)
	)
	(footprint "antmicro-footprints:VQFN-HR-9_2x1.5mm"
		(layer "F.Cu")
		(at 56.100001 88.049999 -90)
		(property "Reference" "U2"
			(at 1.290001 0.380001 180)
			(layer "F.SilkS")
			(effects
				(font
					(size 0.7 0.7)
					(thickness 0.15)
				)
				(justify right top)
			)
		)
		(property "Value" "TPS566231P"
			(at -1.45 2.45 90)
			(layer "F.Fab")
			(hide yes)
			(effects
				(font
					(size 0.7 0.7)
					(thickness 0.15)
				)
				(justify right top)
			)
		)
		(property "Datasheet" "https://www.ti.com/lit/ds/symlink/tps566231.pdf"
			(at 0 -0.045 90)
			(layer "F.Fab")
			(hide yes)
			(effects
				(font
					(size 0.7 0.7)
					(thickness 0.15)
				)
				(justify right top)
			)
		)
		(property "Description" "Switching Voltage Regulators 3-V to 18-V, 6-A synchronous buck converter"
			(at -1.45 3.65 90)
			(layer "F.Fab")
			(hide yes)
			(effects
				(font
					(size 0.7 0.7)
					(thickness 0.15)
				)
				(justify right top)
			)
		)
		(property "Manufacturer" "Texas Instruments"
			(at 0 0 270)
			(unlocked yes)
			(layer "F.Fab")
			(hide yes)
			(effects
				(font
					(size 1 1)
					(thickness 0.15)
				)
			)
		)
		(property "MPN" "TPS566231PRQFR"
			(at 0 0 270)
			(unlocked yes)
			(layer "F.Fab")
			(hide yes)
			(effects
				(font
					(size 1 1)
					(thickness 0.15)
				)
			)
		)
		(property "Author" "Antmicro"
			(at 0 0 270)
			(unlocked yes)
			(layer "F.Fab")
			(hide yes)
			(effects
				(font
					(size 1 1)
					(thickness 0.15)
				)
			)
		)
		(property "License" "Apache-2.0"
			(at 0 0 270)
			(unlocked yes)
			(layer "F.Fab")
			(hide yes)
			(effects
				(font
					(size 1 1)
					(thickness 0.15)
				)
			)
		)
		(sheetname "/Power/")
		(sheetfile "power.kicad_sch")
		(attr smd)
		(fp_line
			(start -1 0.945)
			(end -0.695 0.945)
			(stroke
				(width 0.15)
				(type solid)
			)
			(layer "F.SilkS")
		)
		(fp_line
			(start 1 0.945)
			(end 0.2 0.945)
			(stroke
				(width 0.15)
				(type solid)
			)
			(layer "F.SilkS")
		)
		(fp_line
			(start -1 -0.945)
			(end -0.695 -0.945)
			(stroke
				(width 0.15)
				(type solid)
			)
			(layer "F.SilkS")
		)
		(fp_line
			(start 1 -0.945)
			(end 0.695 -0.945)
			(stroke
				(width 0.15)
				(type solid)
			)
			(layer "F.SilkS")
		)
		(fp_circle
			(center -1.18 -0.77)
			(end -1.13 -0.77)
			(stroke
				(width 0.15)
				(type solid)
			)
			(fill yes)
			(layer "F.SilkS")
		)
		(fp_rect
			(start -1.3 -1.05)
			(end 1.3 1.05)
			(stroke
				(width 0.05)
				(type solid)
			)
			(fill no)
			(layer "F.CrtYd")
		)
		(fp_rect
			(start -1 -0.75)
			(end 1 0.75)
			(stroke
				(width 0.15)
				(type solid)
			)
			(fill no)
			(layer "F.Fab")
		)
		(pad "1" smd roundrect
			(at -0.925 -0.5 270)
			(size 0.55 0.25)
			(layers "F.Cu" "F.Mask" "F.Paste")
			(roundrect_rratio 0.125)
			(net 322 "/Power/VCCD_VCC")
			(pinfunction "V_{CC}")
			(pintype "passive")
		)
		(pad "2" smd roundrect
			(at -0.925 0 270)
			(size 0.55 0.25)
			(layers "F.Cu" "F.Mask" "F.Paste")
			(roundrect_rratio 0.125)
			(net 329 "/Power/VCCD_FB")
			(pinfunction "FB")
			(pintype "input")
		)
		(pad "3" smd roundrect
			(at -0.925 0.5 270)
			(size 0.55 0.25)
			(layers "F.Cu" "F.Mask" "F.Paste")
			(roundrect_rratio 0.125)
			(net 340 "/Power/VCCD_EN")
			(pinfunction "EN")
			(pintype "input")
		)
		(pad "4" smd roundrect
			(at -0.25 0.45 270)
			(size 0.25 1)
			(layers "F.Cu" "F.Mask" "F.Paste")
			(roundrect_rratio 0.125)
			(net 28 "GND")
			(pinfunction "PGND")
			(pintype "power_in")
		)
		(pad "5" smd roundrect
			(at 0.925 0.5 270)
			(size 0.55 0.25)
			(layers "F.Cu" "F.Mask" "F.Paste")
			(roundrect_rratio 0.125)
			(net 314 "VCC")
			(pinfunction "V_{IN}")
			(pintype "power_in")
		)
		(pad "6" smd roundrect
			(at 0.925 0 270)
			(size 0.55 0.25)
			(layers "F.Cu" "F.Mask" "F.Paste")
			(roundrect_rratio 0.125)
			(net 314 "VCC")
			(pinfunction "V_{IN}")
			(pintype "passive")
		)
		(pad "7" smd roundrect
			(at 0.925 -0.5 270)
			(size 0.55 0.25)
			(layers "F.Cu" "F.Mask" "F.Paste")
			(roundrect_rratio 0.125)
			(net 318 "/Power/VCCD_BST")
			(pinfunction "BST")
			(pintype "passive")
		)
		(pad "8" smd roundrect
			(at 0.25 -0.3 270)
			(size 0.25 1.3)
			(layers "F.Cu" "F.Mask" "F.Paste")
			(roundrect_rratio 0.125)
			(net 334 "/Power/VCCD_SW")
			(pinfunction "SW")
			(pintype "power_out")
		)
		(pad "9" smd roundrect
			(at -0.25 -0.675 270)
			(size 0.25 0.55)
			(layers "F.Cu" "F.Mask" "F.Paste")
			(roundrect_rratio 0.125)
			(net 342 "/Power/VCCD_PG")
			(pinfunction "PG")
			(pintype "passive")
		)
	)
	(footprint "antmicro-footprints:R_0402_1005Metric"
		(layer "F.Cu")
		(at 56.97 82.764 -90)
		(descr "Resistor SMD 0402")
		(tags "resistor SMD 0402")
		(property "Reference" "R53"
			(at -3.094 0.09 90)
			(layer "F.SilkS")
			(effects
				(font
					(size 0.7 0.7)
					(thickness 0.15)
				)
				(justify right top)
			)
		)
		(property "Value" "R_8k2_0402"
			(at -1.011843 1.772046 90)
			(layer "F.Fab")
			(hide yes)
			(effects
				(font
					(size 0.7 0.7)
					(thickness 0.15)
				)
				(justify right top)
			)
		)
		(property "Datasheet" "https://www.bourns.com/docs/product-datasheets/cr.pdf"
			(at 0 0 90)
			(layer "F.Fab")
			(hide yes)
			(effects
				(font
					(size 1.27 1.27)
					(thickness 0.15)
				)
			)
		)
		(property "Description" "SMD Chip Resistor"
			(at 0 0 90)
			(layer "F.Fab")
			(hide yes)
			(effects
				(font
					(size 1.27 1.27)
					(thickness 0.15)
				)
			)
		)
		(property "MPN" "CR0402-FX-8201GLF"
			(at 0 0 270)
			(unlocked yes)
			(layer "F.Fab")
			(hide yes)
			(effects
				(font
					(size 1 1)
					(thickness 0.15)
				)
			)
		)
		(property "Manufacturer" "Bourns"
			(at 0 0 270)
			(unlocked yes)
			(layer "F.Fab")
			(hide yes)
			(effects
				(font
					(size 1 1)
					(thickness 0.15)
				)
			)
		)
		(property "License" "Apache-2.0"
			(at 0 0 270)
			(unlocked yes)
			(layer "F.Fab")
			(hide yes)
			(effects
				(font
					(size 1 1)
					(thickness 0.15)
				)
			)
		)
		(property "Author" "Antmicro"
			(at 0 0 270)
			(unlocked yes)
			(layer "F.Fab")
			(hide yes)
			(effects
				(font
					(size 1 1)
					(thickness 0.15)
				)
			)
		)
		(property "Val" "8k2"
			(at 0 0 270)
			(unlocked yes)
			(layer "F.Fab")
			(hide yes)
			(effects
				(font
					(size 1 1)
					(thickness 0.15)
				)
			)
		)
		(property "Tolerance" "1%"
			(at 0 0 270)
			(unlocked yes)
			(layer "F.Fab")
			(hide yes)
			(effects
				(font
					(size 1 1)
					(thickness 0.15)
				)
			)
		)
		(sheetname "/X710-AT2 PCIe/")
		(sheetfile "x710-at2-pcie.kicad_sch")
		(attr smd)
		(fp_rect
			(start -0.925 -0.47)
			(end 0.925 0.47)
			(stroke
				(width 0.05)
				(type default)
			)
			(fill no)
			(layer "F.CrtYd")
		)
		(fp_rect
			(start -0.5 -0.25)
			(end 0.5 0.25)
			(stroke
				(width 0.15)
				(type solid)
			)
			(fill no)
			(layer "F.Fab")
		)
		(pad "1" smd roundrect
			(at -0.48 0 270)
			(size 0.59 0.64)
			(layers "F.Cu" "F.Mask" "F.Paste")
			(roundrect_rratio 0.25)
			(net 4 "/X710-AT2 PCIe/PCIe_JTAG.JTMS")
			(pintype "passive")
		)
		(pad "2" smd roundrect
			(at 0.48 0 270)
			(size 0.59 0.64)
			(layers "F.Cu" "F.Mask" "F.Paste")
			(roundrect_rratio 0.25)
			(net 7 "+3V3")
			(pintype "passive")
		)
	)
	(footprint "antmicro-footprints:C_0402_1005Metric"
		(layer "F.Cu")
		(at 55.099999 92.849999 90)
		(descr "Capacitor SMD 0402")
		(tags "capacitor SMD 0402")
		(property "Reference" "C39"
			(at -1.120001 -2.329999 90)
			(layer "F.SilkS")
			(effects
				(font
					(size 0.7 0.7)
					(thickness 0.15)
				)
				(justify left bottom)
			)
		)
		(property "Value" "C_33p_0402"
			(at -1.022927 2.155213 90)
			(layer "F.Fab")
			(hide yes)
			(effects
				(font
					(size 0.7 0.7)
					(thickness 0.15)
				)
				(justify left bottom)
			)
		)
		(property "Datasheet" "https://spicat.kyocera-avx.com/product/mlcc/chartview/04025A330FAT2A/"
			(at 0 0 90)
			(layer "F.Fab")
			(hide yes)
			(effects
				(font
					(size 1.27 1.27)
					(thickness 0.15)
				)
			)
		)
		(property "Description" "SMD Multilayer Ceramic Capacitor, 33 pF, 50 V, 0402 [1005 Metric], ± 5%, C0G / NP0, MC"
			(at 0 0 90)
			(layer "F.Fab")
			(hide yes)
			(effects
				(font
					(size 1.27 1.27)
					(thickness 0.15)
				)
			)
		)
		(property "MPN" "04025A330FAT2A"
			(at 0 0 90)
			(unlocked yes)
			(layer "F.Fab")
			(hide yes)
			(effects
				(font
					(size 1 1)
					(thickness 0.15)
				)
			)
		)
		(property "Manufacturer" "KYOCERA AVX"
			(at 0 0 90)
			(unlocked yes)
			(layer "F.Fab")
			(hide yes)
			(effects
				(font
					(size 1 1)
					(thickness 0.15)
				)
			)
		)
		(property "License" "Apache-2.0"
			(at 0 0 90)
			(unlocked yes)
			(layer "F.Fab")
			(hide yes)
			(effects
				(font
					(size 1 1)
					(thickness 0.15)
				)
			)
		)
		(property "Author" "Antmicro"
			(at 0 0 90)
			(unlocked yes)
			(layer "F.Fab")
			(hide yes)
			(effects
				(font
					(size 1 1)
					(thickness 0.15)
				)
			)
		)
		(property "Val" "33p"
			(at 0 0 90)
			(unlocked yes)
			(layer "F.Fab")
			(hide yes)
			(effects
				(font
					(size 1 1)
					(thickness 0.15)
				)
			)
		)
		(property "Voltage" ""
			(at 0 0 90)
			(unlocked yes)
			(layer "F.Fab")
			(hide yes)
			(effects
				(font
					(size 1 1)
					(thickness 0.15)
				)
			)
		)
		(property "Dielectric" ""
			(at 0 0 90)
			(unlocked yes)
			(layer "F.Fab")
			(hide yes)
			(effects
				(font
					(size 1 1)
					(thickness 0.15)
				)
			)
		)
		(sheetname "/Power/")
		(sheetfile "power.kicad_sch")
		(attr smd exclude_from_pos_files exclude_from_bom dnp)
		(fp_rect
			(start -0.925 -0.47)
			(end 0.925 0.47)
			(stroke
				(width 0.05)
				(type default)
			)
			(fill no)
			(layer "F.CrtYd")
		)
		(fp_line
			(start 0.504 -0.25)
			(end 0.504 0.248)
			(stroke
				(width 0.15)
				(type solid)
			)
			(layer "F.Fab")
		)
		(fp_line
			(start -0.494 -0.25)
			(end 0.504 -0.25)
			(stroke
				(width 0.15)
				(type solid)
			)
			(layer "F.Fab")
		)
		(fp_line
			(start 0.504 0.248)
			(end -0.494 0.248)
			(stroke
				(width 0.15)
				(type solid)
			)
			(layer "F.Fab")
		)
		(fp_line
			(start -0.494 0.248)
			(end -0.494 -0.25)
			(stroke
				(width 0.15)
				(type solid)
			)
			(layer "F.Fab")
		)
		(pad "1" smd roundrect
			(at -0.48 0 90)
			(size 0.59 0.64)
			(layers "F.Cu" "F.Mask" "F.Paste")
			(roundrect_rratio 0.25)
			(net 331 "/Power/DVDD_FB")
			(pintype "passive")
		)
		(pad "2" smd roundrect
			(at 0.48 0 90)
			(size 0.59 0.64)
			(layers "F.Cu" "F.Mask" "F.Paste")
			(roundrect_rratio 0.25)
			(net 311 "/Power/+DVDD_OUT")
			(pintype "passive")
		)
	)
	(footprint "antmicro-footprints:C_0603_1608Metric_EIA"
		(layer "F.Cu")
		(at 66.7 90.699999 180)
		(descr "Capacitor SMD 0603, IPC-7351 Density Level A")
		(tags "Capacitor 0603")
		(property "Reference" "C81"
			(at 1.01 1.139999 0)
			(layer "F.SilkS")
			(effects
				(font
					(size 0.7 0.7)
					(thickness 0.15)
				)
				(justify right top)
			)
		)
		(property "Value" "C_22u_16V_0603"
			(at -1.42757 1.770288 0)
			(layer "F.Fab")
			(hide yes)
			(effects
				(font
					(size 0.7 0.7)
					(thickness 0.15)
				)
				(justify right top)
			)
		)
		(property "Datasheet" "https://product.samsungsem.com/mlcc/CL10A226MO7JZN.do"
			(at 0 0 0)
			(layer "F.Fab")
			(hide yes)
			(effects
				(font
					(size 1.27 1.27)
					(thickness 0.15)
				)
			)
		)
		(property "Description" "SMD Multilayer Ceramic Capacitor"
			(at 0 0 0)
			(layer "F.Fab")
			(hide yes)
			(effects
				(font
					(size 1.27 1.27)
					(thickness 0.15)
				)
			)
		)
		(property "MPN" "CL10A226MO7JZNC"
			(at 0 0 180)
			(unlocked yes)
			(layer "F.Fab")
			(hide yes)
			(effects
				(font
					(size 1 1)
					(thickness 0.15)
				)
			)
		)
		(property "Manufacturer" "Samsung Electro-Mechanics"
			(at 0 0 180)
			(unlocked yes)
			(layer "F.Fab")
			(hide yes)
			(effects
				(font
					(size 1 1)
					(thickness 0.15)
				)
			)
		)
		(property "License" "Apache-2.0"
			(at 0 0 180)
			(unlocked yes)
			(layer "F.Fab")
			(hide yes)
			(effects
				(font
					(size 1 1)
					(thickness 0.15)
				)
			)
		)
		(property "Author" "Antmicro"
			(at 0 0 180)
			(unlocked yes)
			(layer "F.Fab")
			(hide yes)
			(effects
				(font
					(size 1 1)
					(thickness 0.15)
				)
			)
		)
		(property "Val" "22u"
			(at 0 0 180)
			(unlocked yes)
			(layer "F.Fab")
			(hide yes)
			(effects
				(font
					(size 1 1)
					(thickness 0.15)
				)
			)
		)
		(property "Voltage" "16V"
			(at 0 0 180)
			(unlocked yes)
			(layer "F.Fab")
			(hide yes)
			(effects
				(font
					(size 1 1)
					(thickness 0.15)
				)
			)
		)
		(property "Dielectric" ""
			(at 0 0 180)
			(unlocked yes)
			(layer "F.Fab")
			(hide yes)
			(effects
				(font
					(size 1 1)
					(thickness 0.15)
				)
			)
		)
		(sheetname "/X710-AT2 power/")
		(sheetfile "x710-at2-power.kicad_sch")
		(attr smd)
		(fp_line
			(start -0.15 0.55)
			(end 0.15 0.55)
			(stroke
				(width 0.15)
				(type solid)
			)
			(layer "F.SilkS")
		)
		(fp_line
			(start -0.15 -0.55)
			(end 0.15 -0.55)
			(stroke
				(width 0.15)
				(type solid)
			)
			(layer "F.SilkS")
		)
		(fp_rect
			(start -1.25 -0.65)
			(end 1.25 0.65)
			(stroke
				(width 0.05)
				(type solid)
			)
			(fill no)
			(layer "F.CrtYd")
		)
		(fp_rect
			(start -0.8 -0.45)
			(end 0.8 0.45)
			(stroke
				(width 0.15)
				(type solid)
			)
			(fill no)
			(layer "F.Fab")
		)
		(pad "1" smd roundrect
			(at -0.7 0 180)
			(size 0.8 1.1)
			(layers "F.Cu" "F.Mask" "F.Paste")
			(roundrect_rratio 0.2)
			(net 28 "GND")
			(pintype "passive")
		)
		(pad "2" smd roundrect
			(at 0.7 0 180)
			(size 0.8 1.1)
			(layers "F.Cu" "F.Mask" "F.Paste")
			(roundrect_rratio 0.2)
			(net 6 "DVDD")
			(pintype "passive")
		)
	)
	(footprint "antmicro-footprints:C_0402_1005Metric"
		(layer "F.Cu")
		(at 67.9 103.7 90)
		(descr "Capacitor SMD 0402")
		(tags "capacitor SMD 0402")
		(property "Reference" "C185"
			(at -1.48 -0.59 90)
			(layer "F.SilkS")
			(effects
				(font
					(size 0.7 0.7)
					(thickness 0.15)
				)
				(justify left bottom)
			)
		)
		(property "Value" "C_100n_0402"
			(at -1.022927 2.155213 90)
			(layer "F.Fab")
			(hide yes)
			(effects
				(font
					(size 0.7 0.7)
					(thickness 0.15)
				)
				(justify left bottom)
			)
		)
		(property "Datasheet" "https://www.murata.com/products/productdetail?partno=GRM155R61H104KE14%23"
			(at 0 0 90)
			(layer "F.Fab")
			(hide yes)
			(effects
				(font
					(size 1.27 1.27)
					(thickness 0.15)
				)
			)
		)
		(property "Description" "SMD Multilayer Ceramic Capacitor, 0.1 µF, 50 V, 0402 [1005 Metric], ± 10%, X5R, GRM Series"
			(at 0 0 90)
			(layer "F.Fab")
			(hide yes)
			(effects
				(font
					(size 1.27 1.27)
					(thickness 0.15)
				)
			)
		)
		(property "MPN" "GRM155R61H104KE14D"
			(at 0 0 90)
			(unlocked yes)
			(layer "F.Fab")
			(hide yes)
			(effects
				(font
					(size 1 1)
					(thickness 0.15)
				)
			)
		)
		(property "Val" "100n"
			(at 0 0 90)
			(unlocked yes)
			(layer "F.Fab")
			(hide yes)
			(effects
				(font
					(size 1 1)
					(thickness 0.15)
				)
			)
		)
		(property "Voltage" "50V"
			(at 0 0 90)
			(unlocked yes)
			(layer "F.Fab")
			(hide yes)
			(effects
				(font
					(size 1 1)
					(thickness 0.15)
				)
			)
		)
		(property "Dielectric" "X5R"
			(at 0 0 90)
			(unlocked yes)
			(layer "F.Fab")
			(hide yes)
			(effects
				(font
					(size 1 1)
					(thickness 0.15)
				)
			)
		)
		(property "Manufacturer" "Murata"
			(at 0 0 90)
			(unlocked yes)
			(layer "F.Fab")
			(hide yes)
			(effects
				(font
					(size 1 1)
					(thickness 0.15)
				)
			)
		)
		(property "License" "Apache-2.0"
			(at 0 0 90)
			(unlocked yes)
			(layer "F.Fab")
			(hide yes)
			(effects
				(font
					(size 1 1)
					(thickness 0.15)
				)
			)
		)
		(property "Author" "Antmicro"
			(at 0 0 90)
			(unlocked yes)
			(layer "F.Fab")
			(hide yes)
			(effects
				(font
					(size 1 1)
					(thickness 0.15)
				)
			)
		)
		(sheetname "/X710-AT2 power/")
		(sheetfile "x710-at2-power.kicad_sch")
		(attr smd)
		(fp_rect
			(start -0.925 -0.47)
			(end 0.925 0.47)
			(stroke
				(width 0.05)
				(type default)
			)
			(fill no)
			(layer "F.CrtYd")
		)
		(fp_line
			(start 0.504 -0.25)
			(end 0.504 0.248)
			(stroke
				(width 0.15)
				(type solid)
			)
			(layer "F.Fab")
		)
		(fp_line
			(start -0.494 -0.25)
			(end 0.504 -0.25)
			(stroke
				(width 0.15)
				(type solid)
			)
			(layer "F.Fab")
		)
		(fp_line
			(start 0.504 0.248)
			(end -0.494 0.248)
			(stroke
				(width 0.15)
				(type solid)
			)
			(layer "F.Fab")
		)
		(fp_line
			(start -0.494 0.248)
			(end -0.494 -0.25)
			(stroke
				(width 0.15)
				(type solid)
			)
			(layer "F.Fab")
		)
		(pad "1" smd roundrect
			(at -0.48 0 90)
			(size 0.59 0.64)
			(layers "F.Cu" "F.Mask" "F.Paste")
			(roundrect_rratio 0.25)
			(net 28 "GND")
			(pintype "passive")
		)
		(pad "2" smd roundrect
			(at 0.48 0 90)
			(size 0.59 0.64)
			(layers "F.Cu" "F.Mask" "F.Paste")
			(roundrect_rratio 0.25)
			(net 302 "+1V0")
			(pintype "passive")
		)
	)
	(footprint "antmicro-footprints:C_0402_1005Metric"
		(layer "F.Cu")
		(at 69.52 107.94)
		(descr "Capacitor SMD 0402")
		(tags "capacitor SMD 0402")
		(property "Reference" "C72"
			(at -2.85 0.46 0)
			(layer "F.SilkS")
			(effects
				(font
					(size 0.7 0.7)
					(thickness 0.15)
				)
				(justify left bottom)
			)
		)
		(property "Value" "C_5p6_0402"
			(at -1.022927 2.155213 0)
			(layer "F.Fab")
			(hide yes)
			(effects
				(font
					(size 0.7 0.7)
					(thickness 0.15)
				)
				(justify left bottom)
			)
		)
		(property "Datasheet" "https://www.mouser.com/datasheet/3/76/2/GCM1555C1H5R6BA16_01A.pdf"
			(at 0 0 0)
			(layer "F.Fab")
			(hide yes)
			(effects
				(font
					(size 1.27 1.27)
					(thickness 0.15)
				)
			)
		)
		(property "Description" "Multilayer Ceramic Capacitors MLCC - SMD/SMT 5.6 pF 50 VDC 0.1 pF 0402 C0G (NP0) AEC-Q200"
			(at 0 0 0)
			(layer "F.Fab")
			(hide yes)
			(effects
				(font
					(size 1.27 1.27)
					(thickness 0.15)
				)
			)
		)
		(property "MPN" "GCM1555C1H5R6BA16D"
			(at 0 0 0)
			(unlocked yes)
			(layer "F.Fab")
			(hide yes)
			(effects
				(font
					(size 1 1)
					(thickness 0.15)
				)
			)
		)
		(property "Manufacturer" "Murata"
			(at 0 0 0)
			(unlocked yes)
			(layer "F.Fab")
			(hide yes)
			(effects
				(font
					(size 1 1)
					(thickness 0.15)
				)
			)
		)
		(property "License" "Apache-2.0"
			(at 0 0 0)
			(unlocked yes)
			(layer "F.Fab")
			(hide yes)
			(effects
				(font
					(size 1 1)
					(thickness 0.15)
				)
			)
		)
		(property "Author" "Antmicro"
			(at 0 0 0)
			(unlocked yes)
			(layer "F.Fab")
			(hide yes)
			(effects
				(font
					(size 1 1)
					(thickness 0.15)
				)
			)
		)
		(property "Val" "5p6"
			(at 0 0 0)
			(unlocked yes)
			(layer "F.Fab")
			(hide yes)
			(effects
				(font
					(size 1 1)
					(thickness 0.15)
				)
			)
		)
		(property "Voltage" "50V"
			(at 0 0 0)
			(unlocked yes)
			(layer "F.Fab")
			(hide yes)
			(effects
				(font
					(size 1 1)
					(thickness 0.15)
				)
			)
		)
		(property "Dielectric" "C0G"
			(at 0 0 0)
			(unlocked yes)
			(layer "F.Fab")
			(hide yes)
			(effects
				(font
					(size 1 1)
					(thickness 0.15)
				)
			)
		)
		(sheetname "/X710-AT2 Misc/")
		(sheetfile "x710-at2-mics.kicad_sch")
		(attr smd)
		(fp_rect
			(start -0.925 -0.47)
			(end 0.925 0.47)
			(stroke
				(width 0.05)
				(type default)
			)
			(fill no)
			(layer "F.CrtYd")
		)
		(fp_line
			(start -0.494 -0.25)
			(end 0.504 -0.25)
			(stroke
				(width 0.15)
				(type solid)
			)
			(layer "F.Fab")
		)
		(fp_line
			(start -0.494 0.248)
			(end -0.494 -0.25)
			(stroke
				(width 0.15)
				(type solid)
			)
			(layer "F.Fab")
		)
		(fp_line
			(start 0.504 -0.25)
			(end 0.504 0.248)
			(stroke
				(width 0.15)
				(type solid)
			)
			(layer "F.Fab")
		)
		(fp_line
			(start 0.504 0.248)
			(end -0.494 0.248)
			(stroke
				(width 0.15)
				(type solid)
			)
			(layer "F.Fab")
		)
		(pad "1" smd roundrect
			(at -0.48 0)
			(size 0.59 0.64)
			(layers "F.Cu" "F.Mask" "F.Paste")
			(roundrect_rratio 0.25)
			(net 28 "GND")
			(pintype "passive")
		)
		(pad "2" smd roundrect
			(at 0.48 0)
			(size 0.59 0.64)
			(layers "F.Cu" "F.Mask" "F.Paste")
			(roundrect_rratio 0.25)
			(net 76 "/X710-AT2 Misc/50MHZ_XTAL_R.+")
			(pintype "passive")
		)
	)
	(footprint "antmicro-footprints:VQFN-HR-9_2x1.5mm"
		(layer "F.Cu")
		(at 70.95 80.039996 180)
		(property "Reference" "U1"
			(at -2.11 -0.130004 90)
			(layer "F.SilkS")
			(effects
				(font
					(size 0.7 0.7)
					(thickness 0.15)
				)
				(justify left bottom)
			)
		)
		(property "Value" "TPS566231P"
			(at -1.45 2.45 0)
			(layer "F.Fab")
			(hide yes)
			(effects
				(font
					(size 0.7 0.7)
					(thickness 0.15)
				)
				(justify right top)
			)
		)
		(property "Datasheet" "https://www.ti.com/lit/ds/symlink/tps566231.pdf"
			(at 0 -0.045 0)
			(layer "F.Fab")
			(hide yes)
			(effects
				(font
					(size 0.7 0.7)
					(thickness 0.15)
				)
				(justify right top)
			)
		)
		(property "Description" "Switching Voltage Regulators 3-V to 18-V, 6-A synchronous buck converter"
			(at -1.45 3.65 0)
			(layer "F.Fab")
			(hide yes)
			(effects
				(font
					(size 0.7 0.7)
					(thickness 0.15)
				)
				(justify right top)
			)
		)
		(property "Manufacturer" "Texas Instruments"
			(at 0 0 180)
			(unlocked yes)
			(layer "F.Fab")
			(hide yes)
			(effects
				(font
					(size 1 1)
					(thickness 0.15)
				)
			)
		)
		(property "MPN" "TPS566231PRQFR"
			(at 0 0 180)
			(unlocked yes)
			(layer "F.Fab")
			(hide yes)
			(effects
				(font
					(size 1 1)
					(thickness 0.15)
				)
			)
		)
		(property "Author" "Antmicro"
			(at 0 0 180)
			(unlocked yes)
			(layer "F.Fab")
			(hide yes)
			(effects
				(font
					(size 1 1)
					(thickness 0.15)
				)
			)
		)
		(property "License" "Apache-2.0"
			(at 0 0 180)
			(unlocked yes)
			(layer "F.Fab")
			(hide yes)
			(effects
				(font
					(size 1 1)
					(thickness 0.15)
				)
			)
		)
		(sheetname "/Power/")
		(sheetfile "power.kicad_sch")
		(attr smd)
		(fp_line
			(start 1 0.945)
			(end 0.2 0.945)
			(stroke
				(width 0.15)
				(type solid)
			)
			(layer "F.SilkS")
		)
		(fp_line
			(start 1 -0.945)
			(end 0.695 -0.945)
			(stroke
				(width 0.15)
				(type solid)
			)
			(layer "F.SilkS")
		)
		(fp_line
			(start -1 0.945)
			(end -0.695 0.945)
			(stroke
				(width 0.15)
				(type solid)
			)
			(layer "F.SilkS")
		)
		(fp_line
			(start -1 -0.945)
			(end -0.695 -0.945)
			(stroke
				(width 0.15)
				(type solid)
			)
			(layer "F.SilkS")
		)
		(fp_circle
			(center -1.18 -0.77)
			(end -1.13 -0.77)
			(stroke
				(width 0.15)
				(type solid)
			)
			(fill yes)
			(layer "F.SilkS")
		)
		(fp_rect
			(start -1.3 -1.05)
			(end 1.3 1.05)
			(stroke
				(width 0.05)
				(type solid)
			)
			(fill no)
			(layer "F.CrtYd")
		)
		(fp_rect
			(start -1 -0.75)
			(end 1 0.75)
			(stroke
				(width 0.15)
				(type solid)
			)
			(fill no)
			(layer "F.Fab")
		)
		(pad "1" smd roundrect
			(at -0.925 -0.5 180)
			(size 0.55 0.25)
			(layers "F.Cu" "F.Mask" "F.Paste")
			(roundrect_rratio 0.125)
			(net 315 "/Power/3V3_VCC")
			(pinfunction "V_{CC}")
			(pintype "passive")
		)
		(pad "2" smd roundrect
			(at -0.925 0 180)
			(size 0.55 0.25)
			(layers "F.Cu" "F.Mask" "F.Paste")
			(roundrect_rratio 0.125)
			(net 317 "/Power/3V3_FB")
			(pinfunction "FB")
			(pintype "input")
		)
		(pad "3" smd roundrect
			(at -0.925 0.5 180)
			(size 0.55 0.25)
			(layers "F.Cu" "F.Mask" "F.Paste")
			(roundrect_rratio 0.125)
			(net 379 "/Power/3V3_EN")
			(pinfunction "EN")
			(pintype "input")
		)
		(pad "4" smd roundrect
			(at -0.25 0.45 180)
			(size 0.25 1)
			(layers "F.Cu" "F.Mask" "F.Paste")
			(roundrect_rratio 0.125)
			(net 28 "GND")
			(pinfunction "PGND")
			(pintype "power_in")
		)
		(pad "5" smd roundrect
			(at 0.925 0.5 180)
			(size 0.55 0.25)
			(layers "F.Cu" "F.Mask" "F.Paste")
			(roundrect_rratio 0.125)
			(net 314 "VCC")
			(pinfunction "V_{IN}")
			(pintype "power_in")
		)
		(pad "6" smd roundrect
			(at 0.925 0 180)
			(size 0.55 0.25)
			(layers "F.Cu" "F.Mask" "F.Paste")
			(roundrect_rratio 0.125)
			(net 314 "VCC")
			(pinfunction "V_{IN}")
			(pintype "passive")
		)
		(pad "7" smd roundrect
			(at 0.925 -0.5 180)
			(size 0.55 0.25)
			(layers "F.Cu" "F.Mask" "F.Paste")
			(roundrect_rratio 0.125)
			(net 316 "/Power/3V3_BST")
			(pinfunction "BST")
			(pintype "passive")
		)
		(pad "8" smd roundrect
			(at 0.25 -0.3 180)
			(size 0.25 1.3)
			(layers "F.Cu" "F.Mask" "F.Paste")
			(roundrect_rratio 0.125)
			(net 333 "/Power/3V3_SW")
			(pinfunction "SW")
			(pintype "power_out")
		)
		(pad "9" smd roundrect
			(at -0.25 -0.675 180)
			(size 0.25 0.55)
			(layers "F.Cu" "F.Mask" "F.Paste")
			(roundrect_rratio 0.125)
			(net 338 "/Power/3V3_PG")
			(pinfunction "PG")
			(pintype "passive")
		)
	)
	(footprint "antmicro-footprints:R_0402_1005Metric"
		(layer "F.Cu")
		(at 72.42 107.35)
		(descr "Resistor SMD 0402")
		(tags "resistor SMD 0402")
		(property "Reference" "R47"
			(at -0.9 1.23 0)
			(layer "F.SilkS")
			(effects
				(font
					(size 0.7 0.7)
					(thickness 0.15)
				)
				(justify left bottom)
			)
		)
		(property "Value" "R_10R_0402"
			(at -1.011843 1.772047 0)
			(layer "F.Fab")
			(hide yes)
			(effects
				(font
					(size 0.7 0.7)
					(thickness 0.15)
				)
				(justify left bottom)
			)
		)
		(property "Datasheet" "https://www.bourns.com/docs/product-datasheets/cr.pdf"
			(at 0 0 0)
			(layer "F.Fab")
			(hide yes)
			(effects
				(font
					(size 1.27 1.27)
					(thickness 0.15)
				)
			)
		)
		(property "Description" "SMD Chip Resistor, 10 ohm, ± 1%, 62.5 mW, 0402 [1005 Metric], Thick Film, General Purpose"
			(at 0 0 0)
			(layer "F.Fab")
			(hide yes)
			(effects
				(font
					(size 1.27 1.27)
					(thickness 0.15)
				)
			)
		)
		(property "MPN" "CR0402-FX-10R0GLF"
			(at 0 0 0)
			(unlocked yes)
			(layer "F.Fab")
			(hide yes)
			(effects
				(font
					(size 1 1)
					(thickness 0.15)
				)
			)
		)
		(property "Manufacturer" "Bourns"
			(at 0 0 0)
			(unlocked yes)
			(layer "F.Fab")
			(hide yes)
			(effects
				(font
					(size 1 1)
					(thickness 0.15)
				)
			)
		)
		(property "License" "Apache-2.0"
			(at 0 0 0)
			(unlocked yes)
			(layer "F.Fab")
			(hide yes)
			(effects
				(font
					(size 1 1)
					(thickness 0.15)
				)
			)
		)
		(property "Author" "Antmicro"
			(at 0 0 0)
			(unlocked yes)
			(layer "F.Fab")
			(hide yes)
			(effects
				(font
					(size 1 1)
					(thickness 0.15)
				)
			)
		)
		(property "Val" "10R"
			(at 0 0 0)
			(unlocked yes)
			(layer "F.Fab")
			(hide yes)
			(effects
				(font
					(size 1 1)
					(thickness 0.15)
				)
			)
		)
		(property "Tolerance" "1%"
			(at 0 0 0)
			(unlocked yes)
			(layer "F.Fab")
			(hide yes)
			(effects
				(font
					(size 1 1)
					(thickness 0.15)
				)
			)
		)
		(sheetname "/X710-AT2 Misc/")
		(sheetfile "x710-at2-mics.kicad_sch")
		(attr smd)
		(fp_rect
			(start -0.925 -0.47)
			(end 0.925 0.47)
			(stroke
				(width 0.05)
				(type default)
			)
			(fill no)
			(layer "F.CrtYd")
		)
		(fp_rect
			(start -0.5 -0.25)
			(end 0.5 0.25)
			(stroke
				(width 0.15)
				(type solid)
			)
			(fill no)
			(layer "F.Fab")
		)
		(pad "1" smd roundrect
			(at -0.48 0)
			(size 0.59 0.64)
			(layers "F.Cu" "F.Mask" "F.Paste")
			(roundrect_rratio 0.25)
			(net 76 "/X710-AT2 Misc/50MHZ_XTAL_R.+")
			(pintype "passive")
		)
		(pad "2" smd roundrect
			(at 0.48 0)
			(size 0.59 0.64)
			(layers "F.Cu" "F.Mask" "F.Paste")
			(roundrect_rratio 0.25)
			(net 153 "/X710-AT2 Misc/50MHZ_XTAL.+")
			(pintype "passive")
		)
	)
	(footprint "antmicro-footprints:R_0603_1608Metric"
		(layer "F.Cu")
		(at 74.899998 86.459997 -90)
		(descr "Resistor SMD 0603")
		(tags "resistor SMD 0603")
		(property "Reference" "R1"
			(at 0.950003 0.149998 90)
			(layer "F.SilkS")
			(effects
				(font
					(size 0.7 0.7)
					(thickness 0.15)
				)
				(justify right top)
			)
		)
		(property "Value" "R_0R_22.4A_0603"
			(at 0 1.6 90)
			(layer "F.Fab")
			(hide yes)
			(effects
				(font
					(size 0.7 0.7)
					(thickness 0.15)
				)
				(justify right top)
			)
		)
		(property "Datasheet" "https://fscdn.rohm.com/en/products/databook/datasheet/passive/resistor/chip_resistor/pmr-jpw-e.pdf"
			(at 0 0 90)
			(layer "F.Fab")
			(hide yes)
			(effects
				(font
					(size 1.27 1.27)
					(thickness 0.15)
				)
			)
		)
		(property "Description" "SMD Chip Resistor"
			(at 0 0 90)
			(layer "F.Fab")
			(hide yes)
			(effects
				(font
					(size 1.27 1.27)
					(thickness 0.15)
				)
			)
		)
		(property "MPN" "PMR03EZPJ000"
			(at 0 0 270)
			(unlocked yes)
			(layer "F.Fab")
			(hide yes)
			(effects
				(font
					(size 1 1)
					(thickness 0.15)
				)
			)
		)
		(property "Manufacturer" "ROHM Semiconductor"
			(at 0 0 270)
			(unlocked yes)
			(layer "F.Fab")
			(hide yes)
			(effects
				(font
					(size 1 1)
					(thickness 0.15)
				)
			)
		)
		(property "Val" "0R"
			(at 0 0 270)
			(unlocked yes)
			(layer "F.Fab")
			(hide yes)
			(effects
				(font
					(size 1 1)
					(thickness 0.15)
				)
			)
		)
		(property "Max. Curr." "22.4A"
			(at 0 0 270)
			(unlocked yes)
			(layer "F.Fab")
			(hide yes)
			(effects
				(font
					(size 1 1)
					(thickness 0.15)
				)
			)
		)
		(property "Author" "Antmicro"
			(at 0 0 270)
			(unlocked yes)
			(layer "F.Fab")
			(hide yes)
			(effects
				(font
					(size 1 1)
					(thickness 0.15)
				)
			)
		)
		(property "License" "Apache-2.0"
			(at 0 0 270)
			(unlocked yes)
			(layer "F.Fab")
			(hide yes)
			(effects
				(font
					(size 1 1)
					(thickness 0.15)
				)
			)
		)
		(property "Tolerance" "template_tolerance"
			(at 0 0 270)
			(unlocked yes)
			(layer "F.Fab")
			(hide yes)
			(effects
				(font
					(size 1 1)
					(thickness 0.15)
				)
			)
		)
		(sheetname "/Power/")
		(sheetfile "power.kicad_sch")
		(attr smd)
		(fp_line
			(start -0.15 0.4)
			(end 0.15 0.4)
			(stroke
				(width 0.15)
				(type solid)
			)
			(layer "F.SilkS")
		)
		(fp_line
			(start -0.15 -0.4)
			(end 0.15 -0.4)
			(stroke
				(width 0.15)
				(type solid)
			)
			(layer "F.SilkS")
		)
		(fp_rect
			(start -1.25 -0.65)
			(end 1.25 0.65)
			(stroke
				(width 0.05)
				(type solid)
			)
			(fill no)
			(layer "F.CrtYd")
		)
		(fp_rect
			(start -0.8 -0.4)
			(end 0.8 0.4)
			(stroke
				(width 0.15)
				(type solid)
			)
			(fill no)
			(layer "F.Fab")
		)
		(pad "1" smd roundrect
			(at -0.7 0 270)
			(size 0.8 1)
			(layers "F.Cu" "F.Mask" "F.Paste")
			(roundrect_rratio 0.2)
			(net 255 "/Power/+3V3_OUT")
			(pintype "passive")
		)
		(pad "2" smd roundrect
			(at 0.7 0 270)
			(size 0.8 1)
			(layers "F.Cu" "F.Mask" "F.Paste")
			(roundrect_rratio 0.2)
			(net 7 "+3V3")
			(pintype "passive")
		)
	)
	(footprint "antmicro-footprints:C_0603_1608Metric_EIA"
		(layer "F.Cu")
		(at 66.7 89.1 180)
		(descr "Capacitor SMD 0603, IPC-7351 Density Level A")
		(tags "Capacitor 0603")
		(property "Reference" "C125"
			(at 0.98 0.49 0)
			(layer "F.SilkS")
			(effects
				(font
					(size 0.7 0.7)
					(thickness 0.15)
				)
				(justify right top)
			)
		)
		(property "Value" "C_22u_16V_0603"
			(at -1.42757 1.770288 0)
			(layer "F.Fab")
			(hide yes)
			(effects
				(font
					(size 0.7 0.7)
					(thickness 0.15)
				)
				(justify right top)
			)
		)
		(property "Datasheet" "https://product.samsungsem.com/mlcc/CL10A226MO7JZN.do"
			(at 0 0 0)
			(layer "F.Fab")
			(hide yes)
			(effects
				(font
					(size 1.27 1.27)
					(thickness 0.15)
				)
			)
		)
		(property "Description" "SMD Multilayer Ceramic Capacitor"
			(at 0 0 0)
			(layer "F.Fab")
			(hide yes)
			(effects
				(font
					(size 1.27 1.27)
					(thickness 0.15)
				)
			)
		)
		(property "MPN" "CL10A226MO7JZNC"
			(at 0 0 180)
			(unlocked yes)
			(layer "F.Fab")
			(hide yes)
			(effects
				(font
					(size 1 1)
					(thickness 0.15)
				)
			)
		)
		(property "Manufacturer" "Samsung Electro-Mechanics"
			(at 0 0 180)
			(unlocked yes)
			(layer "F.Fab")
			(hide yes)
			(effects
				(font
					(size 1 1)
					(thickness 0.15)
				)
			)
		)
		(property "License" "Apache-2.0"
			(at 0 0 180)
			(unlocked yes)
			(layer "F.Fab")
			(hide yes)
			(effects
				(font
					(size 1 1)
					(thickness 0.15)
				)
			)
		)
		(property "Author" "Antmicro"
			(at 0 0 180)
			(unlocked yes)
			(layer "F.Fab")
			(hide yes)
			(effects
				(font
					(size 1 1)
					(thickness 0.15)
				)
			)
		)
		(property "Val" "22u"
			(at 0 0 180)
			(unlocked yes)
			(layer "F.Fab")
			(hide yes)
			(effects
				(font
					(size 1 1)
					(thickness 0.15)
				)
			)
		)
		(property "Voltage" "16V"
			(at 0 0 180)
			(unlocked yes)
			(layer "F.Fab")
			(hide yes)
			(effects
				(font
					(size 1 1)
					(thickness 0.15)
				)
			)
		)
		(property "Dielectric" ""
			(at 0 0 180)
			(unlocked yes)
			(layer "F.Fab")
			(hide yes)
			(effects
				(font
					(size 1 1)
					(thickness 0.15)
				)
			)
		)
		(sheetname "/X710-AT2 power/")
		(sheetfile "x710-at2-power.kicad_sch")
		(attr smd)
		(fp_line
			(start -0.15 0.55)
			(end 0.15 0.55)
			(stroke
				(width 0.15)
				(type solid)
			)
			(layer "F.SilkS")
		)
		(fp_line
			(start -0.15 -0.55)
			(end 0.15 -0.55)
			(stroke
				(width 0.15)
				(type solid)
			)
			(layer "F.SilkS")
		)
		(fp_rect
			(start -1.25 -0.65)
			(end 1.25 0.65)
			(stroke
				(width 0.05)
				(type solid)
			)
			(fill no)
			(layer "F.CrtYd")
		)
		(fp_rect
			(start -0.8 -0.45)
			(end 0.8 0.45)
			(stroke
				(width 0.15)
				(type solid)
			)
			(fill no)
			(layer "F.Fab")
		)
		(pad "1" smd roundrect
			(at -0.7 0 180)
			(size 0.8 1.1)
			(layers "F.Cu" "F.Mask" "F.Paste")
			(roundrect_rratio 0.2)
			(net 28 "GND")
			(pintype "passive")
		)
		(pad "2" smd roundrect
			(at 0.7 0 180)
			(size 0.8 1.1)
			(layers "F.Cu" "F.Mask" "F.Paste")
			(roundrect_rratio 0.2)
			(net 9 "VCCD")
			(pintype "passive")
		)
	)
	(footprint "antmicro-footprints:TP_SMD_0.75mm"
		(layer "F.Cu")
		(at 52.05 119.150001 180)
		(property "Reference" "TP17"
			(at 0.41 0.26 0)
			(layer "F.SilkS")
			(hide yes)
			(effects
				(font
					(size 0.7 0.7)
					(thickness 0.15)
				)
				(justify right top)
			)
		)
		(property "Value" "TP_0.75mm_SMD"
			(at 0 1.2 0)
			(layer "F.Fab")
			(hide yes)
			(effects
				(font
					(size 0.7 0.7)
					(thickness 0.15)
				)
				(justify right top)
			)
		)
		(property "Description" "SMT test point"
			(at 0 0 0)
			(layer "F.Fab")
			(hide yes)
			(effects
				(font
					(size 1.27 1.27)
					(thickness 0.15)
				)
			)
		)
		(property "MPN" ""
			(at 0 0 180)
			(unlocked yes)
			(layer "F.Fab")
			(hide yes)
			(effects
				(font
					(size 1 1)
					(thickness 0.15)
				)
			)
		)
		(property "Manufacturer" ""
			(at 0 0 180)
			(unlocked yes)
			(layer "F.Fab")
			(hide yes)
			(effects
				(font
					(size 1 1)
					(thickness 0.15)
				)
			)
		)
		(property "Author" "Antmicro"
			(at 0 0 180)
			(unlocked yes)
			(layer "F.Fab")
			(hide yes)
			(effects
				(font
					(size 1 1)
					(thickness 0.15)
				)
			)
		)
		(property "License" "Apache-2.0"
			(at 0 0 180)
			(unlocked yes)
			(layer "F.Fab")
			(hide yes)
			(effects
				(font
					(size 1 1)
					(thickness 0.15)
				)
			)
		)
		(sheetname "/Power/")
		(sheetfile "power.kicad_sch")
		(attr exclude_from_pos_files exclude_from_bom)
		(fp_circle
			(center 0 0)
			(end 0.475 0)
			(stroke
				(width 0.05)
				(type default)
			)
			(fill no)
			(layer "F.CrtYd")
		)
		(pad "1" smd circle
			(at 0 0 180)
			(size 0.75 0.75)
			(layers "F.Cu" "F.Mask")
			(net 311 "/Power/+DVDD_OUT")
			(pinfunction "1")
			(pintype "passive")
		)
	)
	(footprint "antmicro-footprints:C_0603_1608Metric"
		(layer "F.Cu")
		(at 100.45 99.3)
		(descr "Capacitor SMD 0603")
		(tags "capacitor 0603")
		(property "Reference" "C157"
			(at 4.25 0.45 0)
			(layer "F.SilkS")
			(effects
				(font
					(size 0.7 0.7)
					(thickness 0.15)
				)
				(justify left bottom)
			)
		)
		(property "Value" "C_10u_10V_X7R_0603"
			(at -1.42757 1.770288 0)
			(layer "F.Fab")
			(hide yes)
			(effects
				(font
					(size 0.7 0.7)
					(thickness 0.15)
				)
				(justify left bottom)
			)
		)
		(property "Datasheet" "https://www.murata.com/products/productdetail?partno=GRM188Z71A106KA73%23"
			(at 0 0 0)
			(layer "F.Fab")
			(hide yes)
			(effects
				(font
					(size 1.27 1.27)
					(thickness 0.15)
				)
			)
		)
		(property "Description" "SMD Multilayer Ceramic Capacitor,  10µF, 10V, 0603, ±10%, X7R"
			(at 0 0 0)
			(layer "F.Fab")
			(hide yes)
			(effects
				(font
					(size 1.27 1.27)
					(thickness 0.15)
				)
			)
		)
		(property "MPN" "GRM188Z71A106KA73D"
			(at 0 0 0)
			(unlocked yes)
			(layer "F.Fab")
			(hide yes)
			(effects
				(font
					(size 1 1)
					(thickness 0.15)
				)
			)
		)
		(property "Val" "10u"
			(at 0 0 0)
			(unlocked yes)
			(layer "F.Fab")
			(hide yes)
			(effects
				(font
					(size 1 1)
					(thickness 0.15)
				)
			)
		)
		(property "Voltage" "10V"
			(at 0 0 0)
			(unlocked yes)
			(layer "F.Fab")
			(hide yes)
			(effects
				(font
					(size 1 1)
					(thickness 0.15)
				)
			)
		)
		(property "Dielectric" "X7R"
			(at 0 0 0)
			(unlocked yes)
			(layer "F.Fab")
			(hide yes)
			(effects
				(font
					(size 1 1)
					(thickness 0.15)
				)
			)
		)
		(property "Manufacturer" "Murata"
			(at 0 0 0)
			(unlocked yes)
			(layer "F.Fab")
			(hide yes)
			(effects
				(font
					(size 1 1)
					(thickness 0.15)
				)
			)
		)
		(property "License" "Apache-2.0"
			(at 0 0 0)
			(unlocked yes)
			(layer "F.Fab")
			(hide yes)
			(effects
				(font
					(size 1 1)
					(thickness 0.15)
				)
			)
		)
		(property "Author" "Antmicro"
			(at 0 0 0)
			(unlocked yes)
			(layer "F.Fab")
			(hide yes)
			(effects
				(font
					(size 1 1)
					(thickness 0.15)
				)
			)
		)
		(sheetname "/X710-AT2 power/")
		(sheetfile "x710-at2-power.kicad_sch")
		(attr smd)
		(fp_line
			(start -0.15 -0.4)
			(end 0.15 -0.4)
			(stroke
				(width 0.15)
				(type solid)
			)
			(layer "F.SilkS")
		)
		(fp_line
			(start -0.15 0.4)
			(end 0.15 0.4)
			(stroke
				(width 0.15)
				(type solid)
			)
			(layer "F.SilkS")
		)
		(fp_rect
			(start -1.25 -0.65)
			(end 1.25 0.65)
			(stroke
				(width 0.05)
				(type solid)
			)
			(fill no)
			(layer "F.CrtYd")
		)
		(fp_rect
			(start -0.8 -0.4)
			(end 0.8 0.4)
			(stroke
				(width 0.15)
				(type solid)
			)
			(fill no)
			(layer "F.Fab")
		)
		(pad "1" smd roundrect
			(at -0.7 0)
			(size 0.8 1)
			(layers "F.Cu" "F.Mask" "F.Paste")
			(roundrect_rratio 0.2)
			(net 28 "GND")
			(pintype "passive")
		)
		(pad "2" smd roundrect
			(at 0.7 0)
			(size 0.8 1)
			(layers "F.Cu" "F.Mask" "F.Paste")
			(roundrect_rratio 0.2)
			(net 1 "VCCA")
			(pintype "passive")
		)
	)
	(footprint "antmicro-footprints:C_0603_1608Metric_EIA"
		(layer "F.Cu")
		(at 60.649999 99.500001)
		(descr "Capacitor SMD 0603, IPC-7351 Density Level A")
		(tags "Capacitor 0603")
		(property "Reference" "C25"
			(at -3.459999 -0.660001 0)
			(layer "F.SilkS")
			(effects
				(font
					(size 0.7 0.7)
					(thickness 0.15)
				)
				(justify left bottom)
			)
		)
		(property "Value" "C_22u_16V_0603"
			(at -1.42757 1.770288 0)
			(layer "F.Fab")
			(hide yes)
			(effects
				(font
					(size 0.7 0.7)
					(thickness 0.15)
				)
				(justify left bottom)
			)
		)
		(property "Datasheet" "https://product.samsungsem.com/mlcc/CL10A226MO7JZN.do"
			(at 0 0 0)
			(layer "F.Fab")
			(hide yes)
			(effects
				(font
					(size 1.27 1.27)
					(thickness 0.15)
				)
			)
		)
		(property "Description" "SMD Multilayer Ceramic Capacitor"
			(at 0 0 0)
			(layer "F.Fab")
			(hide yes)
			(effects
				(font
					(size 1.27 1.27)
					(thickness 0.15)
				)
			)
		)
		(property "MPN" "CL10A226MO7JZNC"
			(at 0 0 0)
			(unlocked yes)
			(layer "F.Fab")
			(hide yes)
			(effects
				(font
					(size 1 1)
					(thickness 0.15)
				)
			)
		)
		(property "Manufacturer" "Samsung Electro-Mechanics"
			(at 0 0 0)
			(unlocked yes)
			(layer "F.Fab")
			(hide yes)
			(effects
				(font
					(size 1 1)
					(thickness 0.15)
				)
			)
		)
		(property "License" "Apache-2.0"
			(at 0 0 0)
			(unlocked yes)
			(layer "F.Fab")
			(hide yes)
			(effects
				(font
					(size 1 1)
					(thickness 0.15)
				)
			)
		)
		(property "Author" "Antmicro"
			(at 0 0 0)
			(unlocked yes)
			(layer "F.Fab")
			(hide yes)
			(effects
				(font
					(size 1 1)
					(thickness 0.15)
				)
			)
		)
		(property "Val" "22u"
			(at 0 0 0)
			(unlocked yes)
			(layer "F.Fab")
			(hide yes)
			(effects
				(font
					(size 1 1)
					(thickness 0.15)
				)
			)
		)
		(property "Voltage" "16V"
			(at 0 0 0)
			(unlocked yes)
			(layer "F.Fab")
			(hide yes)
			(effects
				(font
					(size 1 1)
					(thickness 0.15)
				)
			)
		)
		(property "Dielectric" ""
			(at 0 0 0)
			(unlocked yes)
			(layer "F.Fab")
			(hide yes)
			(effects
				(font
					(size 1 1)
					(thickness 0.15)
				)
			)
		)
		(property "Public" "False"
			(at 0 0 0)
			(unlocked yes)
			(layer "F.Fab")
			(hide yes)
			(effects
				(font
					(size 1 1)
					(thickness 0.15)
				)
			)
		)
		(sheetname "/Power/")
		(sheetfile "power.kicad_sch")
		(attr smd)
		(fp_line
			(start -0.15 -0.55)
			(end 0.15 -0.55)
			(stroke
				(width 0.15)
				(type solid)
			)
			(layer "F.SilkS")
		)
		(fp_line
			(start -0.15 0.55)
			(end 0.15 0.55)
			(stroke
				(width 0.15)
				(type solid)
			)
			(layer "F.SilkS")
		)
		(fp_rect
			(start -1.25 -0.65)
			(end 1.25 0.65)
			(stroke
				(width 0.05)
				(type solid)
			)
			(fill no)
			(layer "F.CrtYd")
		)
		(fp_rect
			(start -0.8 -0.45)
			(end 0.8 0.45)
			(stroke
				(width 0.15)
				(type solid)
			)
			(fill no)
			(layer "F.Fab")
		)
		(pad "1" smd roundrect
			(at -0.7 0)
			(size 0.8 1.1)
			(layers "F.Cu" "F.Mask" "F.Paste")
			(roundrect_rratio 0.2)
			(net 28 "GND")
			(pintype "passive")
		)
		(pad "2" smd roundrect
			(at 0.7 0)
			(size 0.8 1.1)
			(layers "F.Cu" "F.Mask" "F.Paste")
			(roundrect_rratio 0.2)
			(net 310 "/Power/+1V88_OUT")
			(pintype "passive")
		)
	)
	(footprint "antmicro-footprints:R_0402_1005Metric"
		(layer "F.Cu")
		(at 99.349999 108.1 180)
		(descr "Resistor SMD 0402")
		(tags "resistor SMD 0402")
		(property "Reference" "R42"
			(at 1.249999 -15.625 0)
			(layer "F.SilkS")
			(effects
				(font
					(size 0.7 0.7)
					(thickness 0.15)
				)
				(justify left bottom)
			)
		)
		(property "Value" "R_22R_0402"
			(at -1.011843 1.772046 0)
			(layer "F.Fab")
			(hide yes)
			(effects
				(font
					(size 0.7 0.7)
					(thickness 0.15)
				)
				(justify right top)
			)
		)
		(property "Datasheet" "https://www.bourns.com/docs/product-datasheets/cr.pdf"
			(at 0 0 0)
			(layer "F.Fab")
			(hide yes)
			(effects
				(font
					(size 1.27 1.27)
					(thickness 0.15)
				)
			)
		)
		(property "Description" "SMD Chip Resistor, 22 ohm, ± 1%, 62.5 mW, 0402 [1005 Metric], Thick Film, General Purpose"
			(at 0 0 0)
			(layer "F.Fab")
			(hide yes)
			(effects
				(font
					(size 1.27 1.27)
					(thickness 0.15)
				)
			)
		)
		(property "MPN" "CR0402-FX-22R0GLF"
			(at 0 0 180)
			(unlocked yes)
			(layer "F.Fab")
			(hide yes)
			(effects
				(font
					(size 1 1)
					(thickness 0.15)
				)
			)
		)
		(property "Manufacturer" "Bourns"
			(at 0 0 180)
			(unlocked yes)
			(layer "F.Fab")
			(hide yes)
			(effects
				(font
					(size 1 1)
					(thickness 0.15)
				)
			)
		)
		(property "License" "Apache-2.0"
			(at 0 0 180)
			(unlocked yes)
			(layer "F.Fab")
			(hide yes)
			(effects
				(font
					(size 1 1)
					(thickness 0.15)
				)
			)
		)
		(property "Author" "Antmicro"
			(at 0 0 180)
			(unlocked yes)
			(layer "F.Fab")
			(hide yes)
			(effects
				(font
					(size 1 1)
					(thickness 0.15)
				)
			)
		)
		(property "Val" "22R"
			(at 0 0 180)
			(unlocked yes)
			(layer "F.Fab")
			(hide yes)
			(effects
				(font
					(size 1 1)
					(thickness 0.15)
				)
			)
		)
		(property "Tolerance" "1%"
			(at 0 0 180)
			(unlocked yes)
			(layer "F.Fab")
			(hide yes)
			(effects
				(font
					(size 1 1)
					(thickness 0.15)
				)
			)
		)
		(sheetname "/X710-AT2 10GbE/")
		(sheetfile "x710-at2-10gbe.kicad_sch")
		(attr smd)
		(fp_rect
			(start -0.925 -0.47)
			(end 0.925 0.47)
			(stroke
				(width 0.05)
				(type default)
			)
			(fill no)
			(layer "F.CrtYd")
		)
		(fp_rect
			(start -0.5 -0.25)
			(end 0.5 0.25)
			(stroke
				(width 0.15)
				(type solid)
			)
			(fill no)
			(layer "F.Fab")
		)
		(pad "1" smd roundrect
			(at -0.48 0 180)
			(size 0.59 0.64)
			(layers "F.Cu" "F.Mask" "F.Paste")
			(roundrect_rratio 0.25)
			(net 143 "/X710-AT2 10GbE/25MHZ_OSC_R.+")
			(pintype "passive")
		)
		(pad "2" smd roundrect
			(at 0.48 0 180)
			(size 0.59 0.64)
			(layers "F.Cu" "F.Mask" "F.Paste")
			(roundrect_rratio 0.25)
			(net 30 "/X710-AT2 10GbE/25MHZ_OSC_AC.+")
			(pintype "passive")
		)
	)
	(footprint "antmicro-footprints:SOD-523"
		(layer "F.Cu")
		(at 79.96 57.771999 180)
		(property "Reference" "D10"
			(at -1.09 -1.678001 0)
			(layer "F.SilkS")
			(effects
				(font
					(size 0.7 0.7)
					(thickness 0.15)
				)
				(justify right top)
			)
		)
		(property "Value" "PESD5Z5_0F"
			(at 0 1.499 0)
			(layer "F.Fab")
			(hide yes)
			(effects
				(font
					(size 0.7 0.7)
					(thickness 0.15)
				)
				(justify right top)
			)
		)
		(property "Datasheet" "https://assets.nexperia.com/documents/data-sheet/PESD5Z5_0.pdf"
			(at 0 0 0)
			(layer "F.Fab")
			(hide yes)
			(effects
				(font
					(size 1.27 1.27)
					(thickness 0.15)
				)
			)
		)
		(property "Description" "Unidirectional TVS, 30 kV,  SOD-523, 5 V, 89 pF"
			(at 0 0 0)
			(layer "F.Fab")
			(hide yes)
			(effects
				(font
					(size 1.27 1.27)
					(thickness 0.15)
				)
			)
		)
		(property "Manufacturer" "Nexperia"
			(at 0 0 180)
			(unlocked yes)
			(layer "F.Fab")
			(hide yes)
			(effects
				(font
					(size 1 1)
					(thickness 0.15)
				)
			)
		)
		(property "MPN" "PESD5Z5.0F"
			(at 0 0 180)
			(unlocked yes)
			(layer "F.Fab")
			(hide yes)
			(effects
				(font
					(size 1 1)
					(thickness 0.15)
				)
			)
		)
		(property "Author" "Antmicro"
			(at 0 0 180)
			(unlocked yes)
			(layer "F.Fab")
			(hide yes)
			(effects
				(font
					(size 1 1)
					(thickness 0.15)
				)
			)
		)
		(property "License" "Apache-2.0"
			(at 0 0 180)
			(unlocked yes)
			(layer "F.Fab")
			(hide yes)
			(effects
				(font
					(size 1 1)
					(thickness 0.15)
				)
			)
		)
		(sheetname "/Power/")
		(sheetfile "power.kicad_sch")
		(attr smd)
		(fp_line
			(start -0.35 -0.5)
			(end -0.35 0.5)
			(stroke
				(width 0.15)
				(type solid)
			)
			(layer "F.SilkS")
		)
		(fp_rect
			(start -1 -0.6)
			(end 1 0.6)
			(stroke
				(width 0.05)
				(type solid)
			)
			(fill no)
			(layer "F.CrtYd")
		)
		(fp_line
			(start 0.65 -0.425)
			(end 0.65 0.423)
			(stroke
				(width 0.15)
				(type solid)
			)
			(layer "F.Fab")
		)
		(fp_line
			(start -0.35 -0.4)
			(end -0.35 0.4)
			(stroke
				(width 0.15)
				(type solid)
			)
			(layer "F.Fab")
		)
		(fp_line
			(start -0.652 0.423)
			(end 0.65 0.423)
			(stroke
				(width 0.15)
				(type solid)
			)
			(layer "F.Fab")
		)
		(fp_line
			(start -0.652 0.423)
			(end -0.652 -0.425)
			(stroke
				(width 0.15)
				(type solid)
			)
			(layer "F.Fab")
		)
		(fp_line
			(start -0.652 -0.425)
			(end 0.65 -0.425)
			(stroke
				(width 0.15)
				(type solid)
			)
			(layer "F.Fab")
		)
		(pad "1" smd roundrect
			(at -0.701 0 180)
			(size 0.5 0.6)
			(layers "F.Cu" "F.Mask" "F.Paste")
			(roundrect_rratio 0.25)
			(net 351 "/Power/+5V_USB")
			(pinfunction "C")
			(pintype "passive")
		)
		(pad "2" smd roundrect
			(at 0.699 0 180)
			(size 0.5 0.6)
			(layers "F.Cu" "F.Mask" "F.Paste")
			(roundrect_rratio 0.25)
			(net 28 "GND")
			(pinfunction "A")
			(pintype "passive")
		)
	)
	(footprint "antmicro-footprints:C_0603_1608Metric"
		(layer "F.Cu")
		(at 97.9 100.65 180)
		(descr "Capacitor SMD 0603")
		(tags "capacitor 0603")
		(property "Reference" "C148"
			(at -3.75 0.35 0)
			(layer "F.SilkS")
			(effects
				(font
					(size 0.7 0.7)
					(thickness 0.15)
				)
				(justify left top)
			)
		)
		(property "Value" "C_10u_10V_X7R_0603"
			(at -1.42757 1.770288 0)
			(layer "F.Fab")
			(hide yes)
			(effects
				(font
					(size 0.7 0.7)
					(thickness 0.15)
				)
				(justify right top)
			)
		)
		(property "Datasheet" "https://www.murata.com/products/productdetail?partno=GRM188Z71A106KA73%23"
			(at 0 0 0)
			(layer "F.Fab")
			(hide yes)
			(effects
				(font
					(size 1.27 1.27)
					(thickness 0.15)
				)
			)
		)
		(property "Description" "SMD Multilayer Ceramic Capacitor,  10µF, 10V, 0603, ±10%, X7R"
			(at 0 0 0)
			(layer "F.Fab")
			(hide yes)
			(effects
				(font
					(size 1.27 1.27)
					(thickness 0.15)
				)
			)
		)
		(property "MPN" "GRM188Z71A106KA73D"
			(at 0 0 180)
			(unlocked yes)
			(layer "F.Fab")
			(hide yes)
			(effects
				(font
					(size 1 1)
					(thickness 0.15)
				)
			)
		)
		(property "Val" "10u"
			(at 0 0 180)
			(unlocked yes)
			(layer "F.Fab")
			(hide yes)
			(effects
				(font
					(size 1 1)
					(thickness 0.15)
				)
			)
		)
		(property "Voltage" "10V"
			(at 0 0 180)
			(unlocked yes)
			(layer "F.Fab")
			(hide yes)
			(effects
				(font
					(size 1 1)
					(thickness 0.15)
				)
			)
		)
		(property "Dielectric" "X7R"
			(at 0 0 180)
			(unlocked yes)
			(layer "F.Fab")
			(hide yes)
			(effects
				(font
					(size 1 1)
					(thickness 0.15)
				)
			)
		)
		(property "Manufacturer" "Murata"
			(at 0 0 180)
			(unlocked yes)
			(layer "F.Fab")
			(hide yes)
			(effects
				(font
					(size 1 1)
					(thickness 0.15)
				)
			)
		)
		(property "License" "Apache-2.0"
			(at 0 0 180)
			(unlocked yes)
			(layer "F.Fab")
			(hide yes)
			(effects
				(font
					(size 1 1)
					(thickness 0.15)
				)
			)
		)
		(property "Author" "Antmicro"
			(at 0 0 180)
			(unlocked yes)
			(layer "F.Fab")
			(hide yes)
			(effects
				(font
					(size 1 1)
					(thickness 0.15)
				)
			)
		)
		(sheetname "/X710-AT2 power/")
		(sheetfile "x710-at2-power.kicad_sch")
		(attr smd)
		(fp_line
			(start -0.15 0.4)
			(end 0.15 0.4)
			(stroke
				(width 0.15)
				(type solid)
			)
			(layer "F.SilkS")
		)
		(fp_line
			(start -0.15 -0.4)
			(end 0.15 -0.4)
			(stroke
				(width 0.15)
				(type solid)
			)
			(layer "F.SilkS")
		)
		(fp_rect
			(start -1.25 -0.65)
			(end 1.25 0.65)
			(stroke
				(width 0.05)
				(type solid)
			)
			(fill no)
			(layer "F.CrtYd")
		)
		(fp_rect
			(start -0.8 -0.4)
			(end 0.8 0.4)
			(stroke
				(width 0.15)
				(type solid)
			)
			(fill no)
			(layer "F.Fab")
		)
		(pad "1" smd roundrect
			(at -0.7 0 180)
			(size 0.8 1)
			(layers "F.Cu" "F.Mask" "F.Paste")
			(roundrect_rratio 0.2)
			(net 28 "GND")
			(pintype "passive")
		)
		(pad "2" smd roundrect
			(at 0.7 0 180)
			(size 0.8 1)
			(layers "F.Cu" "F.Mask" "F.Paste")
			(roundrect_rratio 0.2)
			(net 7 "+3V3")
			(pintype "passive")
		)
	)
	(footprint "antmicro-footprints:C_0402_1005Metric"
		(layer "F.Cu")
		(at 73.849999 81.039994 180)
		(descr "Capacitor SMD 0402")
		(tags "capacitor SMD 0402")
		(property "Reference" "C6"
			(at 2.349999 8.089994 0)
			(layer "F.SilkS")
			(effects
				(font
					(size 0.7 0.7)
					(thickness 0.15)
				)
				(justify right top)
			)
		)
		(property "Value" "C_1u_25V_0402"
			(at -1.022927 2.155213 0)
			(layer "F.Fab")
			(hide yes)
			(effects
				(font
					(size 0.7 0.7)
					(thickness 0.15)
				)
				(justify right top)
			)
		)
		(property "Datasheet" "https://www.murata.com/products/productdetail?partno=GRM155R61E105KE11%23"
			(at 0 0 0)
			(layer "F.Fab")
			(hide yes)
			(effects
				(font
					(size 1.27 1.27)
					(thickness 0.15)
				)
			)
		)
		(property "Description" "SMD Multilayer Ceramic Capacitor, 1 µF, 25 V, 0402 [1005 Metric], ± 10%, X5R, GRM Series"
			(at 0 0 0)
			(layer "F.Fab")
			(hide yes)
			(effects
				(font
					(size 1.27 1.27)
					(thickness 0.15)
				)
			)
		)
		(property "MPN" "GRM155R61E105KE11J"
			(at 0 0 180)
			(unlocked yes)
			(layer "F.Fab")
			(hide yes)
			(effects
				(font
					(size 1 1)
					(thickness 0.15)
				)
			)
		)
		(property "Manufacturer" "Murata"
			(at 0 0 180)
			(unlocked yes)
			(layer "F.Fab")
			(hide yes)
			(effects
				(font
					(size 1 1)
					(thickness 0.15)
				)
			)
		)
		(property "License" "Apache-2.0"
			(at 0 0 180)
			(unlocked yes)
			(layer "F.Fab")
			(hide yes)
			(effects
				(font
					(size 1 1)
					(thickness 0.15)
				)
			)
		)
		(property "Author" "Antmicro"
			(at 0 0 180)
			(unlocked yes)
			(layer "F.Fab")
			(hide yes)
			(effects
				(font
					(size 1 1)
					(thickness 0.15)
				)
			)
		)
		(property "Val" "1u"
			(at 0 0 180)
			(unlocked yes)
			(layer "F.Fab")
			(hide yes)
			(effects
				(font
					(size 1 1)
					(thickness 0.15)
				)
			)
		)
		(property "Voltage" "25V"
			(at 0 0 180)
			(unlocked yes)
			(layer "F.Fab")
			(hide yes)
			(effects
				(font
					(size 1 1)
					(thickness 0.15)
				)
			)
		)
		(property "Dielectric" "X5R"
			(at 0 0 180)
			(unlocked yes)
			(layer "F.Fab")
			(hide yes)
			(effects
				(font
					(size 1 1)
					(thickness 0.15)
				)
			)
		)
		(sheetname "/Power/")
		(sheetfile "power.kicad_sch")
		(attr smd)
		(fp_rect
			(start -0.925 -0.47)
			(end 0.925 0.47)
			(stroke
				(width 0.05)
				(type default)
			)
			(fill no)
			(layer "F.CrtYd")
		)
		(fp_line
			(start 0.504 0.248)
			(end -0.494 0.248)
			(stroke
				(width 0.15)
				(type solid)
			)
			(layer "F.Fab")
		)
		(fp_line
			(start 0.504 -0.25)
			(end 0.504 0.248)
			(stroke
				(width 0.15)
				(type solid)
			)
			(layer "F.Fab")
		)
		(fp_line
			(start -0.494 0.248)
			(end -0.494 -0.25)
			(stroke
				(width 0.15)
				(type solid)
			)
			(layer "F.Fab")
		)
		(fp_line
			(start -0.494 -0.25)
			(end 0.504 -0.25)
			(stroke
				(width 0.15)
				(type solid)
			)
			(layer "F.Fab")
		)
		(pad "1" smd roundrect
			(at -0.48 0 180)
			(size 0.59 0.64)
			(layers "F.Cu" "F.Mask" "F.Paste")
			(roundrect_rratio 0.25)
			(net 28 "GND")
			(pintype "passive")
		)
		(pad "2" smd roundrect
			(at 0.48 0 180)
			(size 0.59 0.64)
			(layers "F.Cu" "F.Mask" "F.Paste")
			(roundrect_rratio 0.25)
			(net 315 "/Power/3V3_VCC")
			(pintype "passive")
		)
	)
	(footprint "antmicro-footprints:R_0402_1005Metric"
		(layer "F.Cu")
		(at 111.15 106.55 90)
		(descr "Resistor SMD 0402")
		(tags "resistor SMD 0402")
		(property "Reference" "R176"
			(at -0.1 -2.55 90)
			(layer "F.SilkS")
			(effects
				(font
					(size 0.7 0.7)
					(thickness 0.15)
				)
				(justify left bottom)
			)
		)
		(property "Value" "R_0R_0402"
			(at -1.011843 1.772046 90)
			(layer "F.Fab")
			(hide yes)
			(effects
				(font
					(size 0.7 0.7)
					(thickness 0.15)
				)
				(justify left bottom)
			)
		)
		(property "Datasheet" "https://industrial.panasonic.com/cdbs/www-data/pdf/RDA0000/AOA0000C301.pdf"
			(at 0 0 90)
			(layer "F.Fab")
			(hide yes)
			(effects
				(font
					(size 1.27 1.27)
					(thickness 0.15)
				)
			)
		)
		(property "Description" "SMD Chip Resistor, Jumper, 0 ohm, 100 mW, 0402 [1005 Metric], Thick Film, General Purpose"
			(at 0 0 90)
			(layer "F.Fab")
			(hide yes)
			(effects
				(font
					(size 1.27 1.27)
					(thickness 0.15)
				)
			)
		)
		(property "MPN" "ERJ2GE0R00X"
			(at 0 0 90)
			(unlocked yes)
			(layer "F.Fab")
			(hide yes)
			(effects
				(font
					(size 1 1)
					(thickness 0.15)
				)
			)
		)
		(property "Manufacturer" "Panasonic"
			(at 0 0 90)
			(unlocked yes)
			(layer "F.Fab")
			(hide yes)
			(effects
				(font
					(size 1 1)
					(thickness 0.15)
				)
			)
		)
		(property "License" "Apache-2.0"
			(at 0 0 90)
			(unlocked yes)
			(layer "F.Fab")
			(hide yes)
			(effects
				(font
					(size 1 1)
					(thickness 0.15)
				)
			)
		)
		(property "Author" "Antmicro"
			(at 0 0 90)
			(unlocked yes)
			(layer "F.Fab")
			(hide yes)
			(effects
				(font
					(size 1 1)
					(thickness 0.15)
				)
			)
		)
		(property "Val" "0R"
			(at 0 0 90)
			(unlocked yes)
			(layer "F.Fab")
			(hide yes)
			(effects
				(font
					(size 1 1)
					(thickness 0.15)
				)
			)
		)
		(property "Tolerance" "~"
			(at 0 0 90)
			(unlocked yes)
			(layer "F.Fab")
			(hide yes)
			(effects
				(font
					(size 1 1)
					(thickness 0.15)
				)
			)
		)
		(property "Current" "1A"
			(at 0 0 90)
			(unlocked yes)
			(layer "F.Fab")
			(hide yes)
			(effects
				(font
					(size 1 1)
					(thickness 0.15)
				)
			)
		)
		(sheetname "/Fan controller/")
		(sheetfile "fan-controller.kicad_sch")
		(attr smd exclude_from_pos_files exclude_from_bom dnp)
		(fp_rect
			(start -0.925 -0.47)
			(end 0.925 0.47)
			(stroke
				(width 0.05)
				(type default)
			)
			(fill no)
			(layer "F.CrtYd")
		)
		(fp_rect
			(start -0.5 -0.25)
			(end 0.5 0.25)
			(stroke
				(width 0.15)
				(type solid)
			)
			(fill no)
			(layer "F.Fab")
		)
		(pad "1" smd roundrect
			(at -0.48 0 90)
			(size 0.59 0.64)
			(layers "F.Cu" "F.Mask" "F.Paste")
			(roundrect_rratio 0.25)
			(net 28 "GND")
			(pintype "passive")
		)
		(pad "2" smd roundrect
			(at 0.48 0 90)
			(size 0.59 0.64)
			(layers "F.Cu" "F.Mask" "F.Paste")
			(roundrect_rratio 0.25)
			(net 398 "/Fan controller/D0")
			(pintype "passive")
		)
	)
	(footprint "antmicro-footprints:MP_Pad6mm_Drill3.2mm"
		(layer "F.Cu")
		(at 56.75 54.250001)
		(property "Reference" "MP4"
			(at -3.8 -2.900001 0)
			(layer "F.SilkS")
			(hide yes)
			(effects
				(font
					(size 0.7 0.7)
					(thickness 0.15)
				)
				(justify left bottom)
			)
		)
		(property "Value" "MP_Pad6mm_Drill3.2mm"
			(at 0 3.9 0)
			(layer "F.Fab")
			(hide yes)
			(effects
				(font
					(size 0.7 0.7)
					(thickness 0.15)
				)
				(justify left bottom)
			)
		)
		(property "Description" "Mechanical part"
			(at 0 0 0)
			(layer "F.Fab")
			(hide yes)
			(effects
				(font
					(size 1.27 1.27)
					(thickness 0.15)
				)
			)
		)
		(property "Author" "Antmicro"
			(at 0 0 0)
			(unlocked yes)
			(layer "F.Fab")
			(hide yes)
			(effects
				(font
					(size 1 1)
					(thickness 0.15)
				)
			)
		)
		(property "License" "Apache-2.0"
			(at 0 0 0)
			(unlocked yes)
			(layer "F.Fab")
			(hide yes)
			(effects
				(font
					(size 1 1)
					(thickness 0.15)
				)
			)
		)
		(sheetname "/")
		(sheetfile "oculink-to-10gbe-adapter.kicad_sch")
		(attr exclude_from_pos_files exclude_from_bom)
		(fp_circle
			(center 0 0)
			(end 3.25 0)
			(stroke
				(width 0.05)
				(type default)
			)
			(fill no)
			(layer "F.CrtYd")
		)
		(pad "1" thru_hole circle
			(at 0 0)
			(size 6 6)
			(drill 3.2)
			(layers "*.Cu" "*.Mask")
			(remove_unused_layers no)
			(net 28 "GND")
			(pintype "passive")
		)
	)
	(footprint "antmicro-footprints:SOD-523"
		(layer "F.Cu")
		(at 111.325 108.405 180)
		(property "Reference" "D13"
			(at -1.125 -0.695 0)
			(layer "F.SilkS")
			(effects
				(font
					(size 0.7 0.7)
					(thickness 0.15)
				)
				(justify right top)
			)
		)
		(property "Value" "PESD5Z5_0F"
			(at 0 1.499 0)
			(layer "F.Fab")
			(hide yes)
			(effects
				(font
					(size 0.7 0.7)
					(thickness 0.15)
				)
				(justify right top)
			)
		)
		(property "Datasheet" "https://assets.nexperia.com/documents/data-sheet/PESD5Z5_0.pdf"
			(at 0 0 0)
			(layer "F.Fab")
			(hide yes)
			(effects
				(font
					(size 1.27 1.27)
					(thickness 0.15)
				)
			)
		)
		(property "Description" "Unidirectional TVS, 30 kV,  SOD-523, 5 V, 89 pF"
			(at 0 0 0)
			(layer "F.Fab")
			(hide yes)
			(effects
				(font
					(size 1.27 1.27)
					(thickness 0.15)
				)
			)
		)
		(property "Manufacturer" "Nexperia"
			(at 0 0 180)
			(unlocked yes)
			(layer "F.Fab")
			(hide yes)
			(effects
				(font
					(size 1 1)
					(thickness 0.15)
				)
			)
		)
		(property "MPN" "PESD5Z5.0F"
			(at 0 0 180)
			(unlocked yes)
			(layer "F.Fab")
			(hide yes)
			(effects
				(font
					(size 1 1)
					(thickness 0.15)
				)
			)
		)
		(property "Author" "Antmicro"
			(at 0 0 180)
			(unlocked yes)
			(layer "F.Fab")
			(hide yes)
			(effects
				(font
					(size 1 1)
					(thickness 0.15)
				)
			)
		)
		(property "License" "Apache-2.0"
			(at 0 0 180)
			(unlocked yes)
			(layer "F.Fab")
			(hide yes)
			(effects
				(font
					(size 1 1)
					(thickness 0.15)
				)
			)
		)
		(sheetname "/Fan controller/")
		(sheetfile "fan-controller.kicad_sch")
		(attr smd exclude_from_pos_files exclude_from_bom dnp)
		(fp_line
			(start -0.35 -0.5)
			(end -0.35 0.5)
			(stroke
				(width 0.15)
				(type solid)
			)
			(layer "F.SilkS")
		)
		(fp_rect
			(start -1 -0.6)
			(end 1 0.6)
			(stroke
				(width 0.05)
				(type solid)
			)
			(fill no)
			(layer "F.CrtYd")
		)
		(fp_line
			(start 0.65 -0.425)
			(end 0.65 0.423)
			(stroke
				(width 0.15)
				(type solid)
			)
			(layer "F.Fab")
		)
		(fp_line
			(start -0.35 -0.4)
			(end -0.35 0.4)
			(stroke
				(width 0.15)
				(type solid)
			)
			(layer "F.Fab")
		)
		(fp_line
			(start -0.652 0.423)
			(end 0.65 0.423)
			(stroke
				(width 0.15)
				(type solid)
			)
			(layer "F.Fab")
		)
		(fp_line
			(start -0.652 0.423)
			(end -0.652 -0.425)
			(stroke
				(width 0.15)
				(type solid)
			)
			(layer "F.Fab")
		)
		(fp_line
			(start -0.652 -0.425)
			(end 0.65 -0.425)
			(stroke
				(width 0.15)
				(type solid)
			)
			(layer "F.Fab")
		)
		(pad "1" smd roundrect
			(at -0.701 0 180)
			(size 0.5 0.6)
			(layers "F.Cu" "F.Mask" "F.Paste")
			(roundrect_rratio 0.25)
			(net 390 "/Fan controller/PWM")
			(pinfunction "C")
			(pintype "passive")
		)
		(pad "2" smd roundrect
			(at 0.699 0 180)
			(size 0.5 0.6)
			(layers "F.Cu" "F.Mask" "F.Paste")
			(roundrect_rratio 0.25)
			(net 28 "GND")
			(pinfunction "A")
			(pintype "passive")
		)
	)
	(footprint "antmicro-footprints:C_0603_1608Metric_EIA"
		(layer "F.Cu")
		(at 66.7 93.399999 180)
		(descr "Capacitor SMD 0603, IPC-7351 Density Level A")
		(tags "Capacitor 0603")
		(property "Reference" "C79"
			(at -3.26 0.349999 0)
			(layer "F.SilkS")
			(effects
				(font
					(size 0.7 0.7)
					(thickness 0.15)
				)
				(justify right top)
			)
		)
		(property "Value" "C_22u_16V_0603"
			(at -1.42757 1.770288 0)
			(layer "F.Fab")
			(hide yes)
			(effects
				(font
					(size 0.7 0.7)
					(thickness 0.15)
				)
				(justify right top)
			)
		)
		(property "Datasheet" "https://product.samsungsem.com/mlcc/CL10A226MO7JZN.do"
			(at 0 0 0)
			(layer "F.Fab")
			(hide yes)
			(effects
				(font
					(size 1.27 1.27)
					(thickness 0.15)
				)
			)
		)
		(property "Description" "SMD Multilayer Ceramic Capacitor"
			(at 0 0 0)
			(layer "F.Fab")
			(hide yes)
			(effects
				(font
					(size 1.27 1.27)
					(thickness 0.15)
				)
			)
		)
		(property "MPN" "CL10A226MO7JZNC"
			(at 0 0 180)
			(unlocked yes)
			(layer "F.Fab")
			(hide yes)
			(effects
				(font
					(size 1 1)
					(thickness 0.15)
				)
			)
		)
		(property "Manufacturer" "Samsung Electro-Mechanics"
			(at 0 0 180)
			(unlocked yes)
			(layer "F.Fab")
			(hide yes)
			(effects
				(font
					(size 1 1)
					(thickness 0.15)
				)
			)
		)
		(property "License" "Apache-2.0"
			(at 0 0 180)
			(unlocked yes)
			(layer "F.Fab")
			(hide yes)
			(effects
				(font
					(size 1 1)
					(thickness 0.15)
				)
			)
		)
		(property "Author" "Antmicro"
			(at 0 0 180)
			(unlocked yes)
			(layer "F.Fab")
			(hide yes)
			(effects
				(font
					(size 1 1)
					(thickness 0.15)
				)
			)
		)
		(property "Val" "22u"
			(at 0 0 180)
			(unlocked yes)
			(layer "F.Fab")
			(hide yes)
			(effects
				(font
					(size 1 1)
					(thickness 0.15)
				)
			)
		)
		(property "Voltage" "16V"
			(at 0 0 180)
			(unlocked yes)
			(layer "F.Fab")
			(hide yes)
			(effects
				(font
					(size 1 1)
					(thickness 0.15)
				)
			)
		)
		(property "Dielectric" ""
			(at 0 0 180)
			(unlocked yes)
			(layer "F.Fab")
			(hide yes)
			(effects
				(font
					(size 1 1)
					(thickness 0.15)
				)
			)
		)
		(sheetname "/X710-AT2 power/")
		(sheetfile "x710-at2-power.kicad_sch")
		(attr smd)
		(fp_line
			(start -0.15 0.55)
			(end 0.15 0.55)
			(stroke
				(width 0.15)
				(type solid)
			)
			(layer "F.SilkS")
		)
		(fp_line
			(start -0.15 -0.55)
			(end 0.15 -0.55)
			(stroke
				(width 0.15)
				(type solid)
			)
			(layer "F.SilkS")
		)
		(fp_rect
			(start -1.25 -0.65)
			(end 1.25 0.65)
			(stroke
				(width 0.05)
				(type solid)
			)
			(fill no)
			(layer "F.CrtYd")
		)
		(fp_rect
			(start -0.8 -0.45)
			(end 0.8 0.45)
			(stroke
				(width 0.15)
				(type solid)
			)
			(fill no)
			(layer "F.Fab")
		)
		(pad "1" smd roundrect
			(at -0.7 0 180)
			(size 0.8 1.1)
			(layers "F.Cu" "F.Mask" "F.Paste")
			(roundrect_rratio 0.2)
			(net 28 "GND")
			(pintype "passive")
		)
		(pad "2" smd roundrect
			(at 0.7 0 180)
			(size 0.8 1.1)
			(layers "F.Cu" "F.Mask" "F.Paste")
			(roundrect_rratio 0.2)
			(net 6 "DVDD")
			(pintype "passive")
		)
	)
	(footprint "antmicro-footprints:C_0805_2012Metric"
		(layer "F.Cu")
		(at 69.45 114.3 90)
		(descr "Capacitor SMD 0805")
		(tags "capacitor SMD 0805")
		(property "Reference" "C173"
			(at -2.4 5.33 90)
			(layer "F.SilkS")
			(effects
				(font
					(size 0.7 0.7)
					(thickness 0.15)
				)
				(justify left bottom)
			)
		)
		(property "Value" "C_100u_0805"
			(at -2.055717 1.963153 90)
			(layer "F.Fab")
			(hide yes)
			(effects
				(font
					(size 0.7 0.7)
					(thickness 0.15)
				)
				(justify left bottom)
			)
		)
		(property "Datasheet" "https://www.murata.com/products/productdetail?partno=GRM21BR60J107ME15%23"
			(at 0 0 90)
			(layer "F.Fab")
			(hide yes)
			(effects
				(font
					(size 1.27 1.27)
					(thickness 0.15)
				)
			)
		)
		(property "Description" "SMD Multilayer Ceramic Capacitor, 100 µF, 6.3 V, 0805 [2012 Metric], ± 20%, X5R, GRM Series"
			(at 0 0 90)
			(layer "F.Fab")
			(hide yes)
			(effects
				(font
					(size 1.27 1.27)
					(thickness 0.15)
				)
			)
		)
		(property "MPN" "GRM21BR60J107ME15L"
			(at 0 0 90)
			(unlocked yes)
			(layer "F.Fab")
			(hide yes)
			(effects
				(font
					(size 1 1)
					(thickness 0.15)
				)
			)
		)
		(property "Manufacturer" "Murata"
			(at 0 0 90)
			(unlocked yes)
			(layer "F.Fab")
			(hide yes)
			(effects
				(font
					(size 1 1)
					(thickness 0.15)
				)
			)
		)
		(property "License" "Apache-2.0"
			(at 0 0 90)
			(unlocked yes)
			(layer "F.Fab")
			(hide yes)
			(effects
				(font
					(size 1 1)
					(thickness 0.15)
				)
			)
		)
		(property "Author" "Antmicro"
			(at 0 0 90)
			(unlocked yes)
			(layer "F.Fab")
			(hide yes)
			(effects
				(font
					(size 1 1)
					(thickness 0.15)
				)
			)
		)
		(property "Val" "100u"
			(at 0 0 90)
			(unlocked yes)
			(layer "F.Fab")
			(hide yes)
			(effects
				(font
					(size 1 1)
					(thickness 0.15)
				)
			)
		)
		(property "Voltage" ""
			(at 0 0 90)
			(unlocked yes)
			(layer "F.Fab")
			(hide yes)
			(effects
				(font
					(size 1 1)
					(thickness 0.15)
				)
			)
		)
		(property "Dielectric" ""
			(at 0 0 90)
			(unlocked yes)
			(layer "F.Fab")
			(hide yes)
			(effects
				(font
					(size 1 1)
					(thickness 0.15)
				)
			)
		)
		(property "Public" "False"
			(at 0 0 90)
			(unlocked yes)
			(layer "F.Fab")
			(hide yes)
			(effects
				(font
					(size 1 1)
					(thickness 0.15)
				)
			)
		)
		(sheetname "/X710-AT2 power/")
		(sheetfile "x710-at2-power.kicad_sch")
		(attr smd)
		(fp_line
			(start -0.3 -0.7)
			(end 0.3 -0.7)
			(stroke
				(width 0.15)
				(type solid)
			)
			(layer "F.SilkS")
		)
		(fp_line
			(start -0.3 0.7)
			(end 0.3 0.7)
			(stroke
				(width 0.15)
				(type solid)
			)
			(layer "F.SilkS")
		)
		(fp_rect
			(start 1.95 -0.9)
			(end -1.95 0.9)
			(stroke
				(width 0.05)
				(type default)
			)
			(fill no)
			(layer "F.CrtYd")
		)
		(fp_rect
			(start -0.95 -0.675)
			(end 0.95 0.675)
			(stroke
				(width 0.15)
				(type solid)
			)
			(fill no)
			(layer "F.Fab")
		)
		(pad "1" smd roundrect
			(at -1.1 0 90)
			(size 1.2 1.3)
			(layers "F.Cu" "F.Mask" "F.Paste")
			(roundrect_rratio 0.25)
			(net 28 "GND")
			(pintype "passive")
		)
		(pad "2" smd roundrect
			(at 1.1 0 90)
			(size 1.2 1.3)
			(layers "F.Cu" "F.Mask" "F.Paste")
			(roundrect_rratio 0.25)
			(net 14 "P1_AVDDL")
			(pintype "passive")
		)
	)
	(footprint "antmicro-footprints:R_0402_1005Metric"
		(layer "F.Cu")
		(at 97.4 103.3 180)
		(descr "Resistor SMD 0402")
		(tags "resistor SMD 0402")
		(property "Reference" "R107"
			(at 2.25 -15.05 0)
			(layer "F.SilkS")
			(effects
				(font
					(size 0.7 0.7)
					(thickness 0.15)
				)
				(justify left bottom)
			)
		)
		(property "Value" "R_100R_0402"
			(at -1.011843 1.772046 0)
			(layer "F.Fab")
			(hide yes)
			(effects
				(font
					(size 0.7 0.7)
					(thickness 0.15)
				)
				(justify right top)
			)
		)
		(property "Datasheet" "https://www.bourns.com/docs/product-datasheets/cr.pdf"
			(at 0 0 0)
			(layer "F.Fab")
			(hide yes)
			(effects
				(font
					(size 1.27 1.27)
					(thickness 0.15)
				)
			)
		)
		(property "Description" "SMD Chip Resistor, 100 ohm, ± 1%, 62.5 mW, 0402 [1005 Metric], Thick Film, General Purpose"
			(at 0 0 0)
			(layer "F.Fab")
			(hide yes)
			(effects
				(font
					(size 1.27 1.27)
					(thickness 0.15)
				)
			)
		)
		(property "MPN" "CR0402-FX-1000GLF"
			(at 0 0 180)
			(unlocked yes)
			(layer "F.Fab")
			(hide yes)
			(effects
				(font
					(size 1 1)
					(thickness 0.15)
				)
			)
		)
		(property "Manufacturer" "Bourns"
			(at 0 0 180)
			(unlocked yes)
			(layer "F.Fab")
			(hide yes)
			(effects
				(font
					(size 1 1)
					(thickness 0.15)
				)
			)
		)
		(property "License" "Apache-2.0"
			(at 0 0 180)
			(unlocked yes)
			(layer "F.Fab")
			(hide yes)
			(effects
				(font
					(size 1 1)
					(thickness 0.15)
				)
			)
		)
		(property "Author" "Antmicro"
			(at 0 0 180)
			(unlocked yes)
			(layer "F.Fab")
			(hide yes)
			(effects
				(font
					(size 1 1)
					(thickness 0.15)
				)
			)
		)
		(property "Val" "100R"
			(at 0 0 180)
			(unlocked yes)
			(layer "F.Fab")
			(hide yes)
			(effects
				(font
					(size 1 1)
					(thickness 0.15)
				)
			)
		)
		(property "Tolerance" "1%"
			(at 0 0 180)
			(unlocked yes)
			(layer "F.Fab")
			(hide yes)
			(effects
				(font
					(size 1 1)
					(thickness 0.15)
				)
			)
		)
		(sheetname "/X710-AT2 Misc/")
		(sheetfile "x710-at2-mics.kicad_sch")
		(attr smd exclude_from_pos_files exclude_from_bom dnp)
		(fp_rect
			(start -0.925 -0.47)
			(end 0.925 0.47)
			(stroke
				(width 0.05)
				(type default)
			)
			(fill no)
			(layer "F.CrtYd")
		)
		(fp_rect
			(start -0.5 -0.25)
			(end 0.5 0.25)
			(stroke
				(width 0.15)
				(type solid)
			)
			(fill no)
			(layer "F.Fab")
		)
		(pad "1" smd roundrect
			(at -0.48 0 180)
			(size 0.59 0.64)
			(layers "F.Cu" "F.Mask" "F.Paste")
			(roundrect_rratio 0.25)
			(net 28 "GND")
			(pintype "passive")
		)
		(pad "2" smd roundrect
			(at 0.48 0 180)
			(size 0.59 0.64)
			(layers "F.Cu" "F.Mask" "F.Paste")
			(roundrect_rratio 0.25)
			(net 100 "/X710-AT2 Misc/AUX_PWR")
			(pintype "passive")
		)
	)
	(footprint "antmicro-footprints:R_0402_1005Metric"
		(layer "F.Cu")
		(at 58.1 85.15 90)
		(descr "Resistor SMD 0402")
		(tags "resistor SMD 0402")
		(property "Reference" "R11"
			(at 0.79 1 90)
			(layer "F.SilkS")
			(effects
				(font
					(size 0.7 0.7)
					(thickness 0.15)
				)
				(justify left bottom)
			)
		)
		(property "Value" "R_100k_0402"
			(at -1.011843 1.772046 90)
			(layer "F.Fab")
			(hide yes)
			(effects
				(font
					(size 0.7 0.7)
					(thickness 0.15)
				)
				(justify left bottom)
			)
		)
		(property "Datasheet" "https://www.bourns.com/docs/product-datasheets/cr.pdf"
			(at 0 0 90)
			(layer "F.Fab")
			(hide yes)
			(effects
				(font
					(size 1.27 1.27)
					(thickness 0.15)
				)
			)
		)
		(property "Description" "SMD Chip Resistor, 100 kohm, ± 1%, 62.5 mW, 0402 [1005 Metric], Thick Film, General Purpose"
			(at 0 0 90)
			(layer "F.Fab")
			(hide yes)
			(effects
				(font
					(size 1.27 1.27)
					(thickness 0.15)
				)
			)
		)
		(property "MPN" "CR0402-FX-1003GLF"
			(at 0 0 90)
			(unlocked yes)
			(layer "F.Fab")
			(hide yes)
			(effects
				(font
					(size 1 1)
					(thickness 0.15)
				)
			)
		)
		(property "Manufacturer" "Bourns"
			(at 0 0 90)
			(unlocked yes)
			(layer "F.Fab")
			(hide yes)
			(effects
				(font
					(size 1 1)
					(thickness 0.15)
				)
			)
		)
		(property "License" "Apache-2.0"
			(at 0 0 90)
			(unlocked yes)
			(layer "F.Fab")
			(hide yes)
			(effects
				(font
					(size 1 1)
					(thickness 0.15)
				)
			)
		)
		(property "Author" "Antmicro"
			(at 0 0 90)
			(unlocked yes)
			(layer "F.Fab")
			(hide yes)
			(effects
				(font
					(size 1 1)
					(thickness 0.15)
				)
			)
		)
		(property "Val" "100k"
			(at 0 0 90)
			(unlocked yes)
			(layer "F.Fab")
			(hide yes)
			(effects
				(font
					(size 1 1)
					(thickness 0.15)
				)
			)
		)
		(property "Tolerance" "1%"
			(at 0 0 90)
			(unlocked yes)
			(layer "F.Fab")
			(hide yes)
			(effects
				(font
					(size 1 1)
					(thickness 0.15)
				)
			)
		)
		(sheetname "/Power/")
		(sheetfile "power.kicad_sch")
		(attr smd)
		(fp_rect
			(start -0.925 -0.47)
			(end 0.925 0.47)
			(stroke
				(width 0.05)
				(type default)
			)
			(fill no)
			(layer "F.CrtYd")
		)
		(fp_rect
			(start -0.5 -0.25)
			(end 0.5 0.25)
			(stroke
				(width 0.15)
				(type solid)
			)
			(fill no)
			(layer "F.Fab")
		)
		(pad "1" smd roundrect
			(at -0.48 0 90)
			(size 0.59 0.64)
			(layers "F.Cu" "F.Mask" "F.Paste")
			(roundrect_rratio 0.25)
			(net 342 "/Power/VCCD_PG")
			(pintype "passive")
		)
		(pad "2" smd roundrect
			(at 0.48 0 90)
			(size 0.59 0.64)
			(layers "F.Cu" "F.Mask" "F.Paste")
			(roundrect_rratio 0.25)
			(net 322 "/Power/VCCD_VCC")
			(pintype "passive")
		)
	)
	(footprint "antmicro-footprints:R_0402_1005Metric"
		(layer "F.Cu")
		(at 104.625001 93.45 -90)
		(descr "Resistor SMD 0402")
		(tags "resistor SMD 0402")
		(property "Reference" "R114"
			(at 0.85 0.525001 90)
			(layer "F.SilkS")
			(effects
				(font
					(size 0.7 0.7)
					(thickness 0.15)
				)
				(justify left bottom)
			)
		)
		(property "Value" "R_2k_0402"
			(at -1.011843 1.772046 90)
			(layer "F.Fab")
			(hide yes)
			(effects
				(font
					(size 0.7 0.7)
					(thickness 0.15)
				)
				(justify right top)
			)
		)
		(property "Datasheet" "https://www.bourns.com/docs/product-datasheets/cr.pdf"
			(at 0 0 90)
			(layer "F.Fab")
			(hide yes)
			(effects
				(font
					(size 1.27 1.27)
					(thickness 0.15)
				)
			)
		)
		(property "Description" "SMD Chip Resistor, 2 kohm, ± 1%, 62.5 mW, 0402 [1005 Metric], Thick Film, General Purpose"
			(at 0 0 90)
			(layer "F.Fab")
			(hide yes)
			(effects
				(font
					(size 1.27 1.27)
					(thickness 0.15)
				)
			)
		)
		(property "MPN" "CR0402-FX-2001GLF"
			(at 0 0 270)
			(unlocked yes)
			(layer "F.Fab")
			(hide yes)
			(effects
				(font
					(size 1 1)
					(thickness 0.15)
				)
			)
		)
		(property "Manufacturer" "Bourns"
			(at 0 0 270)
			(unlocked yes)
			(layer "F.Fab")
			(hide yes)
			(effects
				(font
					(size 1 1)
					(thickness 0.15)
				)
			)
		)
		(property "License" "Apache-2.0"
			(at 0 0 270)
			(unlocked yes)
			(layer "F.Fab")
			(hide yes)
			(effects
				(font
					(size 1 1)
					(thickness 0.15)
				)
			)
		)
		(property "Author" "Antmicro"
			(at 0 0 270)
			(unlocked yes)
			(layer "F.Fab")
			(hide yes)
			(effects
				(font
					(size 1 1)
					(thickness 0.15)
				)
			)
		)
		(property "Val" "2k"
			(at 0 0 270)
			(unlocked yes)
			(layer "F.Fab")
			(hide yes)
			(effects
				(font
					(size 1 1)
					(thickness 0.15)
				)
			)
		)
		(property "Tolerance" "1%"
			(at 0 0 270)
			(unlocked yes)
			(layer "F.Fab")
			(hide yes)
			(effects
				(font
					(size 1 1)
					(thickness 0.15)
				)
			)
		)
		(sheetname "/X710-AT2 Misc/")
		(sheetfile "x710-at2-mics.kicad_sch")
		(attr smd)
		(fp_rect
			(start -0.925 -0.47)
			(end 0.925 0.47)
			(stroke
				(width 0.05)
				(type default)
			)
			(fill no)
			(layer "F.CrtYd")
		)
		(fp_rect
			(start -0.5 -0.25)
			(end 0.5 0.25)
			(stroke
				(width 0.15)
				(type solid)
			)
			(fill no)
			(layer "F.Fab")
		)
		(pad "1" smd roundrect
			(at -0.48 0 270)
			(size 0.59 0.64)
			(layers "F.Cu" "F.Mask" "F.Paste")
			(roundrect_rratio 0.25)
			(net 381 "/X710-AT2 Misc/MDIO.MDIO")
			(pintype "passive")
		)
		(pad "2" smd roundrect
			(at 0.48 0 270)
			(size 0.59 0.64)
			(layers "F.Cu" "F.Mask" "F.Paste")
			(roundrect_rratio 0.25)
			(net 18 "+1V88")
			(pintype "passive")
		)
	)
	(footprint "antmicro-footprints:R_0402_1005Metric"
		(layer "F.Cu")
		(at 87.1 112.45 90)
		(descr "Resistor SMD 0402")
		(tags "resistor SMD 0402")
		(property "Reference" "R74"
			(at -0.85 0.4375 90)
			(layer "F.SilkS")
			(effects
				(font
					(size 0.7 0.7)
					(thickness 0.15)
				)
				(justify right bottom)
			)
		)
		(property "Value" "R_0R_0402"
			(at -1.011843 1.772046 90)
			(layer "F.Fab")
			(hide yes)
			(effects
				(font
					(size 0.7 0.7)
					(thickness 0.15)
				)
				(justify left bottom)
			)
		)
		(property "Datasheet" "https://industrial.panasonic.com/cdbs/www-data/pdf/RDA0000/AOA0000C301.pdf"
			(at 0 0 90)
			(layer "F.Fab")
			(hide yes)
			(effects
				(font
					(size 1.27 1.27)
					(thickness 0.15)
				)
			)
		)
		(property "Description" "SMD Chip Resistor, Jumper, 0 ohm, 100 mW, 0402 [1005 Metric], Thick Film, General Purpose"
			(at 0 0 90)
			(layer "F.Fab")
			(hide yes)
			(effects
				(font
					(size 1.27 1.27)
					(thickness 0.15)
				)
			)
		)
		(property "MPN" "ERJ2GE0R00X"
			(at 0 0 90)
			(unlocked yes)
			(layer "F.Fab")
			(hide yes)
			(effects
				(font
					(size 1 1)
					(thickness 0.15)
				)
			)
		)
		(property "Manufacturer" "Panasonic"
			(at 0 0 90)
			(unlocked yes)
			(layer "F.Fab")
			(hide yes)
			(effects
				(font
					(size 1 1)
					(thickness 0.15)
				)
			)
		)
		(property "License" "Apache-2.0"
			(at 0 0 90)
			(unlocked yes)
			(layer "F.Fab")
			(hide yes)
			(effects
				(font
					(size 1 1)
					(thickness 0.15)
				)
			)
		)
		(property "Author" "Antmicro"
			(at 0 0 90)
			(unlocked yes)
			(layer "F.Fab")
			(hide yes)
			(effects
				(font
					(size 1 1)
					(thickness 0.15)
				)
			)
		)
		(property "Val" "0R"
			(at 0 0 90)
			(unlocked yes)
			(layer "F.Fab")
			(hide yes)
			(effects
				(font
					(size 1 1)
					(thickness 0.15)
				)
			)
		)
		(property "Tolerance" "~"
			(at 0 0 90)
			(unlocked yes)
			(layer "F.Fab")
			(hide yes)
			(effects
				(font
					(size 1 1)
					(thickness 0.15)
				)
			)
		)
		(property "Current" "1A"
			(at 0 0 90)
			(unlocked yes)
			(layer "F.Fab")
			(hide yes)
			(effects
				(font
					(size 1 1)
					(thickness 0.15)
				)
			)
		)
		(sheetname "/X710-AT2 10GbE/")
		(sheetfile "x710-at2-10gbe.kicad_sch")
		(attr smd)
		(fp_rect
			(start -0.925 -0.47)
			(end 0.925 0.47)
			(stroke
				(width 0.05)
				(type default)
			)
			(fill no)
			(layer "F.CrtYd")
		)
		(fp_rect
			(start -0.5 -0.25)
			(end 0.5 0.25)
			(stroke
				(width 0.15)
				(type solid)
			)
			(fill no)
			(layer "F.Fab")
		)
		(pad "1" smd roundrect
			(at -0.48 0 90)
			(size 0.59 0.64)
			(layers "F.Cu" "F.Mask" "F.Paste")
			(roundrect_rratio 0.25)
			(net 28 "GND")
			(pintype "passive")
		)
		(pad "2" smd roundrect
			(at 0.48 0 90)
			(size 0.59 0.64)
			(layers "F.Cu" "F.Mask" "F.Paste")
			(roundrect_rratio 0.25)
			(net 293 "/X710-AT2 10GbE/TPIN_3")
			(pintype "passive")
		)
	)
	(footprint "antmicro-footprints:FB_0603_1608Metric"
		(layer "F.Cu")
		(at 69.1 95.35)
		(property "Reference" "FB3"
			(at -0.79 -0.53 0)
			(layer "F.SilkS")
			(effects
				(font
					(size 0.7 0.7)
					(thickness 0.15)
				)
				(justify left bottom)
			)
		)
		(property "Value" "FB_470Z_1A_Murata-BLM18PG_0603"
			(at 0 1.5 0)
			(layer "F.Fab")
			(hide yes)
			(effects
				(font
					(size 0.7 0.7)
					(thickness 0.15)
				)
				(justify left bottom)
			)
		)
		(property "Datasheet" "https://www.murata.com/en-us/products/productdata/8796738650142/ENFA0003.pdf"
			(at 0 0 0)
			(layer "F.Fab")
			(hide yes)
			(effects
				(font
					(size 1.27 1.27)
					(thickness 0.15)
				)
			)
		)
		(property "Description" "Ferrite Bead, 0603 [1608 Metric], 470 ohm, 1 A, BLM18P, 0.2 ohm, ± 25%, DC power line"
			(at 0 0 0)
			(layer "F.Fab")
			(hide yes)
			(effects
				(font
					(size 1.27 1.27)
					(thickness 0.15)
				)
			)
		)
		(property "Val" "470Z/1A"
			(at 0 0 0)
			(unlocked yes)
			(layer "F.Fab")
			(hide yes)
			(effects
				(font
					(size 1 1)
					(thickness 0.15)
				)
			)
		)
		(property "MPN" "BLM18PG471SN1D"
			(at 0 0 0)
			(unlocked yes)
			(layer "F.Fab")
			(hide yes)
			(effects
				(font
					(size 1 1)
					(thickness 0.15)
				)
			)
		)
		(property "Manufacturer" "Murata"
			(at 0 0 0)
			(unlocked yes)
			(layer "F.Fab")
			(hide yes)
			(effects
				(font
					(size 1 1)
					(thickness 0.15)
				)
			)
		)
		(property "Current" ""
			(at 0 0 0)
			(unlocked yes)
			(layer "F.Fab")
			(hide yes)
			(effects
				(font
					(size 1 1)
					(thickness 0.15)
				)
			)
		)
		(property "Author" "Antmicro"
			(at 0 0 0)
			(unlocked yes)
			(layer "F.Fab")
			(hide yes)
			(effects
				(font
					(size 1 1)
					(thickness 0.15)
				)
			)
		)
		(property "License" "Apache-2.0"
			(at 0 0 0)
			(unlocked yes)
			(layer "F.Fab")
			(hide yes)
			(effects
				(font
					(size 1 1)
					(thickness 0.15)
				)
			)
		)
		(sheetname "/X710-AT2 power/")
		(sheetfile "x710-at2-power.kicad_sch")
		(attr smd)
		(fp_line
			(start -0.15 -0.4)
			(end 0.15 -0.4)
			(stroke
				(width 0.15)
				(type solid)
			)
			(layer "F.SilkS")
		)
		(fp_line
			(start -0.15 0.4)
			(end 0.15 0.4)
			(stroke
				(width 0.15)
				(type solid)
			)
			(layer "F.SilkS")
		)
		(fp_rect
			(start -1.25 -0.65)
			(end 1.25 0.65)
			(stroke
				(width 0.05)
				(type solid)
			)
			(fill no)
			(layer "F.CrtYd")
		)
		(fp_line
			(start -0.803 0.406)
			(end -0.803 -0.408)
			(stroke
				(width 0.15)
				(type solid)
			)
			(layer "F.Fab")
		)
		(fp_line
			(start 0.8 -0.408)
			(end -0.803 -0.408)
			(stroke
				(width 0.15)
				(type solid)
			)
			(layer "F.Fab")
		)
		(fp_line
			(start 0.8 -0.408)
			(end 0.8 0.406)
			(stroke
				(width 0.15)
				(type solid)
			)
			(layer "F.Fab")
		)
		(fp_line
			(start 0.8 0.406)
			(end -0.803 0.406)
			(stroke
				(width 0.15)
				(type solid)
			)
			(layer "F.Fab")
		)
		(pad "1" smd roundrect
			(at -0.7 0)
			(size 0.8 1)
			(layers "F.Cu" "F.Mask" "F.Paste")
			(roundrect_rratio 0.2)
			(net 18 "+1V88")
			(pintype "passive")
		)
		(pad "2" smd roundrect
			(at 0.7 0)
			(size 0.8 1)
			(layers "F.Cu" "F.Mask" "F.Paste")
			(roundrect_rratio 0.2)
			(net 23 "XGB_AVDDH")
			(pintype "passive")
		)
	)
	(footprint "antmicro-footprints:SW_DS04-254-1-01BK-SMT"
		(layer "F.Cu")
		(at 117.1 94.4 -90)
		(property "Reference" "SW1"
			(at -5.61 -0.89 90)
			(layer "F.SilkS")
			(effects
				(font
					(size 0.7 0.7)
					(thickness 0.15)
				)
				(justify right top)
			)
		)
		(property "Value" "SW_DS04-254-1-01BK-SMT"
			(at 0 3 90)
			(layer "F.Fab")
			(hide yes)
			(effects
				(font
					(size 0.7 0.7)
					(thickness 0.15)
				)
				(justify right top)
			)
		)
		(property "Datasheet" "https://www.mouser.com/datasheet/2/670/ds04_254_smt-1777718.pdf"
			(at 0 0 90)
			(layer "F.Fab")
			(hide yes)
			(effects
				(font
					(size 1.27 1.27)
					(thickness 0.15)
				)
			)
		)
		(property "Description" "Slide switch"
			(at 0 0 90)
			(layer "F.Fab")
			(hide yes)
			(effects
				(font
					(size 1.27 1.27)
					(thickness 0.15)
				)
			)
		)
		(property "MPN" "DS04-254-1-01BK-SMT"
			(at 0 0 270)
			(unlocked yes)
			(layer "F.Fab")
			(hide yes)
			(effects
				(font
					(size 1 1)
					(thickness 0.15)
				)
			)
		)
		(property "Manufacturer" "CUI Inc"
			(at 0 0 270)
			(unlocked yes)
			(layer "F.Fab")
			(hide yes)
			(effects
				(font
					(size 1 1)
					(thickness 0.15)
				)
			)
		)
		(property "Author" "Antmicro"
			(at 0 0 270)
			(unlocked yes)
			(layer "F.Fab")
			(hide yes)
			(effects
				(font
					(size 1 1)
					(thickness 0.15)
				)
			)
		)
		(property "License" "Apache-2.0"
			(at 0 0 270)
			(unlocked yes)
			(layer "F.Fab")
			(hide yes)
			(effects
				(font
					(size 1 1)
					(thickness 0.15)
				)
			)
		)
		(property ki_fp_filters "SW?DIP?x1*")
		(sheetname "/X710-AT2 RSVD/")
		(sheetfile "x710-at2-rsvd.kicad_sch")
		(attr smd)
		(fp_rect
			(start -3.3 -2)
			(end 3.3 2)
			(stroke
				(width 0.15)
				(type solid)
			)
			(fill no)
			(layer "F.SilkS")
		)
		(fp_rect
			(start -5.25 -2.025)
			(end 5.25 2.025)
			(stroke
				(width 0.05)
				(type solid)
			)
			(fill no)
			(layer "F.CrtYd")
		)
		(fp_rect
			(start -3.1 -1.8)
			(end 3.1 1.8)
			(stroke
				(width 0.15)
				(type solid)
			)
			(fill no)
			(layer "F.Fab")
		)
		(pad "1" smd rect
			(at -4.472 0.038 270)
			(size 1.5 1.1)
			(layers "F.Cu" "F.Mask" "F.Paste")
			(net 114 "/X710-AT2 RSVD/DEBUG_EN")
			(pintype "passive")
		)
		(pad "2" smd rect
			(at 4.428 0.038 90)
			(size 1.5 1.1)
			(layers "F.Cu" "F.Mask" "F.Paste")
			(net 7 "+3V3")
			(pintype "passive")
		)
	)
	(footprint "antmicro-footprints:C_0805_2012Metric"
		(layer "F.Cu")
		(at 71.3 114.3 90)
		(descr "Capacitor SMD 0805")
		(tags "capacitor SMD 0805")
		(property "Reference" "C172"
			(at -2.37 4.38 90)
			(layer "F.SilkS")
			(effects
				(font
					(size 0.7 0.7)
					(thickness 0.15)
				)
				(justify left bottom)
			)
		)
		(property "Value" "C_100u_0805"
			(at -2.055717 1.963153 90)
			(layer "F.Fab")
			(hide yes)
			(effects
				(font
					(size 0.7 0.7)
					(thickness 0.15)
				)
				(justify left bottom)
			)
		)
		(property "Datasheet" "https://www.murata.com/products/productdetail?partno=GRM21BR60J107ME15%23"
			(at 0 0 90)
			(layer "F.Fab")
			(hide yes)
			(effects
				(font
					(size 1.27 1.27)
					(thickness 0.15)
				)
			)
		)
		(property "Description" "SMD Multilayer Ceramic Capacitor, 100 µF, 6.3 V, 0805 [2012 Metric], ± 20%, X5R, GRM Series"
			(at 0 0 90)
			(layer "F.Fab")
			(hide yes)
			(effects
				(font
					(size 1.27 1.27)
					(thickness 0.15)
				)
			)
		)
		(property "MPN" "GRM21BR60J107ME15L"
			(at 0 0 90)
			(unlocked yes)
			(layer "F.Fab")
			(hide yes)
			(effects
				(font
					(size 1 1)
					(thickness 0.15)
				)
			)
		)
		(property "Manufacturer" "Murata"
			(at 0 0 90)
			(unlocked yes)
			(layer "F.Fab")
			(hide yes)
			(effects
				(font
					(size 1 1)
					(thickness 0.15)
				)
			)
		)
		(property "License" "Apache-2.0"
			(at 0 0 90)
			(unlocked yes)
			(layer "F.Fab")
			(hide yes)
			(effects
				(font
					(size 1 1)
					(thickness 0.15)
				)
			)
		)
		(property "Author" "Antmicro"
			(at 0 0 90)
			(unlocked yes)
			(layer "F.Fab")
			(hide yes)
			(effects
				(font
					(size 1 1)
					(thickness 0.15)
				)
			)
		)
		(property "Val" "100u"
			(at 0 0 90)
			(unlocked yes)
			(layer "F.Fab")
			(hide yes)
			(effects
				(font
					(size 1 1)
					(thickness 0.15)
				)
			)
		)
		(property "Voltage" ""
			(at 0 0 90)
			(unlocked yes)
			(layer "F.Fab")
			(hide yes)
			(effects
				(font
					(size 1 1)
					(thickness 0.15)
				)
			)
		)
		(property "Dielectric" ""
			(at 0 0 90)
			(unlocked yes)
			(layer "F.Fab")
			(hide yes)
			(effects
				(font
					(size 1 1)
					(thickness 0.15)
				)
			)
		)
		(property "Public" "False"
			(at 0 0 90)
			(unlocked yes)
			(layer "F.Fab")
			(hide yes)
			(effects
				(font
					(size 1 1)
					(thickness 0.15)
				)
			)
		)
		(sheetname "/X710-AT2 power/")
		(sheetfile "x710-at2-power.kicad_sch")
		(attr smd)
		(fp_line
			(start -0.3 -0.7)
			(end 0.3 -0.7)
			(stroke
				(width 0.15)
				(type solid)
			)
			(layer "F.SilkS")
		)
		(fp_line
			(start -0.3 0.7)
			(end 0.3 0.7)
			(stroke
				(width 0.15)
				(type solid)
			)
			(layer "F.SilkS")
		)
		(fp_rect
			(start 1.95 -0.9)
			(end -1.95 0.9)
			(stroke
				(width 0.05)
				(type default)
			)
			(fill no)
			(layer "F.CrtYd")
		)
		(fp_rect
			(start -0.95 -0.675)
			(end 0.95 0.675)
			(stroke
				(width 0.15)
				(type solid)
			)
			(fill no)
			(layer "F.Fab")
		)
		(pad "1" smd roundrect
			(at -1.1 0 90)
			(size 1.2 1.3)
			(layers "F.Cu" "F.Mask" "F.Paste")
			(roundrect_rratio 0.25)
			(net 28 "GND")
			(pintype "passive")
		)
		(pad "2" smd roundrect
			(at 1.1 0 90)
			(size 1.2 1.3)
			(layers "F.Cu" "F.Mask" "F.Paste")
			(roundrect_rratio 0.25)
			(net 14 "P1_AVDDL")
			(pintype "passive")
		)
	)
	(footprint "antmicro-footprints:C_0402_1005Metric"
		(layer "F.Cu")
		(at 54.4 111.6 -90)
		(descr "Capacitor SMD 0402")
		(tags "capacitor SMD 0402")
		(property "Reference" "C32"
			(at 0.81 0.45 90)
			(layer "F.SilkS")
			(effects
				(font
					(size 0.7 0.7)
					(thickness 0.15)
				)
				(justify right top)
			)
		)
		(property "Value" "C_100n_0402"
			(at -1.022927 2.155213 90)
			(layer "F.Fab")
			(hide yes)
			(effects
				(font
					(size 0.7 0.7)
					(thickness 0.15)
				)
				(justify right top)
			)
		)
		(property "Datasheet" "https://www.murata.com/products/productdetail?partno=GRM155R61H104KE14%23"
			(at 0 0 90)
			(layer "F.Fab")
			(hide yes)
			(effects
				(font
					(size 1.27 1.27)
					(thickness 0.15)
				)
			)
		)
		(property "Description" "SMD Multilayer Ceramic Capacitor, 0.1 µF, 50 V, 0402 [1005 Metric], ± 10%, X5R, GRM Series"
			(at 0 0 90)
			(layer "F.Fab")
			(hide yes)
			(effects
				(font
					(size 1.27 1.27)
					(thickness 0.15)
				)
			)
		)
		(property "MPN" "GRM155R61H104KE14D"
			(at 0 0 270)
			(unlocked yes)
			(layer "F.Fab")
			(hide yes)
			(effects
				(font
					(size 1 1)
					(thickness 0.15)
				)
			)
		)
		(property "Manufacturer" "Murata"
			(at 0 0 270)
			(unlocked yes)
			(layer "F.Fab")
			(hide yes)
			(effects
				(font
					(size 1 1)
					(thickness 0.15)
				)
			)
		)
		(property "License" "Apache-2.0"
			(at 0 0 270)
			(unlocked yes)
			(layer "F.Fab")
			(hide yes)
			(effects
				(font
					(size 1 1)
					(thickness 0.15)
				)
			)
		)
		(property "Author" "Antmicro"
			(at 0 0 270)
			(unlocked yes)
			(layer "F.Fab")
			(hide yes)
			(effects
				(font
					(size 1 1)
					(thickness 0.15)
				)
			)
		)
		(property "Val" "100n"
			(at 0 0 270)
			(unlocked yes)
			(layer "F.Fab")
			(hide yes)
			(effects
				(font
					(size 1 1)
					(thickness 0.15)
				)
			)
		)
		(property "Voltage" "50V"
			(at 0 0 270)
			(unlocked yes)
			(layer "F.Fab")
			(hide yes)
			(effects
				(font
					(size 1 1)
					(thickness 0.15)
				)
			)
		)
		(property "Dielectric" "X5R"
			(at 0 0 270)
			(unlocked yes)
			(layer "F.Fab")
			(hide yes)
			(effects
				(font
					(size 1 1)
					(thickness 0.15)
				)
			)
		)
		(sheetname "/Power/")
		(sheetfile "power.kicad_sch")
		(attr smd)
		(fp_rect
			(start -0.925 -0.47)
			(end 0.925 0.47)
			(stroke
				(width 0.05)
				(type default)
			)
			(fill no)
			(layer "F.CrtYd")
		)
		(fp_line
			(start -0.494 0.248)
			(end -0.494 -0.25)
			(stroke
				(width 0.15)
				(type solid)
			)
			(layer "F.Fab")
		)
		(fp_line
			(start 0.504 0.248)
			(end -0.494 0.248)
			(stroke
				(width 0.15)
				(type solid)
			)
			(layer "F.Fab")
		)
		(fp_line
			(start -0.494 -0.25)
			(end 0.504 -0.25)
			(stroke
				(width 0.15)
				(type solid)
			)
			(layer "F.Fab")
		)
		(fp_line
			(start 0.504 -0.25)
			(end 0.504 0.248)
			(stroke
				(width 0.15)
				(type solid)
			)
			(layer "F.Fab")
		)
		(pad "1" smd roundrect
			(at -0.48 0 270)
			(size 0.59 0.64)
			(layers "F.Cu" "F.Mask" "F.Paste")
			(roundrect_rratio 0.25)
			(net 28 "GND")
			(pintype "passive")
		)
		(pad "2" smd roundrect
			(at 0.48 0 270)
			(size 0.59 0.64)
			(layers "F.Cu" "F.Mask" "F.Paste")
			(roundrect_rratio 0.25)
			(net 314 "VCC")
			(pintype "passive")
		)
	)
	(footprint "antmicro-footprints:Resonator_SMD_Murata_XRCGB_2x1.6x0.65mm"
		(layer "F.Cu")
		(at 69.3945 106.22 180)
		(property "Reference" "Y2"
			(at 2.3445 -0.61 0)
			(layer "F.SilkS")
			(effects
				(font
					(size 0.7 0.7)
					(thickness 0.15)
				)
				(justify left bottom)
			)
		)
		(property "Value" "Resonator_50MHz_XRCGE"
			(at 0 2.2 0)
			(layer "F.Fab")
			(hide yes)
			(effects
				(font
					(size 0.7 0.7)
					(thickness 0.15)
				)
				(justify right top)
			)
		)
		(property "Datasheet" "https://www.murata.com/products/productdata/8813268205598/SPEC-XRCGE50M000F5A2AR0.pdf"
			(at 0 0 0)
			(layer "F.Fab")
			(hide yes)
			(effects
				(font
					(size 1.27 1.27)
					(thickness 0.15)
				)
			)
		)
		(property "Description" "Crystal, 50 MHz, 2mm x 1.6mm, 50 ppm, 4.7 pF, 50 ppm, XRCGE Series"
			(at 0 0 0)
			(layer "F.Fab")
			(hide yes)
			(effects
				(font
					(size 1.27 1.27)
					(thickness 0.15)
				)
			)
		)
		(property "Manufacturer" "Murata"
			(at 0 0 180)
			(unlocked yes)
			(layer "F.Fab")
			(hide yes)
			(effects
				(font
					(size 1 1)
					(thickness 0.15)
				)
			)
		)
		(property "MPN" "XRCGE50M000F5A2AR0"
			(at 0 0 180)
			(unlocked yes)
			(layer "F.Fab")
			(hide yes)
			(effects
				(font
					(size 1 1)
					(thickness 0.15)
				)
			)
		)
		(property "Val" "50MHz"
			(at 0 0 180)
			(unlocked yes)
			(layer "F.Fab")
			(hide yes)
			(effects
				(font
					(size 1 1)
					(thickness 0.15)
				)
			)
		)
		(property "CLoad" "4.7pF"
			(at 0 0 180)
			(unlocked yes)
			(layer "F.Fab")
			(hide yes)
			(effects
				(font
					(size 1 1)
					(thickness 0.15)
				)
			)
		)
		(property "Author" "Antmicro"
			(at 0 0 180)
			(unlocked yes)
			(layer "F.Fab")
			(hide yes)
			(effects
				(font
					(size 1 1)
					(thickness 0.15)
				)
			)
		)
		(property "License" "Apache-2.0"
			(at 0 0 180)
			(unlocked yes)
			(layer "F.Fab")
			(hide yes)
			(effects
				(font
					(size 1 1)
					(thickness 0.15)
				)
			)
		)
		(sheetname "/X710-AT2 Misc/")
		(sheetfile "x710-at2-mics.kicad_sch")
		(attr smd)
		(fp_line
			(start 0.95 0.4)
			(end 0.95 -0.4)
			(stroke
				(width 0.15)
				(type solid)
			)
			(layer "F.SilkS")
		)
		(fp_line
			(start -0.4 1.15)
			(end 0.4 1.15)
			(stroke
				(width 0.15)
				(type solid)
			)
			(layer "F.SilkS")
		)
		(fp_line
			(start -0.4 -1.15)
			(end 0.4 -1.15)
			(stroke
				(width 0.15)
				(type solid)
			)
			(layer "F.SilkS")
		)
		(fp_line
			(start -0.95 0.4)
			(end -0.95 -0.4)
			(stroke
				(width 0.15)
				(type solid)
			)
			(layer "F.SilkS")
		)
		(fp_circle
			(center -0.95 -1.15)
			(end -0.9 -1.15)
			(stroke
				(width 0.15)
				(type solid)
			)
			(fill yes)
			(layer "F.SilkS")
		)
		(fp_rect
			(start -1.05 -1.25)
			(end 1.05 1.24)
			(stroke
				(width 0.05)
				(type solid)
			)
			(fill no)
			(layer "F.CrtYd")
		)
		(fp_rect
			(start -0.85 -1.054)
			(end 0.852 1.054)
			(stroke
				(width 0.15)
				(type solid)
			)
			(fill no)
			(layer "F.Fab")
		)
		(pad "1" smd rect
			(at -0.5 -0.675 180)
			(size 0.7 0.75)
			(layers "F.Cu" "F.Mask" "F.Paste")
			(net 76 "/X710-AT2 Misc/50MHZ_XTAL_R.+")
			(pintype "passive")
		)
		(pad "2" smd rect
			(at -0.5 0.675 180)
			(size 0.7 0.75)
			(layers "F.Cu" "F.Mask" "F.Paste")
			(net 28 "GND")
			(pinfunction "SH")
			(pintype "passive")
		)
		(pad "3" smd rect
			(at 0.5 0.675 180)
			(size 0.7 0.75)
			(layers "F.Cu" "F.Mask" "F.Paste")
			(net 77 "/X710-AT2 Misc/50MHZ_XTAL_R.-")
			(pintype "passive")
		)
		(pad "4" smd rect
			(at 0.5 -0.675 180)
			(size 0.7 0.75)
			(layers "F.Cu" "F.Mask" "F.Paste")
			(net 28 "GND")
			(pinfunction "SH")
			(pintype "passive")
		)
	)
	(footprint "antmicro-footprints:R_0402_1005Metric"
		(layer "F.Cu")
		(at 110.35 95.35 90)
		(descr "Resistor SMD 0402")
		(tags "resistor SMD 0402")
		(property "Reference" "R68"
			(at 2.9 0.35 90)
			(layer "F.SilkS")
			(effects
				(font
					(size 0.7 0.7)
					(thickness 0.15)
				)
				(justify left bottom)
			)
		)
		(property "Value" "R_10R_0402"
			(at -1.011843 1.772046 90)
			(layer "F.Fab")
			(hide yes)
			(effects
				(font
					(size 0.7 0.7)
					(thickness 0.15)
				)
				(justify left bottom)
			)
		)
		(property "Datasheet" "https://www.bourns.com/docs/product-datasheets/cr.pdf"
			(at 0 0 90)
			(layer "F.Fab")
			(hide yes)
			(effects
				(font
					(size 1.27 1.27)
					(thickness 0.15)
				)
			)
		)
		(property "Description" "SMD Chip Resistor, 10 ohm, ± 1%, 62.5 mW, 0402 [1005 Metric], Thick Film, General Purpose"
			(at 0 0 90)
			(layer "F.Fab")
			(hide yes)
			(effects
				(font
					(size 1.27 1.27)
					(thickness 0.15)
				)
			)
		)
		(property "MPN" "CR0402-FX-10R0GLF"
			(at 0 0 90)
			(unlocked yes)
			(layer "F.Fab")
			(hide yes)
			(effects
				(font
					(size 1 1)
					(thickness 0.15)
				)
			)
		)
		(property "Manufacturer" "Bourns"
			(at 0 0 90)
			(unlocked yes)
			(layer "F.Fab")
			(hide yes)
			(effects
				(font
					(size 1 1)
					(thickness 0.15)
				)
			)
		)
		(property "License" "Apache-2.0"
			(at 0 0 90)
			(unlocked yes)
			(layer "F.Fab")
			(hide yes)
			(effects
				(font
					(size 1 1)
					(thickness 0.15)
				)
			)
		)
		(property "Author" "Antmicro"
			(at 0 0 90)
			(unlocked yes)
			(layer "F.Fab")
			(hide yes)
			(effects
				(font
					(size 1 1)
					(thickness 0.15)
				)
			)
		)
		(property "Val" "10R"
			(at 0 0 90)
			(unlocked yes)
			(layer "F.Fab")
			(hide yes)
			(effects
				(font
					(size 1 1)
					(thickness 0.15)
				)
			)
		)
		(property "Tolerance" "1%"
			(at 0 0 90)
			(unlocked yes)
			(layer "F.Fab")
			(hide yes)
			(effects
				(font
					(size 1 1)
					(thickness 0.15)
				)
			)
		)
		(sheetname "/X710-AT2 10GbE/")
		(sheetfile "x710-at2-10gbe.kicad_sch")
		(attr smd)
		(fp_rect
			(start -0.925 -0.47)
			(end 0.925 0.47)
			(stroke
				(width 0.05)
				(type default)
			)
			(fill no)
			(layer "F.CrtYd")
		)
		(fp_rect
			(start -0.5 -0.25)
			(end 0.5 0.25)
			(stroke
				(width 0.15)
				(type solid)
			)
			(fill no)
			(layer "F.Fab")
		)
		(pad "1" smd roundrect
			(at -0.48 0 90)
			(size 0.59 0.64)
			(layers "F.Cu" "F.Mask" "F.Paste")
			(roundrect_rratio 0.25)
			(net 288 "/X710-AT2 10GbE/MDIO0_I2C0.MDC")
			(pintype "passive")
		)
		(pad "2" smd roundrect
			(at 0.48 0 90)
			(size 0.59 0.64)
			(layers "F.Cu" "F.Mask" "F.Paste")
			(roundrect_rratio 0.25)
			(net 130 "/X710-AT2 10GbE/MDC0_SCL0")
			(pintype "passive")
		)
	)
	(footprint "antmicro-footprints:C_0603_1608Metric_EIA"
		(layer "F.Cu")
		(at 66.7 82.100001 180)
		(descr "Capacitor SMD 0603, IPC-7351 Density Level A")
		(tags "Capacitor 0603")
		(property "Reference" "C124"
			(at -2.01 4.030001 0)
			(layer "F.SilkS")
			(effects
				(font
					(size 0.7 0.7)
					(thickness 0.15)
				)
				(justify right top)
			)
		)
		(property "Value" "C_22u_16V_0603"
			(at -1.42757 1.770288 0)
			(layer "F.Fab")
			(hide yes)
			(effects
				(font
					(size 0.7 0.7)
					(thickness 0.15)
				)
				(justify right top)
			)
		)
		(property "Datasheet" "https://product.samsungsem.com/mlcc/CL10A226MO7JZN.do"
			(at 0 0 0)
			(layer "F.Fab")
			(hide yes)
			(effects
				(font
					(size 1.27 1.27)
					(thickness 0.15)
				)
			)
		)
		(property "Description" "SMD Multilayer Ceramic Capacitor"
			(at 0 0 0)
			(layer "F.Fab")
			(hide yes)
			(effects
				(font
					(size 1.27 1.27)
					(thickness 0.15)
				)
			)
		)
		(property "MPN" "CL10A226MO7JZNC"
			(at 0 0 180)
			(unlocked yes)
			(layer "F.Fab")
			(hide yes)
			(effects
				(font
					(size 1 1)
					(thickness 0.15)
				)
			)
		)
		(property "Manufacturer" "Samsung Electro-Mechanics"
			(at 0 0 180)
			(unlocked yes)
			(layer "F.Fab")
			(hide yes)
			(effects
				(font
					(size 1 1)
					(thickness 0.15)
				)
			)
		)
		(property "License" "Apache-2.0"
			(at 0 0 180)
			(unlocked yes)
			(layer "F.Fab")
			(hide yes)
			(effects
				(font
					(size 1 1)
					(thickness 0.15)
				)
			)
		)
		(property "Author" "Antmicro"
			(at 0 0 180)
			(unlocked yes)
			(layer "F.Fab")
			(hide yes)
			(effects
				(font
					(size 1 1)
					(thickness 0.15)
				)
			)
		)
		(property "Val" "22u"
			(at 0 0 180)
			(unlocked yes)
			(layer "F.Fab")
			(hide yes)
			(effects
				(font
					(size 1 1)
					(thickness 0.15)
				)
			)
		)
		(property "Voltage" "16V"
			(at 0 0 180)
			(unlocked yes)
			(layer "F.Fab")
			(hide yes)
			(effects
				(font
					(size 1 1)
					(thickness 0.15)
				)
			)
		)
		(property "Dielectric" ""
			(at 0 0 180)
			(unlocked yes)
			(layer "F.Fab")
			(hide yes)
			(effects
				(font
					(size 1 1)
					(thickness 0.15)
				)
			)
		)
		(sheetname "/X710-AT2 power/")
		(sheetfile "x710-at2-power.kicad_sch")
		(attr smd)
		(fp_line
			(start -0.15 0.55)
			(end 0.15 0.55)
			(stroke
				(width 0.15)
				(type solid)
			)
			(layer "F.SilkS")
		)
		(fp_line
			(start -0.15 -0.55)
			(end 0.15 -0.55)
			(stroke
				(width 0.15)
				(type solid)
			)
			(layer "F.SilkS")
		)
		(fp_rect
			(start -1.25 -0.65)
			(end 1.25 0.65)
			(stroke
				(width 0.05)
				(type solid)
			)
			(fill no)
			(layer "F.CrtYd")
		)
		(fp_rect
			(start -0.8 -0.45)
			(end 0.8 0.45)
			(stroke
				(width 0.15)
				(type solid)
			)
			(fill no)
			(layer "F.Fab")
		)
		(pad "1" smd roundrect
			(at -0.7 0 180)
			(size 0.8 1.1)
			(layers "F.Cu" "F.Mask" "F.Paste")
			(roundrect_rratio 0.2)
			(net 28 "GND")
			(pintype "passive")
		)
		(pad "2" smd roundrect
			(at 0.7 0 180)
			(size 0.8 1.1)
			(layers "F.Cu" "F.Mask" "F.Paste")
			(roundrect_rratio 0.2)
			(net 9 "VCCD")
			(pintype "passive")
		)
	)
	(footprint "antmicro-footprints:C_0603_1608Metric"
		(layer "F.Cu")
		(at 72.45 103.7 90)
		(descr "Capacitor SMD 0603")
		(tags "capacitor 0603")
		(property "Reference" "C186"
			(at -1.36 1.54 90)
			(layer "F.SilkS")
			(effects
				(font
					(size 0.7 0.7)
					(thickness 0.15)
				)
				(justify left bottom)
			)
		)
		(property "Value" "C_10u_10V_X7R_0603"
			(at -1.42757 1.770288 90)
			(layer "F.Fab")
			(hide yes)
			(effects
				(font
					(size 0.7 0.7)
					(thickness 0.15)
				)
				(justify left bottom)
			)
		)
		(property "Datasheet" "https://www.murata.com/products/productdetail?partno=GRM188Z71A106KA73%23"
			(at 0 0 90)
			(layer "F.Fab")
			(hide yes)
			(effects
				(font
					(size 1.27 1.27)
					(thickness 0.15)
				)
			)
		)
		(property "Description" "SMD Multilayer Ceramic Capacitor,  10µF, 10V, 0603, ±10%, X7R"
			(at 0 0 90)
			(layer "F.Fab")
			(hide yes)
			(effects
				(font
					(size 1.27 1.27)
					(thickness 0.15)
				)
			)
		)
		(property "MPN" "GRM188Z71A106KA73D"
			(at 0 0 90)
			(unlocked yes)
			(layer "F.Fab")
			(hide yes)
			(effects
				(font
					(size 1 1)
					(thickness 0.15)
				)
			)
		)
		(property "Val" "10u"
			(at 0 0 90)
			(unlocked yes)
			(layer "F.Fab")
			(hide yes)
			(effects
				(font
					(size 1 1)
					(thickness 0.15)
				)
			)
		)
		(property "Voltage" "10V"
			(at 0 0 90)
			(unlocked yes)
			(layer "F.Fab")
			(hide yes)
			(effects
				(font
					(size 1 1)
					(thickness 0.15)
				)
			)
		)
		(property "Dielectric" "X7R"
			(at 0 0 90)
			(unlocked yes)
			(layer "F.Fab")
			(hide yes)
			(effects
				(font
					(size 1 1)
					(thickness 0.15)
				)
			)
		)
		(property "Manufacturer" "Murata"
			(at 0 0 90)
			(unlocked yes)
			(layer "F.Fab")
			(hide yes)
			(effects
				(font
					(size 1 1)
					(thickness 0.15)
				)
			)
		)
		(property "License" "Apache-2.0"
			(at 0 0 90)
			(unlocked yes)
			(layer "F.Fab")
			(hide yes)
			(effects
				(font
					(size 1 1)
					(thickness 0.15)
				)
			)
		)
		(property "Author" "Antmicro"
			(at 0 0 90)
			(unlocked yes)
			(layer "F.Fab")
			(hide yes)
			(effects
				(font
					(size 1 1)
					(thickness 0.15)
				)
			)
		)
		(sheetname "/X710-AT2 power/")
		(sheetfile "x710-at2-power.kicad_sch")
		(attr smd)
		(fp_line
			(start -0.15 -0.4)
			(end 0.15 -0.4)
			(stroke
				(width 0.15)
				(type solid)
			)
			(layer "F.SilkS")
		)
		(fp_line
			(start -0.15 0.4)
			(end 0.15 0.4)
			(stroke
				(width 0.15)
				(type solid)
			)
			(layer "F.SilkS")
		)
		(fp_rect
			(start -1.25 -0.65)
			(end 1.25 0.65)
			(stroke
				(width 0.05)
				(type solid)
			)
			(fill no)
			(layer "F.CrtYd")
		)
		(fp_rect
			(start -0.8 -0.4)
			(end 0.8 0.4)
			(stroke
				(width 0.15)
				(type solid)
			)
			(fill no)
			(layer "F.Fab")
		)
		(pad "1" smd roundrect
			(at -0.7 0 90)
			(size 0.8 1)
			(layers "F.Cu" "F.Mask" "F.Paste")
			(roundrect_rratio 0.2)
			(net 28 "GND")
			(pintype "passive")
		)
		(pad "2" smd roundrect
			(at 0.7 0 90)
			(size 0.8 1)
			(layers "F.Cu" "F.Mask" "F.Paste")
			(roundrect_rratio 0.2)
			(net 24 "XFI_PVDD")
			(pintype "passive")
		)
	)
	(footprint "antmicro-footprints:C_0805_2012Metric"
		(layer "F.Cu")
		(at 69.45 110.39 90)
		(descr "Capacitor SMD 0805")
		(tags "capacitor SMD 0805")
		(property "Reference" "C163"
			(at -3.63 5.24 90)
			(layer "F.SilkS")
			(effects
				(font
					(size 0.7 0.7)
					(thickness 0.15)
				)
				(justify left bottom)
			)
		)
		(property "Value" "C_100u_0805"
			(at -2.055717 1.963153 90)
			(layer "F.Fab")
			(hide yes)
			(effects
				(font
					(size 0.7 0.7)
					(thickness 0.15)
				)
				(justify left bottom)
			)
		)
		(property "Datasheet" "https://www.murata.com/products/productdetail?partno=GRM21BR60J107ME15%23"
			(at 0 0 90)
			(layer "F.Fab")
			(hide yes)
			(effects
				(font
					(size 1.27 1.27)
					(thickness 0.15)
				)
			)
		)
		(property "Description" "SMD Multilayer Ceramic Capacitor, 100 µF, 6.3 V, 0805 [2012 Metric], ± 20%, X5R, GRM Series"
			(at 0 0 90)
			(layer "F.Fab")
			(hide yes)
			(effects
				(font
					(size 1.27 1.27)
					(thickness 0.15)
				)
			)
		)
		(property "MPN" "GRM21BR60J107ME15L"
			(at 0 0 90)
			(unlocked yes)
			(layer "F.Fab")
			(hide yes)
			(effects
				(font
					(size 1 1)
					(thickness 0.15)
				)
			)
		)
		(property "Manufacturer" "Murata"
			(at 0 0 90)
			(unlocked yes)
			(layer "F.Fab")
			(hide yes)
			(effects
				(font
					(size 1 1)
					(thickness 0.15)
				)
			)
		)
		(property "License" "Apache-2.0"
			(at 0 0 90)
			(unlocked yes)
			(layer "F.Fab")
			(hide yes)
			(effects
				(font
					(size 1 1)
					(thickness 0.15)
				)
			)
		)
		(property "Author" "Antmicro"
			(at 0 0 90)
			(unlocked yes)
			(layer "F.Fab")
			(hide yes)
			(effects
				(font
					(size 1 1)
					(thickness 0.15)
				)
			)
		)
		(property "Val" "100u"
			(at 0 0 90)
			(unlocked yes)
			(layer "F.Fab")
			(hide yes)
			(effects
				(font
					(size 1 1)
					(thickness 0.15)
				)
			)
		)
		(property "Voltage" ""
			(at 0 0 90)
			(unlocked yes)
			(layer "F.Fab")
			(hide yes)
			(effects
				(font
					(size 1 1)
					(thickness 0.15)
				)
			)
		)
		(property "Dielectric" ""
			(at 0 0 90)
			(unlocked yes)
			(layer "F.Fab")
			(hide yes)
			(effects
				(font
					(size 1 1)
					(thickness 0.15)
				)
			)
		)
		(property "Public" "False"
			(at 0 0 90)
			(unlocked yes)
			(layer "F.Fab")
			(hide yes)
			(effects
				(font
					(size 1 1)
					(thickness 0.15)
				)
			)
		)
		(sheetname "/X710-AT2 power/")
		(sheetfile "x710-at2-power.kicad_sch")
		(attr smd)
		(fp_line
			(start -0.3 -0.7)
			(end 0.3 -0.7)
			(stroke
				(width 0.15)
				(type solid)
			)
			(layer "F.SilkS")
		)
		(fp_line
			(start -0.3 0.7)
			(end 0.3 0.7)
			(stroke
				(width 0.15)
				(type solid)
			)
			(layer "F.SilkS")
		)
		(fp_rect
			(start 1.95 -0.9)
			(end -1.95 0.9)
			(stroke
				(width 0.05)
				(type default)
			)
			(fill no)
			(layer "F.CrtYd")
		)
		(fp_rect
			(start -0.95 -0.675)
			(end 0.95 0.675)
			(stroke
				(width 0.15)
				(type solid)
			)
			(fill no)
			(layer "F.Fab")
		)
		(pad "1" smd roundrect
			(at -1.1 0 90)
			(size 1.2 1.3)
			(layers "F.Cu" "F.Mask" "F.Paste")
			(roundrect_rratio 0.25)
			(net 28 "GND")
			(pintype "passive")
		)
		(pad "2" smd roundrect
			(at 1.1 0 90)
			(size 1.2 1.3)
			(layers "F.Cu" "F.Mask" "F.Paste")
			(roundrect_rratio 0.25)
			(net 5 "P0_AVDDL")
			(pintype "passive")
		)
	)
	(footprint "antmicro-footprints:C_0402_1005Metric"
		(layer "F.Cu")
		(at 54.4 96.199999 -90)
		(descr "Capacitor SMD 0402")
		(tags "capacitor SMD 0402")
		(property "Reference" "C42"
			(at 0.840001 0.41 90)
			(layer "F.SilkS")
			(effects
				(font
					(size 0.7 0.7)
					(thickness 0.15)
				)
				(justify right top)
			)
		)
		(property "Value" "C_100n_0402"
			(at -1.022927 2.155213 90)
			(layer "F.Fab")
			(hide yes)
			(effects
				(font
					(size 0.7 0.7)
					(thickness 0.15)
				)
				(justify right top)
			)
		)
		(property "Datasheet" "https://www.murata.com/products/productdetail?partno=GRM155R61H104KE14%23"
			(at 0 0 90)
			(layer "F.Fab")
			(hide yes)
			(effects
				(font
					(size 1.27 1.27)
					(thickness 0.15)
				)
			)
		)
		(property "Description" "SMD Multilayer Ceramic Capacitor, 0.1 µF, 50 V, 0402 [1005 Metric], ± 10%, X5R, GRM Series"
			(at 0 0 90)
			(layer "F.Fab")
			(hide yes)
			(effects
				(font
					(size 1.27 1.27)
					(thickness 0.15)
				)
			)
		)
		(property "MPN" "GRM155R61H104KE14D"
			(at 0 0 270)
			(unlocked yes)
			(layer "F.Fab")
			(hide yes)
			(effects
				(font
					(size 1 1)
					(thickness 0.15)
				)
			)
		)
		(property "Manufacturer" "Murata"
			(at 0 0 270)
			(unlocked yes)
			(layer "F.Fab")
			(hide yes)
			(effects
				(font
					(size 1 1)
					(thickness 0.15)
				)
			)
		)
		(property "License" "Apache-2.0"
			(at 0 0 270)
			(unlocked yes)
			(layer "F.Fab")
			(hide yes)
			(effects
				(font
					(size 1 1)
					(thickness 0.15)
				)
			)
		)
		(property "Author" "Antmicro"
			(at 0 0 270)
			(unlocked yes)
			(layer "F.Fab")
			(hide yes)
			(effects
				(font
					(size 1 1)
					(thickness 0.15)
				)
			)
		)
		(property "Val" "100n"
			(at 0 0 270)
			(unlocked yes)
			(layer "F.Fab")
			(hide yes)
			(effects
				(font
					(size 1 1)
					(thickness 0.15)
				)
			)
		)
		(property "Voltage" "50V"
			(at 0 0 270)
			(unlocked yes)
			(layer "F.Fab")
			(hide yes)
			(effects
				(font
					(size 1 1)
					(thickness 0.15)
				)
			)
		)
		(property "Dielectric" "X5R"
			(at 0 0 270)
			(unlocked yes)
			(layer "F.Fab")
			(hide yes)
			(effects
				(font
					(size 1 1)
					(thickness 0.15)
				)
			)
		)
		(sheetname "/Power/")
		(sheetfile "power.kicad_sch")
		(attr smd)
		(fp_rect
			(start -0.925 -0.47)
			(end 0.925 0.47)
			(stroke
				(width 0.05)
				(type default)
			)
			(fill no)
			(layer "F.CrtYd")
		)
		(fp_line
			(start -0.494 0.248)
			(end -0.494 -0.25)
			(stroke
				(width 0.15)
				(type solid)
			)
			(layer "F.Fab")
		)
		(fp_line
			(start 0.504 0.248)
			(end -0.494 0.248)
			(stroke
				(width 0.15)
				(type solid)
			)
			(layer "F.Fab")
		)
		(fp_line
			(start -0.494 -0.25)
			(end 0.504 -0.25)
			(stroke
				(width 0.15)
				(type solid)
			)
			(layer "F.Fab")
		)
		(fp_line
			(start 0.504 -0.25)
			(end 0.504 0.248)
			(stroke
				(width 0.15)
				(type solid)
			)
			(layer "F.Fab")
		)
		(pad "1" smd roundrect
			(at -0.48 0 270)
			(size 0.59 0.64)
			(layers "F.Cu" "F.Mask" "F.Paste")
			(roundrect_rratio 0.25)
			(net 28 "GND")
			(pintype "passive")
		)
		(pad "2" smd roundrect
			(at 0.48 0 270)
			(size 0.59 0.64)
			(layers "F.Cu" "F.Mask" "F.Paste")
			(roundrect_rratio 0.25)
			(net 314 "VCC")
			(pintype "passive")
		)
	)
	(footprint "antmicro-footprints:R_0402_1005Metric"
		(layer "F.Cu")
		(at 111.35 95.35 -90)
		(descr "Resistor SMD 0402")
		(tags "resistor SMD 0402")
		(property "Reference" "R65"
			(at -2.9 -0.334999 90)
			(layer "F.SilkS")
			(effects
				(font
					(size 0.7 0.7)
					(thickness 0.15)
				)
				(justify left bottom)
			)
		)
		(property "Value" "R_3k3_0402"
			(at -1.011843 1.772046 90)
			(layer "F.Fab")
			(hide yes)
			(effects
				(font
					(size 0.7 0.7)
					(thickness 0.15)
				)
				(justify right top)
			)
		)
		(property "Datasheet" "https://www.bourns.com/docs/product-datasheets/cr.pdf"
			(at 0 0 90)
			(layer "F.Fab")
			(hide yes)
			(effects
				(font
					(size 1.27 1.27)
					(thickness 0.15)
				)
			)
		)
		(property "Description" "SMD Chip Resistor, 3.3 kohm, ± 1%, 63 mW, 0402 [1005 Metric], Thick Film, General Purpose"
			(at 0 0 90)
			(layer "F.Fab")
			(hide yes)
			(effects
				(font
					(size 1.27 1.27)
					(thickness 0.15)
				)
			)
		)
		(property "MPN" "CR0402-FX-3301GLF"
			(at 0 0 270)
			(unlocked yes)
			(layer "F.Fab")
			(hide yes)
			(effects
				(font
					(size 1 1)
					(thickness 0.15)
				)
			)
		)
		(property "Manufacturer" "Bourns"
			(at 0 0 270)
			(unlocked yes)
			(layer "F.Fab")
			(hide yes)
			(effects
				(font
					(size 1 1)
					(thickness 0.15)
				)
			)
		)
		(property "License" "Apache-2.0"
			(at 0 0 270)
			(unlocked yes)
			(layer "F.Fab")
			(hide yes)
			(effects
				(font
					(size 1 1)
					(thickness 0.15)
				)
			)
		)
		(property "Author" "Antmicro"
			(at 0 0 270)
			(unlocked yes)
			(layer "F.Fab")
			(hide yes)
			(effects
				(font
					(size 1 1)
					(thickness 0.15)
				)
			)
		)
		(property "Val" "3k3"
			(at 0 0 270)
			(unlocked yes)
			(layer "F.Fab")
			(hide yes)
			(effects
				(font
					(size 1 1)
					(thickness 0.15)
				)
			)
		)
		(property "Tolerance" "1%"
			(at 0 0 270)
			(unlocked yes)
			(layer "F.Fab")
			(hide yes)
			(effects
				(font
					(size 1 1)
					(thickness 0.15)
				)
			)
		)
		(sheetname "/X710-AT2 10GbE/")
		(sheetfile "x710-at2-10gbe.kicad_sch")
		(attr smd)
		(fp_rect
			(start -0.925 -0.47)
			(end 0.925 0.47)
			(stroke
				(width 0.05)
				(type default)
			)
			(fill no)
			(layer "F.CrtYd")
		)
		(fp_rect
			(start -0.5 -0.25)
			(end 0.5 0.25)
			(stroke
				(width 0.15)
				(type solid)
			)
			(fill no)
			(layer "F.Fab")
		)
		(pad "1" smd roundrect
			(at -0.48 0 270)
			(size 0.59 0.64)
			(layers "F.Cu" "F.Mask" "F.Paste")
			(roundrect_rratio 0.25)
			(net 130 "/X710-AT2 10GbE/MDC0_SCL0")
			(pintype "passive")
		)
		(pad "2" smd roundrect
			(at 0.48 0 270)
			(size 0.59 0.64)
			(layers "F.Cu" "F.Mask" "F.Paste")
			(roundrect_rratio 0.25)
			(net 7 "+3V3")
			(pintype "passive")
		)
	)
	(footprint "antmicro-footprints:TDFN-8-1EP_2x3x0.75mm_P0.5mm_EP1.75x1.63mm"
		(layer "F.Cu")
		(at 111.15 103.4 -90)
		(descr "8-Lead Plastic Dual Flat, 2x3mm Body")
		(tags "DFN 0.5")
		(property "Reference" "U14"
			(at -0.31 1.85 90)
			(layer "F.SilkS")
			(effects
				(font
					(size 0.7 0.7)
					(thickness 0.15)
				)
				(justify right top)
			)
		)
		(property "Value" "MAX31740ATA+T"
			(at -2.1 3 90)
			(layer "F.Fab")
			(hide yes)
			(effects
				(font
					(size 0.7 0.7)
					(thickness 0.15)
				)
				(justify right top)
			)
		)
		(property "Datasheet" "https://www.analog.com/media/en/technical-documentation/data-sheets/max31740.pdf"
			(at 0 0 90)
			(layer "F.Fab")
			(hide yes)
			(effects
				(font
					(size 1.27 1.27)
					(thickness 0.15)
				)
			)
		)
		(property "Description" "Pwm fan speed controller, temperature measurement, Control speed of 2-, 3-, 4- Wire Fans"
			(at 0 0 90)
			(layer "F.Fab")
			(hide yes)
			(effects
				(font
					(size 1.27 1.27)
					(thickness 0.15)
				)
			)
		)
		(property "MPN" "MAX31740ATA+T"
			(at 0 0 270)
			(unlocked yes)
			(layer "F.Fab")
			(hide yes)
			(effects
				(font
					(size 1 1)
					(thickness 0.15)
				)
			)
		)
		(property "Manufacturer" "Analog Devices"
			(at 0 0 270)
			(unlocked yes)
			(layer "F.Fab")
			(hide yes)
			(effects
				(font
					(size 1 1)
					(thickness 0.15)
				)
			)
		)
		(property "Author" "Antmicro"
			(at 0 0 270)
			(unlocked yes)
			(layer "F.Fab")
			(hide yes)
			(effects
				(font
					(size 1 1)
					(thickness 0.15)
				)
			)
		)
		(property "License" "Apache-2.0"
			(at 0 0 270)
			(unlocked yes)
			(layer "F.Fab")
			(hide yes)
			(effects
				(font
					(size 1 1)
					(thickness 0.15)
				)
			)
		)
		(sheetname "/Fan controller/")
		(sheetfile "fan-controller.kicad_sch")
		(attr smd exclude_from_pos_files exclude_from_bom dnp)
		(fp_circle
			(center -1.8 -1.1)
			(end -1.75 -1.1)
			(stroke
				(width 0.15)
				(type solid)
			)
			(fill yes)
			(layer "F.SilkS")
		)
		(fp_rect
			(start -2.05 -1.25)
			(end 2.05 1.25)
			(stroke
				(width 0.05)
				(type default)
			)
			(fill no)
			(layer "F.CrtYd")
		)
		(pad "1" smd rect
			(at -1.5 -0.75)
			(size 0.3 0.75)
			(layers "F.Cu" "F.Mask" "F.Paste")
			(net 399 "/Fan controller/DMIN")
			(pinfunction "DMIN")
			(pintype "passive")
		)
		(pad "2" smd rect
			(at -1.5 -0.25)
			(size 0.3 0.75)
			(layers "F.Cu" "F.Mask" "F.Paste")
			(net 400 "/Fan controller/SLOPE")
			(pinfunction "SLOPE")
			(pintype "passive")
		)
		(pad "3" smd rect
			(at -1.5 0.25)
			(size 0.3 0.75)
			(layers "F.Cu" "F.Mask" "F.Paste")
			(net 385 "/Fan controller/SENSE")
			(pinfunction "SENSE")
			(pintype "passive")
		)
		(pad "4" smd rect
			(at -1.5 0.75)
			(size 0.3 0.75)
			(layers "F.Cu" "F.Mask" "F.Paste")
			(net 28 "GND")
			(pinfunction "GND")
			(pintype "power_in")
		)
		(pad "5" smd rect
			(at 1.5 0.75)
			(size 0.3 0.75)
			(layers "F.Cu" "F.Mask" "F.Paste")
			(net 387 "/Fan controller/FREQ")
			(pinfunction "FREQ")
			(pintype "passive")
		)
		(pad "6" smd rect
			(at 1.5 0.25)
			(size 0.3 0.75)
			(layers "F.Cu" "F.Mask" "F.Paste")
			(net 398 "/Fan controller/D0")
			(pinfunction "D0")
			(pintype "passive")
		)
		(pad "7" smd rect
			(at 1.5 -0.25)
			(size 0.3 0.75)
			(layers "F.Cu" "F.Mask" "F.Paste")
			(net 390 "/Fan controller/PWM")
			(pinfunction "PWM_OUT")
			(pintype "output")
		)
		(pad "8" smd rect
			(at 1.5 -0.75)
			(size 0.3 0.75)
			(layers "F.Cu" "F.Mask" "F.Paste")
			(net 388 "/Fan controller/+5V")
			(pinfunction "VDD")
			(pintype "power_in")
		)
		(pad "9" smd rect
			(at 0 0)
			(size 1.63 1.75)
			(layers "F.Cu" "F.Mask" "F.Paste")
			(net 28 "GND")
			(pinfunction "EP")
			(pintype "power_in")
		)
	)
	(footprint "antmicro-footprints:C_0402_1005Metric"
		(layer "F.Cu")
		(at 67.27 114.3 180)
		(descr "Capacitor SMD 0402")
		(tags "capacitor SMD 0402")
		(property "Reference" "C171"
			(at 0.69 0.36 0)
			(layer "F.SilkS")
			(effects
				(font
					(size 0.7 0.7)
					(thickness 0.15)
				)
				(justify right top)
			)
		)
		(property "Value" "C_100n_0402"
			(at -1.022927 2.155213 0)
			(layer "F.Fab")
			(hide yes)
			(effects
				(font
					(size 0.7 0.7)
					(thickness 0.15)
				)
				(justify right top)
			)
		)
		(property "Datasheet" "https://www.murata.com/products/productdetail?partno=GRM155R61H104KE14%23"
			(at 0 0 0)
			(layer "F.Fab")
			(hide yes)
			(effects
				(font
					(size 1.27 1.27)
					(thickness 0.15)
				)
			)
		)
		(property "Description" "SMD Multilayer Ceramic Capacitor, 0.1 µF, 50 V, 0402 [1005 Metric], ± 10%, X5R, GRM Series"
			(at 0 0 0)
			(layer "F.Fab")
			(hide yes)
			(effects
				(font
					(size 1.27 1.27)
					(thickness 0.15)
				)
			)
		)
		(property "MPN" "GRM155R61H104KE14D"
			(at 0 0 180)
			(unlocked yes)
			(layer "F.Fab")
			(hide yes)
			(effects
				(font
					(size 1 1)
					(thickness 0.15)
				)
			)
		)
		(property "Val" "100n"
			(at 0 0 180)
			(unlocked yes)
			(layer "F.Fab")
			(hide yes)
			(effects
				(font
					(size 1 1)
					(thickness 0.15)
				)
			)
		)
		(property "Voltage" "50V"
			(at 0 0 180)
			(unlocked yes)
			(layer "F.Fab")
			(hide yes)
			(effects
				(font
					(size 1 1)
					(thickness 0.15)
				)
			)
		)
		(property "Dielectric" "X5R"
			(at 0 0 180)
			(unlocked yes)
			(layer "F.Fab")
			(hide yes)
			(effects
				(font
					(size 1 1)
					(thickness 0.15)
				)
			)
		)
		(property "Manufacturer" "Murata"
			(at 0 0 180)
			(unlocked yes)
			(layer "F.Fab")
			(hide yes)
			(effects
				(font
					(size 1 1)
					(thickness 0.15)
				)
			)
		)
		(property "License" "Apache-2.0"
			(at 0 0 180)
			(unlocked yes)
			(layer "F.Fab")
			(hide yes)
			(effects
				(font
					(size 1 1)
					(thickness 0.15)
				)
			)
		)
		(property "Author" "Antmicro"
			(at 0 0 180)
			(unlocked yes)
			(layer "F.Fab")
			(hide yes)
			(effects
				(font
					(size 1 1)
					(thickness 0.15)
				)
			)
		)
		(sheetname "/X710-AT2 power/")
		(sheetfile "x710-at2-power.kicad_sch")
		(attr smd)
		(fp_rect
			(start -0.925 -0.47)
			(end 0.925 0.47)
			(stroke
				(width 0.05)
				(type default)
			)
			(fill no)
			(layer "F.CrtYd")
		)
		(fp_line
			(start 0.504 0.248)
			(end -0.494 0.248)
			(stroke
				(width 0.15)
				(type solid)
			)
			(layer "F.Fab")
		)
		(fp_line
			(start 0.504 -0.25)
			(end 0.504 0.248)
			(stroke
				(width 0.15)
				(type solid)
			)
			(layer "F.Fab")
		)
		(fp_line
			(start -0.494 0.248)
			(end -0.494 -0.25)
			(stroke
				(width 0.15)
				(type solid)
			)
			(layer "F.Fab")
		)
		(fp_line
			(start -0.494 -0.25)
			(end 0.504 -0.25)
			(stroke
				(width 0.15)
				(type solid)
			)
			(layer "F.Fab")
		)
		(pad "1" smd roundrect
			(at -0.48 0 180)
			(size 0.59 0.64)
			(layers "F.Cu" "F.Mask" "F.Paste")
			(roundrect_rratio 0.25)
			(net 28 "GND")
			(pintype "passive")
		)
		(pad "2" smd roundrect
			(at 0.48 0 180)
			(size 0.59 0.64)
			(layers "F.Cu" "F.Mask" "F.Paste")
			(roundrect_rratio 0.25)
			(net 302 "+1V0")
			(pintype "passive")
		)
	)
	(footprint "antmicro-footprints:R_0402_1005Metric"
		(layer "F.Cu")
		(at 80.35 84.15)
		(descr "Resistor SMD 0402")
		(tags "resistor SMD 0402")
		(property "Reference" "R103"
			(at 1.05 -1.5 0)
			(layer "F.SilkS")
			(effects
				(font
					(size 0.7 0.7)
					(thickness 0.15)
				)
				(justify right bottom)
			)
		)
		(property "Value" "R_3k3_0402"
			(at -1.011843 1.772046 0)
			(layer "F.Fab")
			(hide yes)
			(effects
				(font
					(size 0.7 0.7)
					(thickness 0.15)
				)
				(justify left bottom)
			)
		)
		(property "Datasheet" "https://www.bourns.com/docs/product-datasheets/cr.pdf"
			(at 0 0 0)
			(layer "F.Fab")
			(hide yes)
			(effects
				(font
					(size 1.27 1.27)
					(thickness 0.15)
				)
			)
		)
		(property "Description" "SMD Chip Resistor, 3.3 kohm, ± 1%, 63 mW, 0402 [1005 Metric], Thick Film, General Purpose"
			(at 0 0 0)
			(layer "F.Fab")
			(hide yes)
			(effects
				(font
					(size 1.27 1.27)
					(thickness 0.15)
				)
			)
		)
		(property "MPN" "CR0402-FX-3301GLF"
			(at 0 0 0)
			(unlocked yes)
			(layer "F.Fab")
			(hide yes)
			(effects
				(font
					(size 1 1)
					(thickness 0.15)
				)
			)
		)
		(property "Manufacturer" "Bourns"
			(at 0 0 0)
			(unlocked yes)
			(layer "F.Fab")
			(hide yes)
			(effects
				(font
					(size 1 1)
					(thickness 0.15)
				)
			)
		)
		(property "License" "Apache-2.0"
			(at 0 0 0)
			(unlocked yes)
			(layer "F.Fab")
			(hide yes)
			(effects
				(font
					(size 1 1)
					(thickness 0.15)
				)
			)
		)
		(property "Author" "Antmicro"
			(at 0 0 0)
			(unlocked yes)
			(layer "F.Fab")
			(hide yes)
			(effects
				(font
					(size 1 1)
					(thickness 0.15)
				)
			)
		)
		(property "Val" "3k3"
			(at 0 0 0)
			(unlocked yes)
			(layer "F.Fab")
			(hide yes)
			(effects
				(font
					(size 1 1)
					(thickness 0.15)
				)
			)
		)
		(property "Tolerance" "1%"
			(at 0 0 0)
			(unlocked yes)
			(layer "F.Fab")
			(hide yes)
			(effects
				(font
					(size 1 1)
					(thickness 0.15)
				)
			)
		)
		(sheetname "/X710-AT2 Misc/")
		(sheetfile "x710-at2-mics.kicad_sch")
		(attr smd)
		(fp_rect
			(start -0.925 -0.47)
			(end 0.925 0.47)
			(stroke
				(width 0.05)
				(type default)
			)
			(fill no)
			(layer "F.CrtYd")
		)
		(fp_rect
			(start -0.5 -0.25)
			(end 0.5 0.25)
			(stroke
				(width 0.15)
				(type solid)
			)
			(fill no)
			(layer "F.Fab")
		)
		(pad "1" smd roundrect
			(at -0.48 0)
			(size 0.59 0.64)
			(layers "F.Cu" "F.Mask" "F.Paste")
			(roundrect_rratio 0.25)
			(net 99 "/X710-AT2 Misc/LAN_PWR_GOOD")
			(pintype "passive")
		)
		(pad "2" smd roundrect
			(at 0.48 0)
			(size 0.59 0.64)
			(layers "F.Cu" "F.Mask" "F.Paste")
			(roundrect_rratio 0.25)
			(net 78 "Net-(U10-VCC)")
			(pintype "passive")
		)
	)
	(footprint "antmicro-footprints:L_Bourns-SRP4021HMT"
		(layer "F.Cu")
		(at 99.55 94.4 180)
		(property "Reference" "L8"
			(at -2.2 2.2 0)
			(layer "F.SilkS")
			(effects
				(font
					(size 0.7 0.7)
					(thickness 0.15)
				)
				(justify right bottom)
			)
		)
		(property "Value" "L_1u_10A_Bourns-SRP4021HMT"
			(at -2.85 3.4 0)
			(layer "F.Fab")
			(hide yes)
			(effects
				(font
					(size 0.7 0.7)
					(thickness 0.15)
				)
				(justify right top)
			)
		)
		(property "Datasheet" "https://www.mouser.com/datasheet/2/54/Bourns_04_01_2025_SRP4021HMT_Datasheet-3580094.pdf"
			(at 0 0 0)
			(layer "F.Fab")
			(hide yes)
			(effects
				(font
					(size 0.7 0.7)
					(thickness 0.15)
				)
				(justify right top)
			)
		)
		(property "Description" "Power Inductors - SMD Ind,4.1x4.2x1.9mm,1uH+/-20%,10A, Shielded"
			(at 0 0 0)
			(layer "F.Fab")
			(hide yes)
			(effects
				(font
					(size 0.7 0.7)
					(thickness 0.15)
				)
				(justify right top)
			)
		)
		(property "Val" "1u/10A"
			(at 0 0 180)
			(unlocked yes)
			(layer "F.Fab")
			(hide yes)
			(effects
				(font
					(size 1 1)
					(thickness 0.15)
				)
			)
		)
		(property "Manufacturer" "Bourns"
			(at 0 0 180)
			(unlocked yes)
			(layer "F.Fab")
			(hide yes)
			(effects
				(font
					(size 1 1)
					(thickness 0.15)
				)
			)
		)
		(property "MPN" "SRP4021HMT-1R0M"
			(at 0 0 180)
			(unlocked yes)
			(layer "F.Fab")
			(hide yes)
			(effects
				(font
					(size 1 1)
					(thickness 0.15)
				)
			)
		)
		(property "ISat" ""
			(at 0 0 180)
			(unlocked yes)
			(layer "F.Fab")
			(hide yes)
			(effects
				(font
					(size 1 1)
					(thickness 0.15)
				)
			)
		)
		(property "Isat" "8A"
			(at 0 0 180)
			(unlocked yes)
			(layer "F.Fab")
			(hide yes)
			(effects
				(font
					(size 1 1)
					(thickness 0.15)
				)
			)
		)
		(property "IMax" ""
			(at 0 0 180)
			(unlocked yes)
			(layer "F.Fab")
			(hide yes)
			(effects
				(font
					(size 1 1)
					(thickness 0.15)
				)
			)
		)
		(property "Imax" "10A"
			(at 0 0 180)
			(unlocked yes)
			(layer "F.Fab")
			(hide yes)
			(effects
				(font
					(size 1 1)
					(thickness 0.15)
				)
			)
		)
		(property "Size" "4.2x4.1"
			(at 0 0 180)
			(unlocked yes)
			(layer "F.Fab")
			(hide yes)
			(effects
				(font
					(size 1 1)
					(thickness 0.15)
				)
			)
		)
		(property "Author" "Antmicro"
			(at 0 0 180)
			(unlocked yes)
			(layer "F.Fab")
			(hide yes)
			(effects
				(font
					(size 1 1)
					(thickness 0.15)
				)
			)
		)
		(property "License" "Apache-2.0"
			(at 0 0 180)
			(unlocked yes)
			(layer "F.Fab")
			(hide yes)
			(effects
				(font
					(size 1 1)
					(thickness 0.15)
				)
			)
		)
		(sheetname "/X710-AT2 power/")
		(sheetfile "x710-at2-power.kicad_sch")
		(attr smd)
		(fp_line
			(start -0.8 2.05)
			(end 0.8 2.05)
			(stroke
				(width 0.15)
				(type solid)
			)
			(layer "F.SilkS")
		)
		(fp_line
			(start -0.8 -2.05)
			(end 0.8 -2.05)
			(stroke
				(width 0.15)
				(type solid)
			)
			(layer "F.SilkS")
		)
		(fp_rect
			(start -2.85 -2.3)
			(end 2.85 2.3)
			(stroke
				(width 0.05)
				(type solid)
			)
			(fill no)
			(layer "F.CrtYd")
		)
		(fp_rect
			(start -2 -2.05)
			(end 2 2.05)
			(stroke
				(width 0.15)
				(type solid)
			)
			(fill no)
			(layer "F.Fab")
		)
		(pad "1" smd rect
			(at 1.85 0)
			(size 1.5 3.5)
			(layers "F.Cu" "F.Mask" "F.Paste")
			(net 155 "Net-(U9H-SVR_IND)")
			(pintype "passive")
		)
		(pad "2" smd rect
			(at -1.85 0)
			(size 1.5 3.5)
			(layers "F.Cu" "F.Mask" "F.Paste")
			(net 1 "VCCA")
			(pintype "passive")
		)
	)
	(footprint "antmicro-footprints:R_0402_1005Metric"
		(layer "F.Cu")
		(at 101.3 105.2)
		(descr "Resistor SMD 0402")
		(tags "resistor SMD 0402")
		(property "Reference" "R90"
			(at -0.8 15.3 0)
			(layer "F.SilkS")
			(effects
				(font
					(size 0.7 0.7)
					(thickness 0.15)
				)
				(justify left bottom)
			)
		)
		(property "Value" "R_10k_0402"
			(at -1.011843 1.772046 0)
			(layer "F.Fab")
			(hide yes)
			(effects
				(font
					(size 0.7 0.7)
					(thickness 0.15)
				)
				(justify left bottom)
			)
		)
		(property "Datasheet" "https://www.bourns.com/docs/product-datasheets/cr.pdf"
			(at 0 0 0)
			(layer "F.Fab")
			(hide yes)
			(effects
				(font
					(size 1.27 1.27)
					(thickness 0.15)
				)
			)
		)
		(property "Description" "SMD Chip Resistor, 10 kohm, ± 1%, 62.5 mW, 0402 [1005 Metric], Thick Film, General Purpose"
			(at 0 0 0)
			(layer "F.Fab")
			(hide yes)
			(effects
				(font
					(size 1.27 1.27)
					(thickness 0.15)
				)
			)
		)
		(property "MPN" "CR0402-FX-1002GLF"
			(at 0 0 0)
			(unlocked yes)
			(layer "F.Fab")
			(hide yes)
			(effects
				(font
					(size 1 1)
					(thickness 0.15)
				)
			)
		)
		(property "Manufacturer" "Bourns"
			(at 0 0 0)
			(unlocked yes)
			(layer "F.Fab")
			(hide yes)
			(effects
				(font
					(size 1 1)
					(thickness 0.15)
				)
			)
		)
		(property "License" "Apache-2.0"
			(at 0 0 0)
			(unlocked yes)
			(layer "F.Fab")
			(hide yes)
			(effects
				(font
					(size 1 1)
					(thickness 0.15)
				)
			)
		)
		(property "Author" "Antmicro"
			(at 0 0 0)
			(unlocked yes)
			(layer "F.Fab")
			(hide yes)
			(effects
				(font
					(size 1 1)
					(thickness 0.15)
				)
			)
		)
		(property "Val" "10k"
			(at 0 0 0)
			(unlocked yes)
			(layer "F.Fab")
			(hide yes)
			(effects
				(font
					(size 1 1)
					(thickness 0.15)
				)
			)
		)
		(property "Tolerance" "1%"
			(at 0 0 0)
			(unlocked yes)
			(layer "F.Fab")
			(hide yes)
			(effects
				(font
					(size 1 1)
					(thickness 0.15)
				)
			)
		)
		(sheetname "/X710-AT2 Misc/")
		(sheetfile "x710-at2-mics.kicad_sch")
		(attr smd)
		(fp_rect
			(start -0.925 -0.47)
			(end 0.925 0.47)
			(stroke
				(width 0.05)
				(type default)
			)
			(fill no)
			(layer "F.CrtYd")
		)
		(fp_rect
			(start -0.5 -0.25)
			(end 0.5 0.25)
			(stroke
				(width 0.15)
				(type solid)
			)
			(fill no)
			(layer "F.Fab")
		)
		(pad "1" smd roundrect
			(at -0.48 0)
			(size 0.59 0.64)
			(layers "F.Cu" "F.Mask" "F.Paste")
			(roundrect_rratio 0.25)
			(net 28 "GND")
			(pintype "passive")
		)
		(pad "2" smd roundrect
			(at 0.48 0)
			(size 0.59 0.64)
			(layers "F.Cu" "F.Mask" "F.Paste")
			(roundrect_rratio 0.25)
			(net 368 "/X710-AT2 Misc/NCSI.ARB_IN")
			(pintype "passive")
		)
	)
	(footprint "antmicro-footprints:C_0603_1608Metric_EIA"
		(layer "F.Cu")
		(at 67.25 111.55 180)
		(descr "Capacitor SMD 0603, IPC-7351 Density Level A")
		(tags "Capacitor 0603")
		(property "Reference" "C161"
			(at 0.94 0.17 0)
			(layer "F.SilkS")
			(effects
				(font
					(size 0.7 0.7)
					(thickness 0.15)
				)
				(justify right top)
			)
		)
		(property "Value" "C_22u_16V_0603"
			(at -1.42757 1.770288 0)
			(layer "F.Fab")
			(hide yes)
			(effects
				(font
					(size 0.7 0.7)
					(thickness 0.15)
				)
				(justify right top)
			)
		)
		(property "Datasheet" "https://product.samsungsem.com/mlcc/CL10A226MO7JZN.do"
			(at 0 0 0)
			(layer "F.Fab")
			(hide yes)
			(effects
				(font
					(size 1.27 1.27)
					(thickness 0.15)
				)
			)
		)
		(property "Description" "SMD Multilayer Ceramic Capacitor"
			(at 0 0 0)
			(layer "F.Fab")
			(hide yes)
			(effects
				(font
					(size 1.27 1.27)
					(thickness 0.15)
				)
			)
		)
		(property "MPN" "CL10A226MO7JZNC"
			(at 0 0 180)
			(unlocked yes)
			(layer "F.Fab")
			(hide yes)
			(effects
				(font
					(size 1 1)
					(thickness 0.15)
				)
			)
		)
		(property "Manufacturer" "Samsung Electro-Mechanics"
			(at 0 0 180)
			(unlocked yes)
			(layer "F.Fab")
			(hide yes)
			(effects
				(font
					(size 1 1)
					(thickness 0.15)
				)
			)
		)
		(property "License" "Apache-2.0"
			(at 0 0 180)
			(unlocked yes)
			(layer "F.Fab")
			(hide yes)
			(effects
				(font
					(size 1 1)
					(thickness 0.15)
				)
			)
		)
		(property "Author" "Antmicro"
			(at 0 0 180)
			(unlocked yes)
			(layer "F.Fab")
			(hide yes)
			(effects
				(font
					(size 1 1)
					(thickness 0.15)
				)
			)
		)
		(property "Val" "22u"
			(at 0 0 180)
			(unlocked yes)
			(layer "F.Fab")
			(hide yes)
			(effects
				(font
					(size 1 1)
					(thickness 0.15)
				)
			)
		)
		(property "Voltage" "16V"
			(at 0 0 180)
			(unlocked yes)
			(layer "F.Fab")
			(hide yes)
			(effects
				(font
					(size 1 1)
					(thickness 0.15)
				)
			)
		)
		(property "Dielectric" ""
			(at 0 0 180)
			(unlocked yes)
			(layer "F.Fab")
			(hide yes)
			(effects
				(font
					(size 1 1)
					(thickness 0.15)
				)
			)
		)
		(sheetname "/X710-AT2 power/")
		(sheetfile "x710-at2-power.kicad_sch")
		(attr smd)
		(fp_line
			(start -0.15 0.55)
			(end 0.15 0.55)
			(stroke
				(width 0.15)
				(type solid)
			)
			(layer "F.SilkS")
		)
		(fp_line
			(start -0.15 -0.55)
			(end 0.15 -0.55)
			(stroke
				(width 0.15)
				(type solid)
			)
			(layer "F.SilkS")
		)
		(fp_rect
			(start -1.25 -0.65)
			(end 1.25 0.65)
			(stroke
				(width 0.05)
				(type solid)
			)
			(fill no)
			(layer "F.CrtYd")
		)
		(fp_rect
			(start -0.8 -0.45)
			(end 0.8 0.45)
			(stroke
				(width 0.15)
				(type solid)
			)
			(fill no)
			(layer "F.Fab")
		)
		(pad "1" smd roundrect
			(at -0.7 0 180)
			(size 0.8 1.1)
			(layers "F.Cu" "F.Mask" "F.Paste")
			(roundrect_rratio 0.2)
			(net 28 "GND")
			(pintype "passive")
		)
		(pad "2" smd roundrect
			(at 0.7 0 180)
			(size 0.8 1.1)
			(layers "F.Cu" "F.Mask" "F.Paste")
			(roundrect_rratio 0.2)
			(net 302 "+1V0")
			(pintype "passive")
		)
	)
	(footprint "antmicro-footprints:R_0603_1608Metric"
		(layer "F.Cu")
		(at 63.2 84.1)
		(descr "Resistor SMD 0603")
		(tags "resistor SMD 0603")
		(property "Reference" "R8"
			(at -1.26 -1.54 0)
			(layer "F.SilkS")
			(effects
				(font
					(size 0.7 0.7)
					(thickness 0.15)
				)
				(justify left bottom)
			)
		)
		(property "Value" "R_0R_22.4A_0603"
			(at 0 1.6 0)
			(layer "F.Fab")
			(hide yes)
			(effects
				(font
					(size 0.7 0.7)
					(thickness 0.15)
				)
				(justify left bottom)
			)
		)
		(property "Datasheet" "https://fscdn.rohm.com/en/products/databook/datasheet/passive/resistor/chip_resistor/pmr-jpw-e.pdf"
			(at 0 0 0)
			(layer "F.Fab")
			(hide yes)
			(effects
				(font
					(size 1.27 1.27)
					(thickness 0.15)
				)
			)
		)
		(property "Description" "SMD Chip Resistor"
			(at 0 0 0)
			(layer "F.Fab")
			(hide yes)
			(effects
				(font
					(size 1.27 1.27)
					(thickness 0.15)
				)
			)
		)
		(property "MPN" "PMR03EZPJ000"
			(at 0 0 0)
			(unlocked yes)
			(layer "F.Fab")
			(hide yes)
			(effects
				(font
					(size 1 1)
					(thickness 0.15)
				)
			)
		)
		(property "Manufacturer" "ROHM Semiconductor"
			(at 0 0 0)
			(unlocked yes)
			(layer "F.Fab")
			(hide yes)
			(effects
				(font
					(size 1 1)
					(thickness 0.15)
				)
			)
		)
		(property "Val" "0R"
			(at 0 0 0)
			(unlocked yes)
			(layer "F.Fab")
			(hide yes)
			(effects
				(font
					(size 1 1)
					(thickness 0.15)
				)
			)
		)
		(property "Max. Curr." "22.4A"
			(at 0 0 0)
			(unlocked yes)
			(layer "F.Fab")
			(hide yes)
			(effects
				(font
					(size 1 1)
					(thickness 0.15)
				)
			)
		)
		(property "Author" "Antmicro"
			(at 0 0 0)
			(unlocked yes)
			(layer "F.Fab")
			(hide yes)
			(effects
				(font
					(size 1 1)
					(thickness 0.15)
				)
			)
		)
		(property "License" "Apache-2.0"
			(at 0 0 0)
			(unlocked yes)
			(layer "F.Fab")
			(hide yes)
			(effects
				(font
					(size 1 1)
					(thickness 0.15)
				)
			)
		)
		(property "Tolerance" "template_tolerance"
			(at 0 0 0)
			(unlocked yes)
			(layer "F.Fab")
			(hide yes)
			(effects
				(font
					(size 1 1)
					(thickness 0.15)
				)
			)
		)
		(sheetname "/Power/")
		(sheetfile "power.kicad_sch")
		(attr smd)
		(fp_line
			(start -0.15 -0.4)
			(end 0.15 -0.4)
			(stroke
				(width 0.15)
				(type solid)
			)
			(layer "F.SilkS")
		)
		(fp_line
			(start -0.15 0.4)
			(end 0.15 0.4)
			(stroke
				(width 0.15)
				(type solid)
			)
			(layer "F.SilkS")
		)
		(fp_rect
			(start -1.25 -0.65)
			(end 1.25 0.65)
			(stroke
				(width 0.05)
				(type solid)
			)
			(fill no)
			(layer "F.CrtYd")
		)
		(fp_rect
			(start -0.8 -0.4)
			(end 0.8 0.4)
			(stroke
				(width 0.15)
				(type solid)
			)
			(fill no)
			(layer "F.Fab")
		)
		(pad "1" smd roundrect
			(at -0.7 0)
			(size 0.8 1)
			(layers "F.Cu" "F.Mask" "F.Paste")
			(roundrect_rratio 0.2)
			(net 303 "/Power/+VCCD_OUT")
			(pintype "passive")
		)
		(pad "2" smd roundrect
			(at 0.7 0)
			(size 0.8 1)
			(layers "F.Cu" "F.Mask" "F.Paste")
			(roundrect_rratio 0.2)
			(net 9 "VCCD")
			(pintype "passive")
		)
	)
	(footprint "antmicro-footprints:L_Bourns-SRP4021HMT"
		(layer "F.Cu")
		(at 60.249999 96.149999 180)
		(property "Reference" "L5"
			(at -3.950001 0.459999 0)
			(layer "F.SilkS")
			(effects
				(font
					(size 0.7 0.7)
					(thickness 0.15)
				)
				(justify right top)
			)
		)
		(property "Value" "L_1u_10A_Bourns-SRP4021HMT"
			(at -2.85 3.4 0)
			(layer "F.Fab")
			(hide yes)
			(effects
				(font
					(size 0.7 0.7)
					(thickness 0.15)
				)
				(justify right top)
			)
		)
		(property "Datasheet" "https://www.mouser.com/datasheet/2/54/Bourns_04_01_2025_SRP4021HMT_Datasheet-3580094.pdf"
			(at 0 0 0)
			(layer "F.Fab")
			(hide yes)
			(effects
				(font
					(size 0.7 0.7)
					(thickness 0.15)
				)
				(justify right top)
			)
		)
		(property "Description" "Power Inductors - SMD Ind,4.1x4.2x1.9mm,1uH+/-20%,10A, Shielded"
			(at 0 0 0)
			(layer "F.Fab")
			(hide yes)
			(effects
				(font
					(size 0.7 0.7)
					(thickness 0.15)
				)
				(justify right top)
			)
		)
		(property "Val" "1u/10A"
			(at 0 0 180)
			(unlocked yes)
			(layer "F.Fab")
			(hide yes)
			(effects
				(font
					(size 1 1)
					(thickness 0.15)
				)
			)
		)
		(property "Manufacturer" "Bourns"
			(at 0 0 180)
			(unlocked yes)
			(layer "F.Fab")
			(hide yes)
			(effects
				(font
					(size 1 1)
					(thickness 0.15)
				)
			)
		)
		(property "MPN" "SRP4021HMT-1R0M"
			(at 0 0 180)
			(unlocked yes)
			(layer "F.Fab")
			(hide yes)
			(effects
				(font
					(size 1 1)
					(thickness 0.15)
				)
			)
		)
		(property "ISat" ""
			(at 0 0 180)
			(unlocked yes)
			(layer "F.Fab")
			(hide yes)
			(effects
				(font
					(size 1 1)
					(thickness 0.15)
				)
			)
		)
		(property "Isat" "8A"
			(at 0 0 180)
			(unlocked yes)
			(layer "F.Fab")
			(hide yes)
			(effects
				(font
					(size 1 1)
					(thickness 0.15)
				)
			)
		)
		(property "IMax" ""
			(at 0 0 180)
			(unlocked yes)
			(layer "F.Fab")
			(hide yes)
			(effects
				(font
					(size 1 1)
					(thickness 0.15)
				)
			)
		)
		(property "Imax" "10A"
			(at 0 0 180)
			(unlocked yes)
			(layer "F.Fab")
			(hide yes)
			(effects
				(font
					(size 1 1)
					(thickness 0.15)
				)
			)
		)
		(property "Size" "4.2x4.1"
			(at 0 0 180)
			(unlocked yes)
			(layer "F.Fab")
			(hide yes)
			(effects
				(font
					(size 1 1)
					(thickness 0.15)
				)
			)
		)
		(property "Author" "Antmicro"
			(at 0 0 180)
			(unlocked yes)
			(layer "F.Fab")
			(hide yes)
			(effects
				(font
					(size 1 1)
					(thickness 0.15)
				)
			)
		)
		(property "License" "Apache-2.0"
			(at 0 0 180)
			(unlocked yes)
			(layer "F.Fab")
			(hide yes)
			(effects
				(font
					(size 1 1)
					(thickness 0.15)
				)
			)
		)
		(sheetname "/Power/")
		(sheetfile "power.kicad_sch")
		(attr smd)
		(fp_line
			(start -0.8 2.05)
			(end 0.8 2.05)
			(stroke
				(width 0.15)
				(type solid)
			)
			(layer "F.SilkS")
		)
		(fp_line
			(start -0.8 -2.05)
			(end 0.8 -2.05)
			(stroke
				(width 0.15)
				(type solid)
			)
			(layer "F.SilkS")
		)
		(fp_rect
			(start -2.85 -2.3)
			(end 2.85 2.3)
			(stroke
				(width 0.05)
				(type solid)
			)
			(fill no)
			(layer "F.CrtYd")
		)
		(fp_rect
			(start -2 -2.05)
			(end 2 2.05)
			(stroke
				(width 0.15)
				(type solid)
			)
			(fill no)
			(layer "F.Fab")
		)
		(pad "1" smd rect
			(at 1.85 0)
			(size 1.5 3.5)
			(layers "F.Cu" "F.Mask" "F.Paste")
			(net 336 "/Power/DVDD_SW")
			(pintype "passive")
		)
		(pad "2" smd rect
			(at -1.85 0)
			(size 1.5 3.5)
			(layers "F.Cu" "F.Mask" "F.Paste")
			(net 311 "/Power/+DVDD_OUT")
			(pintype "passive")
		)
	)
	(footprint "antmicro-footprints:TP_SMD_0.75mm"
		(layer "F.Cu")
		(at 52.05 126.200001 180)
		(property "Reference" "TP20"
			(at 0.24 0.07 180)
			(layer "F.SilkS")
			(hide yes)
			(effects
				(font
					(size 0.7 0.7)
					(thickness 0.15)
				)
				(justify right top)
			)
		)
		(property "Value" "TP_0.75mm_SMD"
			(at 0 1.2 0)
			(layer "F.Fab")
			(hide yes)
			(effects
				(font
					(size 0.7 0.7)
					(thickness 0.15)
				)
				(justify right top)
			)
		)
		(property "Description" "SMT test point"
			(at 0 0 0)
			(layer "F.Fab")
			(hide yes)
			(effects
				(font
					(size 1.27 1.27)
					(thickness 0.15)
				)
			)
		)
		(property "MPN" ""
			(at 0 0 180)
			(unlocked yes)
			(layer "F.Fab")
			(hide yes)
			(effects
				(font
					(size 1 1)
					(thickness 0.15)
				)
			)
		)
		(property "Manufacturer" ""
			(at 0 0 180)
			(unlocked yes)
			(layer "F.Fab")
			(hide yes)
			(effects
				(font
					(size 1 1)
					(thickness 0.15)
				)
			)
		)
		(property "Author" "Antmicro"
			(at 0 0 180)
			(unlocked yes)
			(layer "F.Fab")
			(hide yes)
			(effects
				(font
					(size 1 1)
					(thickness 0.15)
				)
			)
		)
		(property "License" "Apache-2.0"
			(at 0 0 180)
			(unlocked yes)
			(layer "F.Fab")
			(hide yes)
			(effects
				(font
					(size 1 1)
					(thickness 0.15)
				)
			)
		)
		(sheetname "/Power/")
		(sheetfile "power.kicad_sch")
		(attr exclude_from_pos_files exclude_from_bom)
		(fp_circle
			(center 0 0)
			(end 0.475 0)
			(stroke
				(width 0.05)
				(type default)
			)
			(fill no)
			(layer "F.CrtYd")
		)
		(pad "1" smd circle
			(at 0 0 180)
			(size 0.75 0.75)
			(layers "F.Cu" "F.Mask")
			(net 303 "/Power/+VCCD_OUT")
			(pinfunction "1")
			(pintype "passive")
		)
	)
	(footprint "antmicro-footprints:C_0603_1608Metric_EIA"
		(layer "F.Cu")
		(at 66.7 92.049999 180)
		(descr "Capacitor SMD 0603, IPC-7351 Density Level A")
		(tags "Capacitor 0603")
		(property "Reference" "C80"
			(at -3.22 -0.120001 0)
			(layer "F.SilkS")
			(effects
				(font
					(size 0.7 0.7)
					(thickness 0.15)
				)
				(justify right top)
			)
		)
		(property "Value" "C_22u_16V_0603"
			(at -1.42757 1.770288 0)
			(layer "F.Fab")
			(hide yes)
			(effects
				(font
					(size 0.7 0.7)
					(thickness 0.15)
				)
				(justify right top)
			)
		)
		(property "Datasheet" "https://product.samsungsem.com/mlcc/CL10A226MO7JZN.do"
			(at 0 0 0)
			(layer "F.Fab")
			(hide yes)
			(effects
				(font
					(size 1.27 1.27)
					(thickness 0.15)
				)
			)
		)
		(property "Description" "SMD Multilayer Ceramic Capacitor"
			(at 0 0 0)
			(layer "F.Fab")
			(hide yes)
			(effects
				(font
					(size 1.27 1.27)
					(thickness 0.15)
				)
			)
		)
		(property "MPN" "CL10A226MO7JZNC"
			(at 0 0 180)
			(unlocked yes)
			(layer "F.Fab")
			(hide yes)
			(effects
				(font
					(size 1 1)
					(thickness 0.15)
				)
			)
		)
		(property "Manufacturer" "Samsung Electro-Mechanics"
			(at 0 0 180)
			(unlocked yes)
			(layer "F.Fab")
			(hide yes)
			(effects
				(font
					(size 1 1)
					(thickness 0.15)
				)
			)
		)
		(property "License" "Apache-2.0"
			(at 0 0 180)
			(unlocked yes)
			(layer "F.Fab")
			(hide yes)
			(effects
				(font
					(size 1 1)
					(thickness 0.15)
				)
			)
		)
		(property "Author" "Antmicro"
			(at 0 0 180)
			(unlocked yes)
			(layer "F.Fab")
			(hide yes)
			(effects
				(font
					(size 1 1)
					(thickness 0.15)
				)
			)
		)
		(property "Val" "22u"
			(at 0 0 180)
			(unlocked yes)
			(layer "F.Fab")
			(hide yes)
			(effects
				(font
					(size 1 1)
					(thickness 0.15)
				)
			)
		)
		(property "Voltage" "16V"
			(at 0 0 180)
			(unlocked yes)
			(layer "F.Fab")
			(hide yes)
			(effects
				(font
					(size 1 1)
					(thickness 0.15)
				)
			)
		)
		(property "Dielectric" ""
			(at 0 0 180)
			(unlocked yes)
			(layer "F.Fab")
			(hide yes)
			(effects
				(font
					(size 1 1)
					(thickness 0.15)
				)
			)
		)
		(sheetname "/X710-AT2 power/")
		(sheetfile "x710-at2-power.kicad_sch")
		(attr smd)
		(fp_line
			(start -0.15 0.55)
			(end 0.15 0.55)
			(stroke
				(width 0.15)
				(type solid)
			)
			(layer "F.SilkS")
		)
		(fp_line
			(start -0.15 -0.55)
			(end 0.15 -0.55)
			(stroke
				(width 0.15)
				(type solid)
			)
			(layer "F.SilkS")
		)
		(fp_rect
			(start -1.25 -0.65)
			(end 1.25 0.65)
			(stroke
				(width 0.05)
				(type solid)
			)
			(fill no)
			(layer "F.CrtYd")
		)
		(fp_rect
			(start -0.8 -0.45)
			(end 0.8 0.45)
			(stroke
				(width 0.15)
				(type solid)
			)
			(fill no)
			(layer "F.Fab")
		)
		(pad "1" smd roundrect
			(at -0.7 0 180)
			(size 0.8 1.1)
			(layers "F.Cu" "F.Mask" "F.Paste")
			(roundrect_rratio 0.2)
			(net 28 "GND")
			(pintype "passive")
		)
		(pad "2" smd roundrect
			(at 0.7 0 180)
			(size 0.8 1.1)
			(layers "F.Cu" "F.Mask" "F.Paste")
			(roundrect_rratio 0.2)
			(net 6 "DVDD")
			(pintype "passive")
		)
	)
	(footprint "antmicro-footprints:C_0402_1005Metric"
		(layer "F.Cu")
		(at 56.399999 113.200001)
		(descr "Capacitor SMD 0402")
		(tags "capacitor SMD 0402")
		(property "Reference" "C28"
			(at -0.749999 1.349999 0)
			(layer "F.SilkS")
			(effects
				(font
					(size 0.7 0.7)
					(thickness 0.15)
				)
				(justify left bottom)
			)
		)
		(property "Value" "C_100n_0402"
			(at -1.022927 2.155213 0)
			(layer "F.Fab")
			(hide yes)
			(effects
				(font
					(size 0.7 0.7)
					(thickness 0.15)
				)
				(justify left bottom)
			)
		)
		(property "Datasheet" "https://www.murata.com/products/productdetail?partno=GRM155R61H104KE14%23"
			(at 0 0 0)
			(layer "F.Fab")
			(hide yes)
			(effects
				(font
					(size 1.27 1.27)
					(thickness 0.15)
				)
			)
		)
		(property "Description" "SMD Multilayer Ceramic Capacitor, 0.1 µF, 50 V, 0402 [1005 Metric], ± 10%, X5R, GRM Series"
			(at 0 0 0)
			(layer "F.Fab")
			(hide yes)
			(effects
				(font
					(size 1.27 1.27)
					(thickness 0.15)
				)
			)
		)
		(property "MPN" "GRM155R61H104KE14D"
			(at 0 0 0)
			(unlocked yes)
			(layer "F.Fab")
			(hide yes)
			(effects
				(font
					(size 1 1)
					(thickness 0.15)
				)
			)
		)
		(property "Manufacturer" "Murata"
			(at 0 0 0)
			(unlocked yes)
			(layer "F.Fab")
			(hide yes)
			(effects
				(font
					(size 1 1)
					(thickness 0.15)
				)
			)
		)
		(property "License" "Apache-2.0"
			(at 0 0 0)
			(unlocked yes)
			(layer "F.Fab")
			(hide yes)
			(effects
				(font
					(size 1 1)
					(thickness 0.15)
				)
			)
		)
		(property "Author" "Antmicro"
			(at 0 0 0)
			(unlocked yes)
			(layer "F.Fab")
			(hide yes)
			(effects
				(font
					(size 1 1)
					(thickness 0.15)
				)
			)
		)
		(property "Val" "100n"
			(at 0 0 0)
			(unlocked yes)
			(layer "F.Fab")
			(hide yes)
			(effects
				(font
					(size 1 1)
					(thickness 0.15)
				)
			)
		)
		(property "Voltage" "50V"
			(at 0 0 0)
			(unlocked yes)
			(layer "F.Fab")
			(hide yes)
			(effects
				(font
					(size 1 1)
					(thickness 0.15)
				)
			)
		)
		(property "Dielectric" "X5R"
			(at 0 0 0)
			(unlocked yes)
			(layer "F.Fab")
			(hide yes)
			(effects
				(font
					(size 1 1)
					(thickness 0.15)
				)
			)
		)
		(sheetname "/Power/")
		(sheetfile "power.kicad_sch")
		(attr smd)
		(fp_rect
			(start -0.925 -0.47)
			(end 0.925 0.47)
			(stroke
				(width 0.05)
				(type default)
			)
			(fill no)
			(layer "F.CrtYd")
		)
		(fp_line
			(start -0.494 -0.25)
			(end 0.504 -0.25)
			(stroke
				(width 0.15)
				(type solid)
			)
			(layer "F.Fab")
		)
		(fp_line
			(start -0.494 0.248)
			(end -0.494 -0.25)
			(stroke
				(width 0.15)
				(type solid)
			)
			(layer "F.Fab")
		)
		(fp_line
			(start 0.504 -0.25)
			(end 0.504 0.248)
			(stroke
				(width 0.15)
				(type solid)
			)
			(layer "F.Fab")
		)
		(fp_line
			(start 0.504 0.248)
			(end -0.494 0.248)
			(stroke
				(width 0.15)
				(type solid)
			)
			(layer "F.Fab")
		)
		(pad "1" smd roundrect
			(at -0.48 0)
			(size 0.59 0.64)
			(layers "F.Cu" "F.Mask" "F.Paste")
			(roundrect_rratio 0.25)
			(net 327 "/Power/1V0_BST")
			(pintype "passive")
		)
		(pad "2" smd roundrect
			(at 0.48 0)
			(size 0.59 0.64)
			(layers "F.Cu" "F.Mask" "F.Paste")
			(roundrect_rratio 0.25)
			(net 337 "/Power/1V0_SW")
			(pintype "passive")
		)
	)
	(footprint "antmicro-footprints:R_0402_1005Metric"
		(layer "F.Cu")
		(at 113.15 100.1 -90)
		(descr "Resistor SMD 0402")
		(tags "resistor SMD 0402")
		(property "Reference" "R178"
			(at -0.8 -0.45 90)
			(layer "F.SilkS")
			(effects
				(font
					(size 0.7 0.7)
					(thickness 0.15)
				)
				(justify left bottom)
			)
		)
		(property "Value" "R_1k_0402"
			(at -1.011843 1.772046 90)
			(layer "F.Fab")
			(hide yes)
			(effects
				(font
					(size 0.7 0.7)
					(thickness 0.15)
				)
				(justify right top)
			)
		)
		(property "Datasheet" "https://www.bourns.com/docs/product-datasheets/cr.pdf"
			(at 0 0 90)
			(layer "F.Fab")
			(hide yes)
			(effects
				(font
					(size 1.27 1.27)
					(thickness 0.15)
				)
			)
		)
		(property "Description" "SMD Chip Resistor, 1 kohm, ± 1%, 63 mW, 0402 [1005 Metric], Thick Film, General Purpose"
			(at 0 0 90)
			(layer "F.Fab")
			(hide yes)
			(effects
				(font
					(size 1.27 1.27)
					(thickness 0.15)
				)
			)
		)
		(property "MPN" "CR0402-FX-1001GLF"
			(at 0 0 270)
			(unlocked yes)
			(layer "F.Fab")
			(hide yes)
			(effects
				(font
					(size 1 1)
					(thickness 0.15)
				)
			)
		)
		(property "Manufacturer" "Bourns"
			(at 0 0 270)
			(unlocked yes)
			(layer "F.Fab")
			(hide yes)
			(effects
				(font
					(size 1 1)
					(thickness 0.15)
				)
			)
		)
		(property "License" "Apache-2.0"
			(at 0 0 270)
			(unlocked yes)
			(layer "F.Fab")
			(hide yes)
			(effects
				(font
					(size 1 1)
					(thickness 0.15)
				)
			)
		)
		(property "Author" "Antmicro"
			(at 0 0 270)
			(unlocked yes)
			(layer "F.Fab")
			(hide yes)
			(effects
				(font
					(size 1 1)
					(thickness 0.15)
				)
			)
		)
		(property "Val" "1k"
			(at 0 0 270)
			(unlocked yes)
			(layer "F.Fab")
			(hide yes)
			(effects
				(font
					(size 1 1)
					(thickness 0.15)
				)
			)
		)
		(property "Tolerance" "1%"
			(at 0 0 270)
			(unlocked yes)
			(layer "F.Fab")
			(hide yes)
			(effects
				(font
					(size 1 1)
					(thickness 0.15)
				)
			)
		)
		(sheetname "/Fan controller/")
		(sheetfile "fan-controller.kicad_sch")
		(attr smd exclude_from_pos_files exclude_from_bom dnp)
		(fp_rect
			(start -0.925 -0.47)
			(end 0.925 0.47)
			(stroke
				(width 0.05)
				(type default)
			)
			(fill no)
			(layer "F.CrtYd")
		)
		(fp_rect
			(start -0.5 -0.25)
			(end 0.5 0.25)
			(stroke
				(width 0.15)
				(type solid)
			)
			(fill no)
			(layer "F.Fab")
		)
		(pad "1" smd roundrect
			(at -0.48 0 270)
			(size 0.59 0.64)
			(layers "F.Cu" "F.Mask" "F.Paste")
			(roundrect_rratio 0.25)
			(net 28 "GND")
			(pintype "passive")
		)
		(pad "2" smd roundrect
			(at 0.48 0 270)
			(size 0.59 0.64)
			(layers "F.Cu" "F.Mask" "F.Paste")
			(roundrect_rratio 0.25)
			(net 399 "/Fan controller/DMIN")
			(pintype "passive")
		)
	)
	(footprint "antmicro-footprints:R_0402_1005Metric"
		(layer "F.Cu")
		(at 116.95 107.5 180)
		(descr "Resistor SMD 0402")
		(tags "resistor SMD 0402")
		(property "Reference" "R174"
			(at 0.85 0.35 0)
			(layer "F.SilkS")
			(effects
				(font
					(size 0.7 0.7)
					(thickness 0.15)
				)
				(justify right top)
			)
		)
		(property "Value" "R_0R_0402"
			(at -1.011843 1.772046 0)
			(layer "F.Fab")
			(hide yes)
			(effects
				(font
					(size 0.7 0.7)
					(thickness 0.15)
				)
				(justify right top)
			)
		)
		(property "Datasheet" "https://industrial.panasonic.com/cdbs/www-data/pdf/RDA0000/AOA0000C301.pdf"
			(at 0 0 0)
			(layer "F.Fab")
			(hide yes)
			(effects
				(font
					(size 1.27 1.27)
					(thickness 0.15)
				)
			)
		)
		(property "Description" "SMD Chip Resistor, Jumper, 0 ohm, 100 mW, 0402 [1005 Metric], Thick Film, General Purpose"
			(at 0 0 0)
			(layer "F.Fab")
			(hide yes)
			(effects
				(font
					(size 1.27 1.27)
					(thickness 0.15)
				)
			)
		)
		(property "MPN" "ERJ2GE0R00X"
			(at 0 0 180)
			(unlocked yes)
			(layer "F.Fab")
			(hide yes)
			(effects
				(font
					(size 1 1)
					(thickness 0.15)
				)
			)
		)
		(property "Manufacturer" "Panasonic"
			(at 0 0 180)
			(unlocked yes)
			(layer "F.Fab")
			(hide yes)
			(effects
				(font
					(size 1 1)
					(thickness 0.15)
				)
			)
		)
		(property "License" "Apache-2.0"
			(at 0 0 180)
			(unlocked yes)
			(layer "F.Fab")
			(hide yes)
			(effects
				(font
					(size 1 1)
					(thickness 0.15)
				)
			)
		)
		(property "Author" "Antmicro"
			(at 0 0 180)
			(unlocked yes)
			(layer "F.Fab")
			(hide yes)
			(effects
				(font
					(size 1 1)
					(thickness 0.15)
				)
			)
		)
		(property "Val" "0R"
			(at 0 0 180)
			(unlocked yes)
			(layer "F.Fab")
			(hide yes)
			(effects
				(font
					(size 1 1)
					(thickness 0.15)
				)
			)
		)
		(property "Tolerance" "~"
			(at 0 0 180)
			(unlocked yes)
			(layer "F.Fab")
			(hide yes)
			(effects
				(font
					(size 1 1)
					(thickness 0.15)
				)
			)
		)
		(property "Current" "1A"
			(at 0 0 180)
			(unlocked yes)
			(layer "F.Fab")
			(hide yes)
			(effects
				(font
					(size 1 1)
					(thickness 0.15)
				)
			)
		)
		(sheetname "/Fan controller/")
		(sheetfile "fan-controller.kicad_sch")
		(attr smd exclude_from_pos_files exclude_from_bom dnp)
		(fp_rect
			(start -0.925 -0.47)
			(end 0.925 0.47)
			(stroke
				(width 0.05)
				(type default)
			)
			(fill no)
			(layer "F.CrtYd")
		)
		(fp_rect
			(start -0.5 -0.25)
			(end 0.5 0.25)
			(stroke
				(width 0.15)
				(type solid)
			)
			(fill no)
			(layer "F.Fab")
		)
		(pad "1" smd roundrect
			(at -0.48 0 180)
			(size 0.59 0.64)
			(layers "F.Cu" "F.Mask" "F.Paste")
			(roundrect_rratio 0.25)
			(net 389 "/Fan controller/V_{FAN}")
			(pintype "passive")
		)
		(pad "2" smd roundrect
			(at 0.48 0 180)
			(size 0.59 0.64)
			(layers "F.Cu" "F.Mask" "F.Paste")
			(roundrect_rratio 0.25)
			(net 388 "/Fan controller/+5V")
			(pintype "passive")
		)
	)
	(footprint "antmicro-footprints:LED_0603_1608Metric_G"
		(layer "F.Cu")
		(at 52.3 78 -90)
		(descr "LED SMD 0603 Green")
		(tags "LED SMD 0603 Green")
		(property "Reference" "D11"
			(at -3.3 -0.25 90)
			(layer "F.SilkS")
			(effects
				(font
					(size 0.7 0.7)
					(thickness 0.15)
				)
				(justify right top)
			)
		)
		(property "Value" "LED_G_0603_LG_L29K-G2J1-24-Z"
			(at -0.001 1.599 90)
			(layer "F.Fab")
			(hide yes)
			(effects
				(font
					(size 0.7 0.7)
					(thickness 0.15)
				)
				(justify right top)
			)
		)
		(property "Datasheet" "https://look.ams-osram.com/m/19ee86b3ae0ee95b/original/LG-L29K.pdf"
			(at 0 0 90)
			(layer "F.Fab")
			(hide yes)
			(effects
				(font
					(size 1.27 1.27)
					(thickness 0.15)
				)
			)
		)
		(property "Description" "LED, Green, SMD, 0603, 20 mA, 1.7 V, 570 nm"
			(at 0 0 90)
			(layer "F.Fab")
			(hide yes)
			(effects
				(font
					(size 1.27 1.27)
					(thickness 0.15)
				)
			)
		)
		(property "MPN" "LG L29K-G2J1-24-Z"
			(at 0 0 270)
			(unlocked yes)
			(layer "F.Fab")
			(hide yes)
			(effects
				(font
					(size 1 1)
					(thickness 0.15)
				)
			)
		)
		(property "Manufacturer" "OSRAM"
			(at 0 0 270)
			(unlocked yes)
			(layer "F.Fab")
			(hide yes)
			(effects
				(font
					(size 1 1)
					(thickness 0.15)
				)
			)
		)
		(property "Color" "Green"
			(at 0 0 270)
			(unlocked yes)
			(layer "F.Fab")
			(hide yes)
			(effects
				(font
					(size 1 1)
					(thickness 0.15)
				)
			)
		)
		(property "Author" "Antmicro"
			(at 0 0 270)
			(unlocked yes)
			(layer "F.Fab")
			(hide yes)
			(effects
				(font
					(size 1 1)
					(thickness 0.15)
				)
			)
		)
		(property "License" "Apache-2.0"
			(at 0 0 270)
			(unlocked yes)
			(layer "F.Fab")
			(hide yes)
			(effects
				(font
					(size 1 1)
					(thickness 0.15)
				)
			)
		)
		(sheetname "/Power/")
		(sheetfile "power.kicad_sch")
		(attr smd)
		(fp_line
			(start 0.22 0.35)
			(end -0.22 0.35)
			(stroke
				(width 0.15)
				(type solid)
			)
			(layer "F.SilkS")
		)
		(fp_line
			(start -0.094672 0.201008)
			(end -0.094672 -0.198992)
			(stroke
				(width 0.1)
				(type solid)
			)
			(layer "F.SilkS")
		)
		(fp_line
			(start 0.105328 0.201008)
			(end -0.094672 0.001008)
			(stroke
				(width 0.1)
				(type solid)
			)
			(layer "F.SilkS")
		)
		(fp_line
			(start 0.105328 0.201008)
			(end 0.105328 -0.198992)
			(stroke
				(width 0.1)
				(type solid)
			)
			(layer "F.SilkS")
		)
		(fp_line
			(start -0.094672 0.001008)
			(end -0.24 0.001008)
			(stroke
				(width 0.1)
				(type solid)
			)
			(layer "F.SilkS")
		)
		(fp_line
			(start -0.094672 0.001008)
			(end 0.105328 -0.198992)
			(stroke
				(width 0.1)
				(type solid)
			)
			(layer "F.SilkS")
		)
		(fp_line
			(start 0.105328 0.001008)
			(end 0.24 0.001)
			(stroke
				(width 0.1)
				(type solid)
			)
			(layer "F.SilkS")
		)
		(fp_line
			(start -1.18 -0.319)
			(end -1.18 0.321)
			(stroke
				(width 0.15)
				(type solid)
			)
			(layer "F.SilkS")
		)
		(fp_line
			(start 0.22 -0.35)
			(end -0.22 -0.35)
			(stroke
				(width 0.15)
				(type solid)
			)
			(layer "F.SilkS")
		)
		(fp_rect
			(start 1.25 0.65)
			(end -1.25 -0.65)
			(stroke
				(width 0.05)
				(type solid)
			)
			(fill no)
			(layer "F.CrtYd")
		)
		(fp_line
			(start -0.199 0.2)
			(end -0.199 0.1)
			(stroke
				(width 0.15)
				(type solid)
			)
			(layer "F.Fab")
		)
		(fp_line
			(start 0.201 0.2)
			(end 0.201 0)
			(stroke
				(width 0.15)
				(type solid)
			)
			(layer "F.Fab")
		)
		(fp_line
			(start -0.199 0)
			(end -0.597 0)
			(stroke
				(width 0.15)
				(type solid)
			)
			(layer "F.Fab")
		)
		(fp_line
			(start -0.101 0)
			(end 0.201 0.2)
			(stroke
				(width 0.15)
				(type solid)
			)
			(layer "F.Fab")
		)
		(fp_line
			(start 0.201 0)
			(end 0.201 -0.202)
			(stroke
				(width 0.15)
				(type solid)
			)
			(layer "F.Fab")
		)
		(fp_line
			(start 0.599 0)
			(end 0.201 0)
			(stroke
				(width 0.15)
				(type solid)
			)
			(layer "F.Fab")
		)
		(fp_line
			(start -0.199 -0.202)
			(end -0.199 0.1)
			(stroke
				(width 0.15)
				(type solid)
			)
			(layer "F.Fab")
		)
		(fp_line
			(start 0.201 -0.202)
			(end -0.101 0)
			(stroke
				(width 0.15)
				(type solid)
			)
			(layer "F.Fab")
		)
		(fp_rect
			(start 0.848 0.4)
			(end -0.85 -0.402)
			(stroke
				(width 0.15)
				(type solid)
			)
			(fill no)
			(layer "F.Fab")
		)
		(fp_text user "License: Apache-2.0"
			(at -1.4224 3.599 270)
			(layer "F.Fab")
			(effects
				(font
					(size 0.7 0.7)
					(thickness 0.15)
				)
				(justify left bottom)
			)
		)
		(fp_text user "${REFERENCE}"
			(at -1.4224 5.999 270)
			(layer "F.Fab")
			(effects
				(font
					(size 0.7 0.7)
					(thickness 0.15)
				)
				(justify left bottom)
			)
		)
		(fp_text user "Author: Antmicro"
			(at -1.4224 4.799 270)
			(layer "F.Fab")
			(effects
				(font
					(size 0.7 0.7)
					(thickness 0.15)
				)
				(justify left bottom)
			)
		)
		(pad "1" smd roundrect
			(at -0.7 0 90)
			(size 0.8 1)
			(layers "F.Cu" "F.Mask" "F.Paste")
			(roundrect_rratio 0.2)
			(net 89 "Net-(D11-C)")
			(pinfunction "C")
			(pintype "passive")
		)
		(pad "2" smd roundrect
			(at 0.7 0 90)
			(size 0.8 1)
			(layers "F.Cu" "F.Mask" "F.Paste")
			(roundrect_rratio 0.2)
			(net 79 "Net-(D11-A)")
			(pinfunction "A")
			(pintype "passive")
		)
	)
	(footprint "antmicro-footprints:R_0402_1005Metric"
		(layer "F.Cu")
		(at 57.15 127.45 180)
		(descr "Resistor SMD 0402")
		(tags "resistor SMD 0402")
		(property "Reference" "R144"
			(at -1.5 -0.772697 0)
			(layer "F.SilkS")
			(effects
				(font
					(size 0.7 0.7)
					(thickness 0.15)
				)
				(justify right top)
			)
		)
		(property "Value" "R_1k_0402"
			(at -1.011843 1.772046 0)
			(layer "F.Fab")
			(hide yes)
			(effects
				(font
					(size 0.7 0.7)
					(thickness 0.15)
				)
				(justify right top)
			)
		)
		(property "Datasheet" "https://www.bourns.com/docs/product-datasheets/cr.pdf"
			(at 0 0 0)
			(layer "F.Fab")
			(hide yes)
			(effects
				(font
					(size 1.27 1.27)
					(thickness 0.15)
				)
			)
		)
		(property "Description" "SMD Chip Resistor, 1 kohm, ± 1%, 63 mW, 0402 [1005 Metric], Thick Film, General Purpose"
			(at 0 0 0)
			(layer "F.Fab")
			(hide yes)
			(effects
				(font
					(size 1.27 1.27)
					(thickness 0.15)
				)
			)
		)
		(property "MPN" "CR0402-FX-1001GLF"
			(at 0 0 180)
			(unlocked yes)
			(layer "F.Fab")
			(hide yes)
			(effects
				(font
					(size 1 1)
					(thickness 0.15)
				)
			)
		)
		(property "Manufacturer" "Bourns"
			(at 0 0 180)
			(unlocked yes)
			(layer "F.Fab")
			(hide yes)
			(effects
				(font
					(size 1 1)
					(thickness 0.15)
				)
			)
		)
		(property "License" "Apache-2.0"
			(at 0 0 180)
			(unlocked yes)
			(layer "F.Fab")
			(hide yes)
			(effects
				(font
					(size 1 1)
					(thickness 0.15)
				)
			)
		)
		(property "Author" "Antmicro"
			(at 0 0 180)
			(unlocked yes)
			(layer "F.Fab")
			(hide yes)
			(effects
				(font
					(size 1 1)
					(thickness 0.15)
				)
			)
		)
		(property "Val" "1k"
			(at 0 0 180)
			(unlocked yes)
			(layer "F.Fab")
			(hide yes)
			(effects
				(font
					(size 1 1)
					(thickness 0.15)
				)
			)
		)
		(property "Tolerance" "1%"
			(at 0 0 180)
			(unlocked yes)
			(layer "F.Fab")
			(hide yes)
			(effects
				(font
					(size 1 1)
					(thickness 0.15)
				)
			)
		)
		(sheetname "/Power/")
		(sheetfile "power.kicad_sch")
		(attr smd)
		(fp_poly
			(pts
				(xy -0.925 -0.47) (xy 0.925 -0.47) (xy 0.925 0.47) (xy -0.925 0.47)
			)
			(stroke
				(width 0.05)
				(type default)
			)
			(fill no)
			(layer "F.CrtYd")
		)
		(fp_poly
			(pts
				(xy -0.5 -0.25) (xy 0.5 -0.25) (xy 0.5 0.25) (xy -0.5 0.25)
			)
			(stroke
				(width 0.15)
				(type solid)
			)
			(fill no)
			(layer "F.Fab")
		)
		(pad "1" smd roundrect
			(at -0.48 0 180)
			(size 0.59 0.64)
			(layers "F.Cu" "F.Mask" "F.Paste")
			(roundrect_rratio 0.25)
			(net 28 "GND")
			(pintype "passive")
		)
		(pad "2" smd roundrect
			(at 0.48 0 180)
			(size 0.59 0.64)
			(layers "F.Cu" "F.Mask" "F.Paste")
			(roundrect_rratio 0.25)
			(net 415 "Net-(D16-C)")
			(pintype "passive")
		)
	)
	(footprint "antmicro-footprints:C_0603_1608Metric_EIA"
		(layer "F.Cu")
		(at 66.7 83.5 180)
		(descr "Capacitor SMD 0603, IPC-7351 Density Level A")
		(tags "Capacitor 0603")
		(property "Reference" "C123"
			(at -1.95 4.56 0)
			(layer "F.SilkS")
			(effects
				(font
					(size 0.7 0.7)
					(thickness 0.15)
				)
				(justify right top)
			)
		)
		(property "Value" "C_22u_16V_0603"
			(at -1.42757 1.770288 0)
			(layer "F.Fab")
			(hide yes)
			(effects
				(font
					(size 0.7 0.7)
					(thickness 0.15)
				)
				(justify right top)
			)
		)
		(property "Datasheet" "https://product.samsungsem.com/mlcc/CL10A226MO7JZN.do"
			(at 0 0 0)
			(layer "F.Fab")
			(hide yes)
			(effects
				(font
					(size 1.27 1.27)
					(thickness 0.15)
				)
			)
		)
		(property "Description" "SMD Multilayer Ceramic Capacitor"
			(at 0 0 0)
			(layer "F.Fab")
			(hide yes)
			(effects
				(font
					(size 1.27 1.27)
					(thickness 0.15)
				)
			)
		)
		(property "MPN" "CL10A226MO7JZNC"
			(at 0 0 180)
			(unlocked yes)
			(layer "F.Fab")
			(hide yes)
			(effects
				(font
					(size 1 1)
					(thickness 0.15)
				)
			)
		)
		(property "Manufacturer" "Samsung Electro-Mechanics"
			(at 0 0 180)
			(unlocked yes)
			(layer "F.Fab")
			(hide yes)
			(effects
				(font
					(size 1 1)
					(thickness 0.15)
				)
			)
		)
		(property "License" "Apache-2.0"
			(at 0 0 180)
			(unlocked yes)
			(layer "F.Fab")
			(hide yes)
			(effects
				(font
					(size 1 1)
					(thickness 0.15)
				)
			)
		)
		(property "Author" "Antmicro"
			(at 0 0 180)
			(unlocked yes)
			(layer "F.Fab")
			(hide yes)
			(effects
				(font
					(size 1 1)
					(thickness 0.15)
				)
			)
		)
		(property "Val" "22u"
			(at 0 0 180)
			(unlocked yes)
			(layer "F.Fab")
			(hide yes)
			(effects
				(font
					(size 1 1)
					(thickness 0.15)
				)
			)
		)
		(property "Voltage" "16V"
			(at 0 0 180)
			(unlocked yes)
			(layer "F.Fab")
			(hide yes)
			(effects
				(font
					(size 1 1)
					(thickness 0.15)
				)
			)
		)
		(property "Dielectric" ""
			(at 0 0 180)
			(unlocked yes)
			(layer "F.Fab")
			(hide yes)
			(effects
				(font
					(size 1 1)
					(thickness 0.15)
				)
			)
		)
		(sheetname "/X710-AT2 power/")
		(sheetfile "x710-at2-power.kicad_sch")
		(attr smd)
		(fp_line
			(start -0.15 0.55)
			(end 0.15 0.55)
			(stroke
				(width 0.15)
				(type solid)
			)
			(layer "F.SilkS")
		)
		(fp_line
			(start -0.15 -0.55)
			(end 0.15 -0.55)
			(stroke
				(width 0.15)
				(type solid)
			)
			(layer "F.SilkS")
		)
		(fp_rect
			(start -1.25 -0.65)
			(end 1.25 0.65)
			(stroke
				(width 0.05)
				(type solid)
			)
			(fill no)
			(layer "F.CrtYd")
		)
		(fp_rect
			(start -0.8 -0.45)
			(end 0.8 0.45)
			(stroke
				(width 0.15)
				(type solid)
			)
			(fill no)
			(layer "F.Fab")
		)
		(pad "1" smd roundrect
			(at -0.7 0 180)
			(size 0.8 1.1)
			(layers "F.Cu" "F.Mask" "F.Paste")
			(roundrect_rratio 0.2)
			(net 28 "GND")
			(pintype "passive")
		)
		(pad "2" smd roundrect
			(at 0.7 0 180)
			(size 0.8 1.1)
			(layers "F.Cu" "F.Mask" "F.Paste")
			(roundrect_rratio 0.2)
			(net 9 "VCCD")
			(pintype "passive")
		)
	)
	(footprint "antmicro-footprints:TP_SMD_0.75mm"
		(layer "F.Cu")
		(at 52.05 128.55 -90)
		(property "Reference" "TP21"
			(at -3.05 0.31 90)
			(layer "F.SilkS")
			(hide yes)
			(effects
				(font
					(size 0.7 0.7)
					(thickness 0.15)
				)
				(justify right top)
			)
		)
		(property "Value" "TP_0.75mm_SMD"
			(at 0 1.2 90)
			(layer "F.Fab")
			(hide yes)
			(effects
				(font
					(size 0.7 0.7)
					(thickness 0.15)
				)
				(justify right top)
			)
		)
		(property "Description" "SMT test point"
			(at 0 0 90)
			(layer "F.Fab")
			(hide yes)
			(effects
				(font
					(size 1.27 1.27)
					(thickness 0.15)
				)
			)
		)
		(property "MPN" ""
			(at 0 0 270)
			(unlocked yes)
			(layer "F.Fab")
			(hide yes)
			(effects
				(font
					(size 1 1)
					(thickness 0.15)
				)
			)
		)
		(property "Manufacturer" ""
			(at 0 0 270)
			(unlocked yes)
			(layer "F.Fab")
			(hide yes)
			(effects
				(font
					(size 1 1)
					(thickness 0.15)
				)
			)
		)
		(property "Author" "Antmicro"
			(at 0 0 270)
			(unlocked yes)
			(layer "F.Fab")
			(hide yes)
			(effects
				(font
					(size 1 1)
					(thickness 0.15)
				)
			)
		)
		(property "License" "Apache-2.0"
			(at 0 0 270)
			(unlocked yes)
			(layer "F.Fab")
			(hide yes)
			(effects
				(font
					(size 1 1)
					(thickness 0.15)
				)
			)
		)
		(sheetname "/Power/")
		(sheetfile "power.kicad_sch")
		(attr exclude_from_pos_files exclude_from_bom)
		(fp_circle
			(center 0 0)
			(end 0.475 0)
			(stroke
				(width 0.05)
				(type default)
			)
			(fill no)
			(layer "F.CrtYd")
		)
		(pad "1" smd circle
			(at 0 0 270)
			(size 0.75 0.75)
			(layers "F.Cu" "F.Mask")
			(net 255 "/Power/+3V3_OUT")
			(pinfunction "1")
			(pintype "passive")
		)
	)
	(footprint "antmicro-footprints:C_0603_1608Metric"
		(layer "F.Cu")
		(at 97.9 102 180)
		(descr "Capacitor SMD 0603")
		(tags "capacitor 0603")
		(property "Reference" "C149"
			(at -3.75 0.35 0)
			(layer "F.SilkS")
			(effects
				(font
					(size 0.7 0.7)
					(thickness 0.15)
				)
				(justify left top)
			)
		)
		(property "Value" "C_10u_10V_X7R_0603"
			(at -1.42757 1.770288 0)
			(layer "F.Fab")
			(hide yes)
			(effects
				(font
					(size 0.7 0.7)
					(thickness 0.15)
				)
				(justify right top)
			)
		)
		(property "Datasheet" "https://www.murata.com/products/productdetail?partno=GRM188Z71A106KA73%23"
			(at 0 0 0)
			(layer "F.Fab")
			(hide yes)
			(effects
				(font
					(size 1.27 1.27)
					(thickness 0.15)
				)
			)
		)
		(property "Description" "SMD Multilayer Ceramic Capacitor,  10µF, 10V, 0603, ±10%, X7R"
			(at 0 0 0)
			(layer "F.Fab")
			(hide yes)
			(effects
				(font
					(size 1.27 1.27)
					(thickness 0.15)
				)
			)
		)
		(property "MPN" "GRM188Z71A106KA73D"
			(at 0 0 180)
			(unlocked yes)
			(layer "F.Fab")
			(hide yes)
			(effects
				(font
					(size 1 1)
					(thickness 0.15)
				)
			)
		)
		(property "Val" "10u"
			(at 0 0 180)
			(unlocked yes)
			(layer "F.Fab")
			(hide yes)
			(effects
				(font
					(size 1 1)
					(thickness 0.15)
				)
			)
		)
		(property "Voltage" "10V"
			(at 0 0 180)
			(unlocked yes)
			(layer "F.Fab")
			(hide yes)
			(effects
				(font
					(size 1 1)
					(thickness 0.15)
				)
			)
		)
		(property "Dielectric" "X7R"
			(at 0 0 180)
			(unlocked yes)
			(layer "F.Fab")
			(hide yes)
			(effects
				(font
					(size 1 1)
					(thickness 0.15)
				)
			)
		)
		(property "Manufacturer" "Murata"
			(at 0 0 180)
			(unlocked yes)
			(layer "F.Fab")
			(hide yes)
			(effects
				(font
					(size 1 1)
					(thickness 0.15)
				)
			)
		)
		(property "License" "Apache-2.0"
			(at 0 0 180)
			(unlocked yes)
			(layer "F.Fab")
			(hide yes)
			(effects
				(font
					(size 1 1)
					(thickness 0.15)
				)
			)
		)
		(property "Author" "Antmicro"
			(at 0 0 180)
			(unlocked yes)
			(layer "F.Fab")
			(hide yes)
			(effects
				(font
					(size 1 1)
					(thickness 0.15)
				)
			)
		)
		(sheetname "/X710-AT2 power/")
		(sheetfile "x710-at2-power.kicad_sch")
		(attr smd)
		(fp_line
			(start -0.15 0.4)
			(end 0.15 0.4)
			(stroke
				(width 0.15)
				(type solid)
			)
			(layer "F.SilkS")
		)
		(fp_line
			(start -0.15 -0.4)
			(end 0.15 -0.4)
			(stroke
				(width 0.15)
				(type solid)
			)
			(layer "F.SilkS")
		)
		(fp_rect
			(start -1.25 -0.65)
			(end 1.25 0.65)
			(stroke
				(width 0.05)
				(type solid)
			)
			(fill no)
			(layer "F.CrtYd")
		)
		(fp_rect
			(start -0.8 -0.4)
			(end 0.8 0.4)
			(stroke
				(width 0.15)
				(type solid)
			)
			(fill no)
			(layer "F.Fab")
		)
		(pad "1" smd roundrect
			(at -0.7 0 180)
			(size 0.8 1)
			(layers "F.Cu" "F.Mask" "F.Paste")
			(roundrect_rratio 0.2)
			(net 28 "GND")
			(pintype "passive")
		)
		(pad "2" smd roundrect
			(at 0.7 0 180)
			(size 0.8 1)
			(layers "F.Cu" "F.Mask" "F.Paste")
			(roundrect_rratio 0.2)
			(net 7 "+3V3")
			(pintype "passive")
		)
	)
	(footprint "antmicro-footprints:R_0402_1005Metric"
		(layer "F.Cu")
		(at 58.099999 100.550002 90)
		(descr "Resistor SMD 0402")
		(tags "resistor SMD 0402")
		(property "Reference" "R17"
			(at -1.359998 1.210001 90)
			(layer "F.SilkS")
			(effects
				(font
					(size 0.7 0.7)
					(thickness 0.15)
				)
				(justify left bottom)
			)
		)
		(property "Value" "R_100k_0402"
			(at -1.011843 1.772046 90)
			(layer "F.Fab")
			(hide yes)
			(effects
				(font
					(size 0.7 0.7)
					(thickness 0.15)
				)
				(justify left bottom)
			)
		)
		(property "Datasheet" "https://www.bourns.com/docs/product-datasheets/cr.pdf"
			(at 0 0 90)
			(layer "F.Fab")
			(hide yes)
			(effects
				(font
					(size 1.27 1.27)
					(thickness 0.15)
				)
			)
		)
		(property "Description" "SMD Chip Resistor, 100 kohm, ± 1%, 62.5 mW, 0402 [1005 Metric], Thick Film, General Purpose"
			(at 0 0 90)
			(layer "F.Fab")
			(hide yes)
			(effects
				(font
					(size 1.27 1.27)
					(thickness 0.15)
				)
			)
		)
		(property "MPN" "CR0402-FX-1003GLF"
			(at 0 0 90)
			(unlocked yes)
			(layer "F.Fab")
			(hide yes)
			(effects
				(font
					(size 1 1)
					(thickness 0.15)
				)
			)
		)
		(property "Manufacturer" "Bourns"
			(at 0 0 90)
			(unlocked yes)
			(layer "F.Fab")
			(hide yes)
			(effects
				(font
					(size 1 1)
					(thickness 0.15)
				)
			)
		)
		(property "License" "Apache-2.0"
			(at 0 0 90)
			(unlocked yes)
			(layer "F.Fab")
			(hide yes)
			(effects
				(font
					(size 1 1)
					(thickness 0.15)
				)
			)
		)
		(property "Author" "Antmicro"
			(at 0 0 90)
			(unlocked yes)
			(layer "F.Fab")
			(hide yes)
			(effects
				(font
					(size 1 1)
					(thickness 0.15)
				)
			)
		)
		(property "Val" "100k"
			(at 0 0 90)
			(unlocked yes)
			(layer "F.Fab")
			(hide yes)
			(effects
				(font
					(size 1 1)
					(thickness 0.15)
				)
			)
		)
		(property "Tolerance" "1%"
			(at 0 0 90)
			(unlocked yes)
			(layer "F.Fab")
			(hide yes)
			(effects
				(font
					(size 1 1)
					(thickness 0.15)
				)
			)
		)
		(sheetname "/Power/")
		(sheetfile "power.kicad_sch")
		(attr smd)
		(fp_rect
			(start -0.925 -0.47)
			(end 0.925 0.47)
			(stroke
				(width 0.05)
				(type default)
			)
			(fill no)
			(layer "F.CrtYd")
		)
		(fp_rect
			(start -0.5 -0.25)
			(end 0.5 0.25)
			(stroke
				(width 0.15)
				(type solid)
			)
			(fill no)
			(layer "F.Fab")
		)
		(pad "1" smd roundrect
			(at -0.48 0 90)
			(size 0.59 0.64)
			(layers "F.Cu" "F.Mask" "F.Paste")
			(roundrect_rratio 0.25)
			(net 369 "/Power/1V88_PG")
			(pintype "passive")
		)
		(pad "2" smd roundrect
			(at 0.48 0 90)
			(size 0.59 0.64)
			(layers "F.Cu" "F.Mask" "F.Paste")
			(roundrect_rratio 0.25)
			(net 324 "/Power/1V88_VCC")
			(pintype "passive")
		)
	)
	(footprint "antmicro-footprints:R_0402_1005Metric"
		(layer "F.Cu")
		(at 87.43 58.111999 90)
		(descr "Resistor SMD 0402")
		(tags "resistor SMD 0402")
		(property "Reference" "R27"
			(at -1.160001 2.3 90)
			(layer "F.SilkS")
			(effects
				(font
					(size 0.7 0.7)
					(thickness 0.15)
				)
				(justify left bottom)
			)
		)
		(property "Value" "R_300R_0402"
			(at -1.011843 1.772046 90)
			(layer "F.Fab")
			(hide yes)
			(effects
				(font
					(size 0.7 0.7)
					(thickness 0.15)
				)
				(justify left bottom)
			)
		)
		(property "Datasheet" "https://www.farnell.com/datasheets/3795017.pdf"
			(at 0 0 90)
			(layer "F.Fab")
			(hide yes)
			(effects
				(font
					(size 1.27 1.27)
					(thickness 0.15)
				)
			)
		)
		(property "Description" "MULTICOMP PRO MCMR04X3000FTLSMD Chip Resistor, Ceramic, 300 ohm, ± 1%, 62.5 mW, 0402 [1005 Metric], Thick Film"
			(at 0 0 90)
			(layer "F.Fab")
			(hide yes)
			(effects
				(font
					(size 1.27 1.27)
					(thickness 0.15)
				)
			)
		)
		(property "MPN" "RMCF0402FT300R"
			(at 0 0 90)
			(unlocked yes)
			(layer "F.Fab")
			(hide yes)
			(effects
				(font
					(size 1 1)
					(thickness 0.15)
				)
			)
		)
		(property "Manufacturer" "Stackpole Electronics"
			(at 0 0 90)
			(unlocked yes)
			(layer "F.Fab")
			(hide yes)
			(effects
				(font
					(size 1 1)
					(thickness 0.15)
				)
			)
		)
		(property "License" "Apache-2.0"
			(at 0 0 90)
			(unlocked yes)
			(layer "F.Fab")
			(hide yes)
			(effects
				(font
					(size 1 1)
					(thickness 0.15)
				)
			)
		)
		(property "Author" "Antmicro"
			(at 0 0 90)
			(unlocked yes)
			(layer "F.Fab")
			(hide yes)
			(effects
				(font
					(size 1 1)
					(thickness 0.15)
				)
			)
		)
		(property "Val" "300R"
			(at 0 0 90)
			(unlocked yes)
			(layer "F.Fab")
			(hide yes)
			(effects
				(font
					(size 1 1)
					(thickness 0.15)
				)
			)
		)
		(property "Tolerance" "1%"
			(at 0 0 90)
			(unlocked yes)
			(layer "F.Fab")
			(hide yes)
			(effects
				(font
					(size 1 1)
					(thickness 0.15)
				)
			)
		)
		(sheetname "/Power/")
		(sheetfile "power.kicad_sch")
		(attr smd)
		(fp_rect
			(start -0.925 -0.47)
			(end 0.925 0.47)
			(stroke
				(width 0.05)
				(type default)
			)
			(fill no)
			(layer "F.CrtYd")
		)
		(fp_rect
			(start -0.5 -0.25)
			(end 0.5 0.25)
			(stroke
				(width 0.15)
				(type solid)
			)
			(fill no)
			(layer "F.Fab")
		)
		(pad "1" smd roundrect
			(at -0.48 0 90)
			(size 0.59 0.64)
			(layers "F.Cu" "F.Mask" "F.Paste")
			(roundrect_rratio 0.25)
			(net 28 "GND")
			(pintype "passive")
		)
		(pad "2" smd roundrect
			(at 0.48 0 90)
			(size 0.59 0.64)
			(layers "F.Cu" "F.Mask" "F.Paste")
			(roundrect_rratio 0.25)
			(net 43 "Net-(C37-Pad2)")
			(pintype "passive")
		)
	)
	(footprint "antmicro-footprints:LED_0603_1608Metric_G"
		(layer "F.Cu")
		(at 62.26 52.647 -90)
		(descr "LED SMD 0603 Green")
		(tags "LED SMD 0603 Green")
		(property "Reference" "D2"
			(at -0.607 1.36 90)
			(layer "F.SilkS")
			(effects
				(font
					(size 0.7 0.7)
					(thickness 0.15)
				)
				(justify right top)
			)
		)
		(property "Value" "LED_G_0603_LG_L29K-G2J1-24-Z"
			(at -0.001 1.599 90)
			(layer "F.Fab")
			(hide yes)
			(effects
				(font
					(size 0.7 0.7)
					(thickness 0.15)
				)
				(justify right top)
			)
		)
		(property "Datasheet" "https://look.ams-osram.com/m/19ee86b3ae0ee95b/original/LG-L29K.pdf"
			(at 0 0 90)
			(layer "F.Fab")
			(hide yes)
			(effects
				(font
					(size 1.27 1.27)
					(thickness 0.15)
				)
			)
		)
		(property "Description" "LED, Green, SMD, 0603, 20 mA, 1.7 V, 570 nm"
			(at 0 0 90)
			(layer "F.Fab")
			(hide yes)
			(effects
				(font
					(size 1.27 1.27)
					(thickness 0.15)
				)
			)
		)
		(property "MPN" "LG L29K-G2J1-24-Z"
			(at 0 0 270)
			(unlocked yes)
			(layer "F.Fab")
			(hide yes)
			(effects
				(font
					(size 1 1)
					(thickness 0.15)
				)
			)
		)
		(property "Manufacturer" "OSRAM"
			(at 0 0 270)
			(unlocked yes)
			(layer "F.Fab")
			(hide yes)
			(effects
				(font
					(size 1 1)
					(thickness 0.15)
				)
			)
		)
		(property "Color" "Green"
			(at 0 0 270)
			(unlocked yes)
			(layer "F.Fab")
			(hide yes)
			(effects
				(font
					(size 1 1)
					(thickness 0.15)
				)
			)
		)
		(property "Author" "Antmicro"
			(at 0 0 270)
			(unlocked yes)
			(layer "F.Fab")
			(hide yes)
			(effects
				(font
					(size 1 1)
					(thickness 0.15)
				)
			)
		)
		(property "License" "Apache-2.0"
			(at 0 0 270)
			(unlocked yes)
			(layer "F.Fab")
			(hide yes)
			(effects
				(font
					(size 1 1)
					(thickness 0.15)
				)
			)
		)
		(sheetname "/Power/")
		(sheetfile "power.kicad_sch")
		(attr smd)
		(fp_line
			(start 0.22 0.35)
			(end -0.22 0.35)
			(stroke
				(width 0.15)
				(type solid)
			)
			(layer "F.SilkS")
		)
		(fp_line
			(start -0.094672 0.201008)
			(end -0.094672 -0.198992)
			(stroke
				(width 0.1)
				(type solid)
			)
			(layer "F.SilkS")
		)
		(fp_line
			(start 0.105328 0.201008)
			(end -0.094672 0.001008)
			(stroke
				(width 0.1)
				(type solid)
			)
			(layer "F.SilkS")
		)
		(fp_line
			(start 0.105328 0.201008)
			(end 0.105328 -0.198992)
			(stroke
				(width 0.1)
				(type solid)
			)
			(layer "F.SilkS")
		)
		(fp_line
			(start -0.094672 0.001008)
			(end -0.24 0.001008)
			(stroke
				(width 0.1)
				(type solid)
			)
			(layer "F.SilkS")
		)
		(fp_line
			(start -0.094672 0.001008)
			(end 0.105328 -0.198992)
			(stroke
				(width 0.1)
				(type solid)
			)
			(layer "F.SilkS")
		)
		(fp_line
			(start 0.105328 0.001008)
			(end 0.24 0.001)
			(stroke
				(width 0.1)
				(type solid)
			)
			(layer "F.SilkS")
		)
		(fp_line
			(start -1.18 -0.319)
			(end -1.18 0.321)
			(stroke
				(width 0.15)
				(type solid)
			)
			(layer "F.SilkS")
		)
		(fp_line
			(start 0.22 -0.35)
			(end -0.22 -0.35)
			(stroke
				(width 0.15)
				(type solid)
			)
			(layer "F.SilkS")
		)
		(fp_rect
			(start 1.25 0.65)
			(end -1.25 -0.65)
			(stroke
				(width 0.05)
				(type solid)
			)
			(fill no)
			(layer "F.CrtYd")
		)
		(fp_line
			(start -0.199 0.2)
			(end -0.199 0.1)
			(stroke
				(width 0.15)
				(type solid)
			)
			(layer "F.Fab")
		)
		(fp_line
			(start 0.201 0.2)
			(end 0.201 0)
			(stroke
				(width 0.15)
				(type solid)
			)
			(layer "F.Fab")
		)
		(fp_line
			(start -0.199 0)
			(end -0.597 0)
			(stroke
				(width 0.15)
				(type solid)
			)
			(layer "F.Fab")
		)
		(fp_line
			(start -0.101 0)
			(end 0.201 0.2)
			(stroke
				(width 0.15)
				(type solid)
			)
			(layer "F.Fab")
		)
		(fp_line
			(start 0.201 0)
			(end 0.201 -0.202)
			(stroke
				(width 0.15)
				(type solid)
			)
			(layer "F.Fab")
		)
		(fp_line
			(start 0.599 0)
			(end 0.201 0)
			(stroke
				(width 0.15)
				(type solid)
			)
			(layer "F.Fab")
		)
		(fp_line
			(start -0.199 -0.202)
			(end -0.199 0.1)
			(stroke
				(width 0.15)
				(type solid)
			)
			(layer "F.Fab")
		)
		(fp_line
			(start 0.201 -0.202)
			(end -0.101 0)
			(stroke
				(width 0.15)
				(type solid)
			)
			(layer "F.Fab")
		)
		(fp_rect
			(start 0.848 0.4)
			(end -0.85 -0.402)
			(stroke
				(width 0.15)
				(type solid)
			)
			(fill no)
			(layer "F.Fab")
		)
		(fp_text user "Author: Antmicro"
			(at -1.4224 4.799 270)
			(layer "F.Fab")
			(effects
				(font
					(size 0.7 0.7)
					(thickness 0.15)
				)
				(justify left bottom)
			)
		)
		(fp_text user "License: Apache-2.0"
			(at -1.4224 3.599 270)
			(layer "F.Fab")
			(effects
				(font
					(size 0.7 0.7)
					(thickness 0.15)
				)
				(justify left bottom)
			)
		)
		(fp_text user "${REFERENCE}"
			(at -1.4224 5.999 270)
			(layer "F.Fab")
			(effects
				(font
					(size 0.7 0.7)
					(thickness 0.15)
				)
				(justify left bottom)
			)
		)
		(pad "1" smd roundrect
			(at -0.7 0 90)
			(size 0.8 1)
			(layers "F.Cu" "F.Mask" "F.Paste")
			(roundrect_rratio 0.2)
			(net 28 "GND")
			(pinfunction "C")
			(pintype "passive")
		)
		(pad "2" smd roundrect
			(at 0.7 0 90)
			(size 0.8 1)
			(layers "F.Cu" "F.Mask" "F.Paste")
			(roundrect_rratio 0.2)
			(net 70 "Net-(D2-A)")
			(pinfunction "A")
			(pintype "passive")
		)
	)
	(footprint "antmicro-footprints:C_0603_1608Metric"
		(layer "F.Cu")
		(at 113.2 103.4 -90)
		(descr "Capacitor SMD 0603")
		(tags "capacitor 0603")
		(property "Reference" "C214"
			(at -4.32 -0.71 90)
			(layer "F.SilkS")
			(effects
				(font
					(size 0.7 0.7)
					(thickness 0.15)
				)
				(justify right top)
			)
		)
		(property "Value" "C_10u_10V_X7R_0603"
			(at -1.42757 1.770288 90)
			(layer "F.Fab")
			(hide yes)
			(effects
				(font
					(size 0.7 0.7)
					(thickness 0.15)
				)
				(justify right top)
			)
		)
		(property "Datasheet" "https://www.murata.com/products/productdetail?partno=GRM188Z71A106KA73%23"
			(at 0 0 90)
			(layer "F.Fab")
			(hide yes)
			(effects
				(font
					(size 1.27 1.27)
					(thickness 0.15)
				)
			)
		)
		(property "Description" "SMD Multilayer Ceramic Capacitor,  10µF, 10V, 0603, ±10%, X7R"
			(at 0 0 90)
			(layer "F.Fab")
			(hide yes)
			(effects
				(font
					(size 1.27 1.27)
					(thickness 0.15)
				)
			)
		)
		(property "MPN" "GRM188Z71A106KA73D"
			(at 0 0 270)
			(unlocked yes)
			(layer "F.Fab")
			(hide yes)
			(effects
				(font
					(size 1 1)
					(thickness 0.15)
				)
			)
		)
		(property "Val" "10u"
			(at 0 0 270)
			(unlocked yes)
			(layer "F.Fab")
			(hide yes)
			(effects
				(font
					(size 1 1)
					(thickness 0.15)
				)
			)
		)
		(property "Voltage" "10V"
			(at 0 0 270)
			(unlocked yes)
			(layer "F.Fab")
			(hide yes)
			(effects
				(font
					(size 1 1)
					(thickness 0.15)
				)
			)
		)
		(property "Dielectric" "X7R"
			(at 0 0 270)
			(unlocked yes)
			(layer "F.Fab")
			(hide yes)
			(effects
				(font
					(size 1 1)
					(thickness 0.15)
				)
			)
		)
		(property "Manufacturer" "Murata"
			(at 0 0 270)
			(unlocked yes)
			(layer "F.Fab")
			(hide yes)
			(effects
				(font
					(size 1 1)
					(thickness 0.15)
				)
			)
		)
		(property "License" "Apache-2.0"
			(at 0 0 270)
			(unlocked yes)
			(layer "F.Fab")
			(hide yes)
			(effects
				(font
					(size 1 1)
					(thickness 0.15)
				)
			)
		)
		(property "Author" "Antmicro"
			(at 0 0 270)
			(unlocked yes)
			(layer "F.Fab")
			(hide yes)
			(effects
				(font
					(size 1 1)
					(thickness 0.15)
				)
			)
		)
		(sheetname "/Fan controller/")
		(sheetfile "fan-controller.kicad_sch")
		(attr smd exclude_from_pos_files exclude_from_bom dnp)
		(fp_line
			(start -0.15 0.4)
			(end 0.15 0.4)
			(stroke
				(width 0.15)
				(type solid)
			)
			(layer "F.SilkS")
		)
		(fp_line
			(start -0.15 -0.4)
			(end 0.15 -0.4)
			(stroke
				(width 0.15)
				(type solid)
			)
			(layer "F.SilkS")
		)
		(fp_rect
			(start -1.25 -0.65)
			(end 1.25 0.65)
			(stroke
				(width 0.05)
				(type solid)
			)
			(fill no)
			(layer "F.CrtYd")
		)
		(fp_rect
			(start -0.8 -0.4)
			(end 0.8 0.4)
			(stroke
				(width 0.15)
				(type solid)
			)
			(fill no)
			(layer "F.Fab")
		)
		(pad "1" smd roundrect
			(at -0.7 0 270)
			(size 0.8 1)
			(layers "F.Cu" "F.Mask" "F.Paste")
			(roundrect_rratio 0.2)
			(net 28 "GND")
			(pintype "passive")
		)
		(pad "2" smd roundrect
			(at 0.7 0 270)
			(size 0.8 1)
			(layers "F.Cu" "F.Mask" "F.Paste")
			(roundrect_rratio 0.2)
			(net 388 "/Fan controller/+5V")
			(pintype "passive")
		)
	)
	(footprint "antmicro-footprints:C_0402_1005Metric"
		(layer "F.Cu")
		(at 67.9 100.95 -90)
		(descr "Capacitor SMD 0402")
		(tags "capacitor SMD 0402")
		(property "Reference" "C179"
			(at -1.24 1.5 90)
			(layer "F.SilkS")
			(effects
				(font
					(size 0.7 0.7)
					(thickness 0.15)
				)
				(justify right top)
			)
		)
		(property "Value" "C_100n_0402"
			(at -1.022927 2.155213 90)
			(layer "F.Fab")
			(hide yes)
			(effects
				(font
					(size 0.7 0.7)
					(thickness 0.15)
				)
				(justify right top)
			)
		)
		(property "Datasheet" "https://www.murata.com/products/productdetail?partno=GRM155R61H104KE14%23"
			(at 0 0 90)
			(layer "F.Fab")
			(hide yes)
			(effects
				(font
					(size 1.27 1.27)
					(thickness 0.15)
				)
			)
		)
		(property "Description" "SMD Multilayer Ceramic Capacitor, 0.1 µF, 50 V, 0402 [1005 Metric], ± 10%, X5R, GRM Series"
			(at 0 0 90)
			(layer "F.Fab")
			(hide yes)
			(effects
				(font
					(size 1.27 1.27)
					(thickness 0.15)
				)
			)
		)
		(property "MPN" "GRM155R61H104KE14D"
			(at 0 0 270)
			(unlocked yes)
			(layer "F.Fab")
			(hide yes)
			(effects
				(font
					(size 1 1)
					(thickness 0.15)
				)
			)
		)
		(property "Val" "100n"
			(at 0 0 270)
			(unlocked yes)
			(layer "F.Fab")
			(hide yes)
			(effects
				(font
					(size 1 1)
					(thickness 0.15)
				)
			)
		)
		(property "Voltage" "50V"
			(at 0 0 270)
			(unlocked yes)
			(layer "F.Fab")
			(hide yes)
			(effects
				(font
					(size 1 1)
					(thickness 0.15)
				)
			)
		)
		(property "Dielectric" "X5R"
			(at 0 0 270)
			(unlocked yes)
			(layer "F.Fab")
			(hide yes)
			(effects
				(font
					(size 1 1)
					(thickness 0.15)
				)
			)
		)
		(property "Manufacturer" "Murata"
			(at 0 0 270)
			(unlocked yes)
			(layer "F.Fab")
			(hide yes)
			(effects
				(font
					(size 1 1)
					(thickness 0.15)
				)
			)
		)
		(property "License" "Apache-2.0"
			(at 0 0 270)
			(unlocked yes)
			(layer "F.Fab")
			(hide yes)
			(effects
				(font
					(size 1 1)
					(thickness 0.15)
				)
			)
		)
		(property "Author" "Antmicro"
			(at 0 0 270)
			(unlocked yes)
			(layer "F.Fab")
			(hide yes)
			(effects
				(font
					(size 1 1)
					(thickness 0.15)
				)
			)
		)
		(sheetname "/X710-AT2 power/")
		(sheetfile "x710-at2-power.kicad_sch")
		(attr smd)
		(fp_rect
			(start -0.925 -0.47)
			(end 0.925 0.47)
			(stroke
				(width 0.05)
				(type default)
			)
			(fill no)
			(layer "F.CrtYd")
		)
		(fp_line
			(start -0.494 0.248)
			(end -0.494 -0.25)
			(stroke
				(width 0.15)
				(type solid)
			)
			(layer "F.Fab")
		)
		(fp_line
			(start 0.504 0.248)
			(end -0.494 0.248)
			(stroke
				(width 0.15)
				(type solid)
			)
			(layer "F.Fab")
		)
		(fp_line
			(start -0.494 -0.25)
			(end 0.504 -0.25)
			(stroke
				(width 0.15)
				(type solid)
			)
			(layer "F.Fab")
		)
		(fp_line
			(start 0.504 -0.25)
			(end 0.504 0.248)
			(stroke
				(width 0.15)
				(type solid)
			)
			(layer "F.Fab")
		)
		(pad "1" smd roundrect
			(at -0.48 0 270)
			(size 0.59 0.64)
			(layers "F.Cu" "F.Mask" "F.Paste")
			(roundrect_rratio 0.25)
			(net 28 "GND")
			(pintype "passive")
		)
		(pad "2" smd roundrect
			(at 0.48 0 270)
			(size 0.59 0.64)
			(layers "F.Cu" "F.Mask" "F.Paste")
			(roundrect_rratio 0.25)
			(net 302 "+1V0")
			(pintype "passive")
		)
	)
	(footprint "antmicro-footprints:C_0402_1005Metric"
		(layer "F.Cu")
		(at 103.498001 62.778655 -90)
		(descr "Capacitor SMD 0402")
		(tags "capacitor SMD 0402")
		(property "Reference" "C191"
			(at 1.406345 -2.351999 270)
			(layer "F.SilkS")
			(effects
				(font
					(size 0.7 0.7)
					(thickness 0.15)
				)
				(justify left bottom)
			)
		)
		(property "Value" "C_220n_16V_0402"
			(at -1.022927 2.155213 270)
			(layer "F.Fab")
			(hide yes)
			(effects
				(font
					(size 0.7 0.7)
					(thickness 0.15)
				)
				(justify left bottom)
			)
		)
		(property "Datasheet" "https://www.murata.com/products/productdetail?partno=GRM155R71C224KA12%23"
			(at 0 0 270)
			(layer "F.Fab")
			(hide yes)
			(effects
				(font
					(size 1.27 1.27)
					(thickness 0.15)
				)
			)
		)
		(property "Description" "SMD Multilayer Ceramic Capacitor, 0.22 µF, 16 V, 0402 [1005 Metric], ± 10%, X7R, GRM Series"
			(at 0 0 270)
			(layer "F.Fab")
			(hide yes)
			(effects
				(font
					(size 1.27 1.27)
					(thickness 0.15)
				)
			)
		)
		(property "MPN" "GRM155R71C224KA12D"
			(at 0 0 270)
			(unlocked yes)
			(layer "F.Fab")
			(hide yes)
			(effects
				(font
					(size 1 1)
					(thickness 0.15)
				)
			)
		)
		(property "Manufacturer" "Murata"
			(at 0 0 270)
			(unlocked yes)
			(layer "F.Fab")
			(hide yes)
			(effects
				(font
					(size 1 1)
					(thickness 0.15)
				)
			)
		)
		(property "License" "Apache-2.0"
			(at 0 0 270)
			(unlocked yes)
			(layer "F.Fab")
			(hide yes)
			(effects
				(font
					(size 1 1)
					(thickness 0.15)
				)
			)
		)
		(property "Author" "Antmicro"
			(at 0 0 270)
			(unlocked yes)
			(layer "F.Fab")
			(hide yes)
			(effects
				(font
					(size 1 1)
					(thickness 0.15)
				)
			)
		)
		(property "Val" "220n"
			(at 0 0 270)
			(unlocked yes)
			(layer "F.Fab")
			(hide yes)
			(effects
				(font
					(size 1 1)
					(thickness 0.15)
				)
			)
		)
		(property "Voltage" "16V"
			(at 0 0 270)
			(unlocked yes)
			(layer "F.Fab")
			(hide yes)
			(effects
				(font
					(size 1 1)
					(thickness 0.15)
				)
			)
		)
		(property "Dielectric" "X7R"
			(at 0 0 270)
			(unlocked yes)
			(layer "F.Fab")
			(hide yes)
			(effects
				(font
					(size 1 1)
					(thickness 0.15)
				)
			)
		)
		(sheetname "/X710-AT2 PCIe/")
		(sheetfile "x710-at2-pcie.kicad_sch")
		(attr smd)
		(fp_rect
			(start -0.925 -0.47)
			(end 0.925 0.47)
			(stroke
				(width 0.05)
				(type default)
			)
			(fill no)
			(layer "F.CrtYd")
		)
		(fp_line
			(start -0.494 0.248)
			(end -0.494 -0.25)
			(stroke
				(width 0.15)
				(type solid)
			)
			(layer "F.Fab")
		)
		(fp_line
			(start 0.504 0.248)
			(end -0.494 0.248)
			(stroke
				(width 0.15)
				(type solid)
			)
			(layer "F.Fab")
		)
		(fp_line
			(start -0.494 -0.25)
			(end 0.504 -0.25)
			(stroke
				(width 0.15)
				(type solid)
			)
			(layer "F.Fab")
		)
		(fp_line
			(start 0.504 -0.25)
			(end 0.504 0.248)
			(stroke
				(width 0.15)
				(type solid)
			)
			(layer "F.Fab")
		)
		(pad "1" smd roundrect
			(at -0.48 0 270)
			(size 0.59 0.64)
			(layers "F.Cu" "F.Mask" "F.Paste")
			(roundrect_rratio 0.25)
			(net 17 "/OCuLink/PCIe_{x4}.TX0-")
			(pintype "passive")
		)
		(pad "2" smd roundrect
			(at 0.48 0 270)
			(size 0.59 0.64)
			(layers "F.Cu" "F.Mask" "F.Paste")
			(roundrect_rratio 0.25)
			(net 33 "/X710-AT2 PCIe/PCIe_{x4}_AC.TX0-")
			(pintype "passive")
		)
	)
	(footprint "antmicro-footprints:R_0402_1005Metric"
		(layer "F.Cu")
		(at 56.100001 85.149999 90)
		(descr "Resistor SMD 0402")
		(tags "resistor SMD 0402")
		(property "Reference" "R9"
			(at -1.650001 -0.750001 180)
			(layer "F.SilkS")
			(effects
				(font
					(size 0.7 0.7)
					(thickness 0.15)
				)
				(justify left bottom)
			)
		)
		(property "Value" "R_16k_0402"
			(at -1.011843 1.772046 90)
			(layer "F.Fab")
			(hide yes)
			(effects
				(font
					(size 0.7 0.7)
					(thickness 0.15)
				)
				(justify left bottom)
			)
		)
		(property "Datasheet" "https://www.bourns.com/docs/product-datasheets/cr.pdf"
			(at 0 0 90)
			(layer "F.Fab")
			(hide yes)
			(effects
				(font
					(size 1.27 1.27)
					(thickness 0.15)
				)
			)
		)
		(property "Description" "SMD Chip Resistor"
			(at 0 0 90)
			(layer "F.Fab")
			(hide yes)
			(effects
				(font
					(size 1.27 1.27)
					(thickness 0.15)
				)
			)
		)
		(property "MPN" "CR0402-FX-1602GLF"
			(at 0 0 90)
			(unlocked yes)
			(layer "F.Fab")
			(hide yes)
			(effects
				(font
					(size 1 1)
					(thickness 0.15)
				)
			)
		)
		(property "Manufacturer" "Bourns"
			(at 0 0 90)
			(unlocked yes)
			(layer "F.Fab")
			(hide yes)
			(effects
				(font
					(size 1 1)
					(thickness 0.15)
				)
			)
		)
		(property "License" "Apache-2.0"
			(at 0 0 90)
			(unlocked yes)
			(layer "F.Fab")
			(hide yes)
			(effects
				(font
					(size 1 1)
					(thickness 0.15)
				)
			)
		)
		(property "Author" "Antmicro"
			(at 0 0 90)
			(unlocked yes)
			(layer "F.Fab")
			(hide yes)
			(effects
				(font
					(size 1 1)
					(thickness 0.15)
				)
			)
		)
		(property "Val" "16k"
			(at 0 0 90)
			(unlocked yes)
			(layer "F.Fab")
			(hide yes)
			(effects
				(font
					(size 1 1)
					(thickness 0.15)
				)
			)
		)
		(property "Tolerance" "1%"
			(at 0 0 90)
			(unlocked yes)
			(layer "F.Fab")
			(hide yes)
			(effects
				(font
					(size 1 1)
					(thickness 0.15)
				)
			)
		)
		(sheetname "/Power/")
		(sheetfile "power.kicad_sch")
		(attr smd)
		(fp_rect
			(start -0.925 -0.47)
			(end 0.925 0.47)
			(stroke
				(width 0.05)
				(type default)
			)
			(fill no)
			(layer "F.CrtYd")
		)
		(fp_rect
			(start -0.5 -0.25)
			(end 0.5 0.25)
			(stroke
				(width 0.15)
				(type solid)
			)
			(fill no)
			(layer "F.Fab")
		)
		(pad "1" smd roundrect
			(at -0.48 0 90)
			(size 0.59 0.64)
			(layers "F.Cu" "F.Mask" "F.Paste")
			(roundrect_rratio 0.25)
			(net 329 "/Power/VCCD_FB")
			(pintype "passive")
		)
		(pad "2" smd roundrect
			(at 0.48 0 90)
			(size 0.59 0.64)
			(layers "F.Cu" "F.Mask" "F.Paste")
			(roundrect_rratio 0.25)
			(net 303 "/Power/+VCCD_OUT")
			(pintype "passive")
		)
	)
	(footprint "antmicro-footprints:R_0402_1005Metric"
		(layer "F.Cu")
		(at 89.1 112.45 -90)
		(descr "Resistor SMD 0402")
		(tags "resistor SMD 0402")
		(property "Reference" "R73"
			(at 0.85 -0.4625 90)
			(layer "F.SilkS")
			(effects
				(font
					(size 0.7 0.7)
					(thickness 0.15)
				)
				(justify right bottom)
			)
		)
		(property "Value" "R_1k_0402"
			(at -1.011843 1.772046 90)
			(layer "F.Fab")
			(hide yes)
			(effects
				(font
					(size 0.7 0.7)
					(thickness 0.15)
				)
				(justify right top)
			)
		)
		(property "Datasheet" "https://www.bourns.com/docs/product-datasheets/cr.pdf"
			(at 0 0 90)
			(layer "F.Fab")
			(hide yes)
			(effects
				(font
					(size 1.27 1.27)
					(thickness 0.15)
				)
			)
		)
		(property "Description" "SMD Chip Resistor, 1 kohm, ± 1%, 63 mW, 0402 [1005 Metric], Thick Film, General Purpose"
			(at 0 0 90)
			(layer "F.Fab")
			(hide yes)
			(effects
				(font
					(size 1.27 1.27)
					(thickness 0.15)
				)
			)
		)
		(property "MPN" "CR0402-FX-1001GLF"
			(at 0 0 270)
			(unlocked yes)
			(layer "F.Fab")
			(hide yes)
			(effects
				(font
					(size 1 1)
					(thickness 0.15)
				)
			)
		)
		(property "Manufacturer" "Bourns"
			(at 0 0 270)
			(unlocked yes)
			(layer "F.Fab")
			(hide yes)
			(effects
				(font
					(size 1 1)
					(thickness 0.15)
				)
			)
		)
		(property "License" "Apache-2.0"
			(at 0 0 270)
			(unlocked yes)
			(layer "F.Fab")
			(hide yes)
			(effects
				(font
					(size 1 1)
					(thickness 0.15)
				)
			)
		)
		(property "Author" "Antmicro"
			(at 0 0 270)
			(unlocked yes)
			(layer "F.Fab")
			(hide yes)
			(effects
				(font
					(size 1 1)
					(thickness 0.15)
				)
			)
		)
		(property "Val" "1k"
			(at 0 0 270)
			(unlocked yes)
			(layer "F.Fab")
			(hide yes)
			(effects
				(font
					(size 1 1)
					(thickness 0.15)
				)
			)
		)
		(property "Tolerance" "1%"
			(at 0 0 270)
			(unlocked yes)
			(layer "F.Fab")
			(hide yes)
			(effects
				(font
					(size 1 1)
					(thickness 0.15)
				)
			)
		)
		(sheetname "/X710-AT2 10GbE/")
		(sheetfile "x710-at2-10gbe.kicad_sch")
		(attr smd exclude_from_pos_files exclude_from_bom dnp)
		(fp_rect
			(start -0.925 -0.47)
			(end 0.925 0.47)
			(stroke
				(width 0.05)
				(type default)
			)
			(fill no)
			(layer "F.CrtYd")
		)
		(fp_rect
			(start -0.5 -0.25)
			(end 0.5 0.25)
			(stroke
				(width 0.15)
				(type solid)
			)
			(fill no)
			(layer "F.Fab")
		)
		(pad "1" smd roundrect
			(at -0.48 0 270)
			(size 0.59 0.64)
			(layers "F.Cu" "F.Mask" "F.Paste")
			(roundrect_rratio 0.25)
			(net 294 "/X710-AT2 10GbE/TPIN_5")
			(pintype "passive")
		)
		(pad "2" smd roundrect
			(at 0.48 0 270)
			(size 0.59 0.64)
			(layers "F.Cu" "F.Mask" "F.Paste")
			(roundrect_rratio 0.25)
			(net 18 "+1V88")
			(pintype "passive")
		)
	)
	(footprint "antmicro-footprints:Conn_Molex_KK_1x4_0470531000"
		(layer "F.Cu")
		(at 115.4 117.44 90)
		(property "Reference" "J8"
			(at 5.18 -3 90)
			(layer "F.SilkS")
			(effects
				(font
					(size 0.7 0.7)
					(thickness 0.15)
				)
				(justify left bottom)
			)
		)
		(property "Value" "Molex_KK_1x4_0470531000"
			(at 0 4.7 90)
			(layer "F.Fab")
			(hide yes)
			(effects
				(font
					(size 0.7 0.7)
					(thickness 0.15)
				)
				(justify left bottom)
			)
		)
		(property "Datasheet" "https://tools.molex.com/pdm_docs/sd/470531000_sd.pdf"
			(at 0 0 90)
			(layer "F.Fab")
			(hide yes)
			(effects
				(font
					(size 1.27 1.27)
					(thickness 0.15)
				)
			)
		)
		(property "Description" "Connector Header, THT,  4x1"
			(at 0 0 90)
			(layer "F.Fab")
			(hide yes)
			(effects
				(font
					(size 1.27 1.27)
					(thickness 0.15)
				)
			)
		)
		(property "MPN" "0470531000"
			(at 0 0 90)
			(unlocked yes)
			(layer "F.Fab")
			(hide yes)
			(effects
				(font
					(size 1 1)
					(thickness 0.15)
				)
			)
		)
		(property "Manufacturer" "Molex"
			(at 0 0 90)
			(unlocked yes)
			(layer "F.Fab")
			(hide yes)
			(effects
				(font
					(size 1 1)
					(thickness 0.15)
				)
			)
		)
		(property "Author" "Antmicro"
			(at 0 0 90)
			(unlocked yes)
			(layer "F.Fab")
			(hide yes)
			(effects
				(font
					(size 1 1)
					(thickness 0.15)
				)
			)
		)
		(property "License" "Apache-2.0"
			(at 0 0 90)
			(unlocked yes)
			(layer "F.Fab")
			(hide yes)
			(effects
				(font
					(size 1 1)
					(thickness 0.15)
				)
			)
		)
		(sheetname "/Fan controller/")
		(sheetfile "fan-controller.kicad_sch")
		(attr through_hole exclude_from_pos_files exclude_from_bom dnp)
		(fp_line
			(start -1.35 -2.6)
			(end 4.4 -2.6)
			(stroke
				(width 0.15)
				(type solid)
			)
			(layer "F.SilkS")
		)
		(fp_line
			(start 8.95 -2.55)
			(end 8.95 3.4)
			(stroke
				(width 0.15)
				(type solid)
			)
			(layer "F.SilkS")
		)
		(fp_line
			(start 5.75 -2.55)
			(end 8.95 -2.55)
			(stroke
				(width 0.15)
				(type solid)
			)
			(layer "F.SilkS")
		)
		(fp_line
			(start 5.08 2.29)
			(end 5.08 3.3)
			(stroke
				(width 0.15)
				(type solid)
			)
			(layer "F.SilkS")
		)
		(fp_line
			(start 0 2.29)
			(end 5.08 2.29)
			(stroke
				(width 0.15)
				(type solid)
			)
			(layer "F.SilkS")
		)
		(fp_line
			(start 0 3.3)
			(end 0 2.29)
			(stroke
				(width 0.15)
				(type solid)
			)
			(layer "F.SilkS")
		)
		(fp_line
			(start 8.95 3.4)
			(end -1.35 3.4)
			(stroke
				(width 0.15)
				(type solid)
			)
			(layer "F.SilkS")
		)
		(fp_line
			(start -1.35 3.4)
			(end -1.35 -2.6)
			(stroke
				(width 0.15)
				(type solid)
			)
			(layer "F.SilkS")
		)
		(fp_circle
			(center 0 -3)
			(end 0.05 -3)
			(stroke
				(width 0.15)
				(type solid)
			)
			(fill yes)
			(layer "F.SilkS")
		)
		(fp_rect
			(start -1.54 -2.96)
			(end 9.16 3.55)
			(stroke
				(width 0.05)
				(type solid)
			)
			(fill no)
			(layer "F.CrtYd")
		)
		(fp_line
			(start 8.85 -2.5)
			(end 8.85 3.3)
			(stroke
				(width 0.15)
				(type solid)
			)
			(layer "F.Fab")
		)
		(fp_line
			(start 5.75 -2.5)
			(end 8.85 -2.5)
			(stroke
				(width 0.15)
				(type solid)
			)
			(layer "F.Fab")
		)
		(fp_line
			(start -1.25 -2.5)
			(end 4.4 -2.5)
			(stroke
				(width 0.15)
				(type solid)
			)
			(layer "F.Fab")
		)
		(fp_line
			(start 5.1 2.3)
			(end 0 2.3)
			(stroke
				(width 0.15)
				(type solid)
			)
			(layer "F.Fab")
		)
		(fp_line
			(start 0 2.3)
			(end 0 3.3)
			(stroke
				(width 0.15)
				(type solid)
			)
			(layer "F.Fab")
		)
		(fp_line
			(start 8.85 3.3)
			(end -1.2 3.3)
			(stroke
				(width 0.15)
				(type solid)
			)
			(layer "F.Fab")
		)
		(fp_line
			(start 5.1 3.3)
			(end 5.1 2.3)
			(stroke
				(width 0.15)
				(type solid)
			)
			(layer "F.Fab")
		)
		(fp_line
			(start -1.2 3.3)
			(end -1.25 3.3)
			(stroke
				(width 0.15)
				(type solid)
			)
			(layer "F.Fab")
		)
		(fp_line
			(start -1.25 3.3)
			(end -1.25 -2.5)
			(stroke
				(width 0.15)
				(type solid)
			)
			(layer "F.Fab")
		)
		(pad "" np_thru_hole circle
			(at 5.08 -2.16 180)
			(size 1.1 1.1)
			(drill 1.1)
			(layers "*.Cu" "*.Mask")
		)
		(pad "1" thru_hole rect
			(at 0 0 180)
			(size 2.03 1.73)
			(drill 1.02)
			(layers "*.Cu" "*.Mask")
			(remove_unused_layers no)
			(net 28 "GND")
			(pintype "passive")
		)
		(pad "2" thru_hole oval
			(at 2.54 0 180)
			(size 2.03 1.73)
			(drill 1.02)
			(layers "*.Cu" "*.Mask")
			(remove_unused_layers no)
			(net 389 "/Fan controller/V_{FAN}")
			(pintype "passive")
		)
		(pad "3" thru_hole oval
			(at 5.08 0 180)
			(size 2.03 1.73)
			(drill 1.02)
			(layers "*.Cu" "*.Mask")
			(remove_unused_layers no)
			(net 391 "/Fan controller/TACH")
			(pintype "passive+no_connect")
		)
		(pad "4" thru_hole oval
			(at 7.62 0 180)
			(size 2.03 1.73)
			(drill 1.02)
			(layers "*.Cu" "*.Mask")
			(remove_unused_layers no)
			(net 390 "/Fan controller/PWM")
			(pintype "passive")
		)
	)
	(footprint "antmicro-footprints:R_0402_1005Metric"
		(layer "F.Cu")
		(at 112.15 100.1 90)
		(descr "Resistor SMD 0402")
		(tags "resistor SMD 0402")
		(property "Reference" "R179"
			(at 0.8 -1.55 90)
			(layer "F.SilkS")
			(effects
				(font
					(size 0.7 0.7)
					(thickness 0.15)
				)
				(justify left bottom)
			)
		)
		(property "Value" "R_10k_0402"
			(at -1.011843 1.772046 90)
			(layer "F.Fab")
			(hide yes)
			(effects
				(font
					(size 0.7 0.7)
					(thickness 0.15)
				)
				(justify left bottom)
			)
		)
		(property "Datasheet" "https://www.bourns.com/docs/product-datasheets/cr.pdf"
			(at 0 0 90)
			(layer "F.Fab")
			(hide yes)
			(effects
				(font
					(size 1.27 1.27)
					(thickness 0.15)
				)
			)
		)
		(property "Description" "SMD Chip Resistor, 10 kohm, ± 1%, 62.5 mW, 0402 [1005 Metric], Thick Film, General Purpose"
			(at 0 0 90)
			(layer "F.Fab")
			(hide yes)
			(effects
				(font
					(size 1.27 1.27)
					(thickness 0.15)
				)
			)
		)
		(property "MPN" "CR0402-FX-1002GLF"
			(at 0 0 90)
			(unlocked yes)
			(layer "F.Fab")
			(hide yes)
			(effects
				(font
					(size 1 1)
					(thickness 0.15)
				)
			)
		)
		(property "Manufacturer" "Bourns"
			(at 0 0 90)
			(unlocked yes)
			(layer "F.Fab")
			(hide yes)
			(effects
				(font
					(size 1 1)
					(thickness 0.15)
				)
			)
		)
		(property "License" "Apache-2.0"
			(at 0 0 90)
			(unlocked yes)
			(layer "F.Fab")
			(hide yes)
			(effects
				(font
					(size 1 1)
					(thickness 0.15)
				)
			)
		)
		(property "Author" "Antmicro"
			(at 0 0 90)
			(unlocked yes)
			(layer "F.Fab")
			(hide yes)
			(effects
				(font
					(size 1 1)
					(thickness 0.15)
				)
			)
		)
		(property "Val" "10k"
			(at 0 0 90)
			(unlocked yes)
			(layer "F.Fab")
			(hide yes)
			(effects
				(font
					(size 1 1)
					(thickness 0.15)
				)
			)
		)
		(property "Tolerance" "1%"
			(at 0 0 90)
			(unlocked yes)
			(layer "F.Fab")
			(hide yes)
			(effects
				(font
					(size 1 1)
					(thickness 0.15)
				)
			)
		)
		(sheetname "/Fan controller/")
		(sheetfile "fan-controller.kicad_sch")
		(attr smd exclude_from_pos_files exclude_from_bom dnp)
		(fp_rect
			(start -0.925 -0.47)
			(end 0.925 0.47)
			(stroke
				(width 0.05)
				(type default)
			)
			(fill no)
			(layer "F.CrtYd")
		)
		(fp_rect
			(start -0.5 -0.25)
			(end 0.5 0.25)
			(stroke
				(width 0.15)
				(type solid)
			)
			(fill no)
			(layer "F.Fab")
		)
		(pad "1" smd roundrect
			(at -0.48 0 90)
			(size 0.59 0.64)
			(layers "F.Cu" "F.Mask" "F.Paste")
			(roundrect_rratio 0.25)
			(net 399 "/Fan controller/DMIN")
			(pintype "passive")
		)
		(pad "2" smd roundrect
			(at 0.48 0 90)
			(size 0.59 0.64)
			(layers "F.Cu" "F.Mask" "F.Paste")
			(roundrect_rratio 0.25)
			(net 388 "/Fan controller/+5V")
			(pintype "passive")
		)
	)
	(footprint "antmicro-footprints:R_0402_1005Metric"
		(layer "F.Cu")
		(at 99.349999 110.1 180)
		(descr "Resistor SMD 0402")
		(tags "resistor SMD 0402")
		(property "Reference" "R46"
			(at 1.249999 -15.75 0)
			(layer "F.SilkS")
			(effects
				(font
					(size 0.7 0.7)
					(thickness 0.15)
				)
				(justify left bottom)
			)
		)
		(property "Value" "R_150R_0402"
			(at -1.011843 1.772046 0)
			(layer "F.Fab")
			(hide yes)
			(effects
				(font
					(size 0.7 0.7)
					(thickness 0.15)
				)
				(justify right top)
			)
		)
		(property "Datasheet" "https://www.bourns.com/docs/product-datasheets/cr.pdf"
			(at 0 0 0)
			(layer "F.Fab")
			(hide yes)
			(effects
				(font
					(size 1.27 1.27)
					(thickness 0.15)
				)
			)
		)
		(property "Description" "SMD Chip Resistor, 150 ohm, ± 1%, 62.5 mW, 0402 [1005 Metric], Thick Film, General Purpose"
			(at 0 0 0)
			(layer "F.Fab")
			(hide yes)
			(effects
				(font
					(size 1.27 1.27)
					(thickness 0.15)
				)
			)
		)
		(property "MPN" "CR0402-FX-1500GLF"
			(at 0 0 180)
			(unlocked yes)
			(layer "F.Fab")
			(hide yes)
			(effects
				(font
					(size 1 1)
					(thickness 0.15)
				)
			)
		)
		(property "Manufacturer" "Bourns"
			(at 0 0 180)
			(unlocked yes)
			(layer "F.Fab")
			(hide yes)
			(effects
				(font
					(size 1 1)
					(thickness 0.15)
				)
			)
		)
		(property "License" "Apache-2.0"
			(at 0 0 180)
			(unlocked yes)
			(layer "F.Fab")
			(hide yes)
			(effects
				(font
					(size 1 1)
					(thickness 0.15)
				)
			)
		)
		(property "Author" "Antmicro"
			(at 0 0 180)
			(unlocked yes)
			(layer "F.Fab")
			(hide yes)
			(effects
				(font
					(size 1 1)
					(thickness 0.15)
				)
			)
		)
		(property "Val" "150R"
			(at 0 0 180)
			(unlocked yes)
			(layer "F.Fab")
			(hide yes)
			(effects
				(font
					(size 1 1)
					(thickness 0.15)
				)
			)
		)
		(property "Tolerance" "1%"
			(at 0 0 180)
			(unlocked yes)
			(layer "F.Fab")
			(hide yes)
			(effects
				(font
					(size 1 1)
					(thickness 0.15)
				)
			)
		)
		(sheetname "/X710-AT2 10GbE/")
		(sheetfile "x710-at2-10gbe.kicad_sch")
		(attr smd)
		(fp_rect
			(start -0.925 -0.47)
			(end 0.925 0.47)
			(stroke
				(width 0.05)
				(type default)
			)
			(fill no)
			(layer "F.CrtYd")
		)
		(fp_rect
			(start -0.5 -0.25)
			(end 0.5 0.25)
			(stroke
				(width 0.15)
				(type solid)
			)
			(fill no)
			(layer "F.Fab")
		)
		(pad "1" smd roundrect
			(at -0.48 0 180)
			(size 0.59 0.64)
			(layers "F.Cu" "F.Mask" "F.Paste")
			(roundrect_rratio 0.25)
			(net 28 "GND")
			(pintype "passive")
		)
		(pad "2" smd roundrect
			(at 0.48 0 180)
			(size 0.59 0.64)
			(layers "F.Cu" "F.Mask" "F.Paste")
			(roundrect_rratio 0.25)
			(net 73 "/X710-AT2 10GbE/25MHZ_OSC_AC.-")
			(pintype "passive")
		)
	)
	(footprint "antmicro-footprints:R_0402_1005Metric"
		(layer "F.Cu")
		(at 71.8 91.305 90)
		(descr "Resistor SMD 0402")
		(tags "resistor SMD 0402")
		(property "Reference" "R94"
			(at 0.785 0.34 90)
			(layer "F.SilkS")
			(effects
				(font
					(size 0.7 0.7)
					(thickness 0.15)
				)
				(justify left bottom)
			)
		)
		(property "Value" "R_10k_0402"
			(at -1.011843 1.772046 90)
			(layer "F.Fab")
			(hide yes)
			(effects
				(font
					(size 0.7 0.7)
					(thickness 0.15)
				)
				(justify left bottom)
			)
		)
		(property "Datasheet" "https://www.bourns.com/docs/product-datasheets/cr.pdf"
			(at 0 0 90)
			(layer "F.Fab")
			(hide yes)
			(effects
				(font
					(size 1.27 1.27)
					(thickness 0.15)
				)
			)
		)
		(property "Description" "SMD Chip Resistor, 10 kohm, ± 1%, 62.5 mW, 0402 [1005 Metric], Thick Film, General Purpose"
			(at 0 0 90)
			(layer "F.Fab")
			(hide yes)
			(effects
				(font
					(size 1.27 1.27)
					(thickness 0.15)
				)
			)
		)
		(property "MPN" "CR0402-FX-1002GLF"
			(at 0 0 90)
			(unlocked yes)
			(layer "F.Fab")
			(hide yes)
			(effects
				(font
					(size 1 1)
					(thickness 0.15)
				)
			)
		)
		(property "Manufacturer" "Bourns"
			(at 0 0 90)
			(unlocked yes)
			(layer "F.Fab")
			(hide yes)
			(effects
				(font
					(size 1 1)
					(thickness 0.15)
				)
			)
		)
		(property "License" "Apache-2.0"
			(at 0 0 90)
			(unlocked yes)
			(layer "F.Fab")
			(hide yes)
			(effects
				(font
					(size 1 1)
					(thickness 0.15)
				)
			)
		)
		(property "Author" "Antmicro"
			(at 0 0 90)
			(unlocked yes)
			(layer "F.Fab")
			(hide yes)
			(effects
				(font
					(size 1 1)
					(thickness 0.15)
				)
			)
		)
		(property "Val" "10k"
			(at 0 0 90)
			(unlocked yes)
			(layer "F.Fab")
			(hide yes)
			(effects
				(font
					(size 1 1)
					(thickness 0.15)
				)
			)
		)
		(property "Tolerance" "1%"
			(at 0 0 90)
			(unlocked yes)
			(layer "F.Fab")
			(hide yes)
			(effects
				(font
					(size 1 1)
					(thickness 0.15)
				)
			)
		)
		(sheetname "/X710-AT2 Misc/")
		(sheetfile "x710-at2-mics.kicad_sch")
		(attr smd)
		(fp_rect
			(start -0.925 -0.47)
			(end 0.925 0.47)
			(stroke
				(width 0.05)
				(type default)
			)
			(fill no)
			(layer "F.CrtYd")
		)
		(fp_rect
			(start -0.5 -0.25)
			(end 0.5 0.25)
			(stroke
				(width 0.15)
				(type solid)
			)
			(fill no)
			(layer "F.Fab")
		)
		(pad "1" smd roundrect
			(at -0.48 0 90)
			(size 0.59 0.64)
			(layers "F.Cu" "F.Mask" "F.Paste")
			(roundrect_rratio 0.25)
			(net 105 "/Flash memory/FLASH.~{CE}")
			(pintype "passive")
		)
		(pad "2" smd roundrect
			(at 0.48 0 90)
			(size 0.59 0.64)
			(layers "F.Cu" "F.Mask" "F.Paste")
			(roundrect_rratio 0.25)
			(net 7 "+3V3")
			(pintype "passive")
		)
	)
	(footprint "antmicro-footprints:C_0603_1608Metric_EIA"
		(layer "F.Cu")
		(at 77.2 80.950001 180)
		(descr "Capacitor SMD 0603, IPC-7351 Density Level A")
		(tags "Capacitor 0603")
		(property "Reference" "C155"
			(at -1.4 7.400001 0)
			(layer "F.SilkS")
			(effects
				(font
					(size 0.7 0.7)
					(thickness 0.15)
				)
				(justify right top)
			)
		)
		(property "Value" "C_22u_16V_0603"
			(at -1.42757 1.770288 0)
			(layer "F.Fab")
			(hide yes)
			(effects
				(font
					(size 0.7 0.7)
					(thickness 0.15)
				)
				(justify right top)
			)
		)
		(property "Datasheet" "https://product.samsungsem.com/mlcc/CL10A226MO7JZN.do"
			(at 0 0 0)
			(layer "F.Fab")
			(hide yes)
			(effects
				(font
					(size 1.27 1.27)
					(thickness 0.15)
				)
			)
		)
		(property "Description" "SMD Multilayer Ceramic Capacitor"
			(at 0 0 0)
			(layer "F.Fab")
			(hide yes)
			(effects
				(font
					(size 1.27 1.27)
					(thickness 0.15)
				)
			)
		)
		(property "MPN" "CL10A226MO7JZNC"
			(at 0 0 180)
			(unlocked yes)
			(layer "F.Fab")
			(hide yes)
			(effects
				(font
					(size 1 1)
					(thickness 0.15)
				)
			)
		)
		(property "Manufacturer" "Samsung Electro-Mechanics"
			(at 0 0 180)
			(unlocked yes)
			(layer "F.Fab")
			(hide yes)
			(effects
				(font
					(size 1 1)
					(thickness 0.15)
				)
			)
		)
		(property "License" "Apache-2.0"
			(at 0 0 180)
			(unlocked yes)
			(layer "F.Fab")
			(hide yes)
			(effects
				(font
					(size 1 1)
					(thickness 0.15)
				)
			)
		)
		(property "Author" "Antmicro"
			(at 0 0 180)
			(unlocked yes)
			(layer "F.Fab")
			(hide yes)
			(effects
				(font
					(size 1 1)
					(thickness 0.15)
				)
			)
		)
		(property "Val" "22u"
			(at 0 0 180)
			(unlocked yes)
			(layer "F.Fab")
			(hide yes)
			(effects
				(font
					(size 1 1)
					(thickness 0.15)
				)
			)
		)
		(property "Voltage" "16V"
			(at 0 0 180)
			(unlocked yes)
			(layer "F.Fab")
			(hide yes)
			(effects
				(font
					(size 1 1)
					(thickness 0.15)
				)
			)
		)
		(property "Dielectric" ""
			(at 0 0 180)
			(unlocked yes)
			(layer "F.Fab")
			(hide yes)
			(effects
				(font
					(size 1 1)
					(thickness 0.15)
				)
			)
		)
		(sheetname "/X710-AT2 power/")
		(sheetfile "x710-at2-power.kicad_sch")
		(attr smd)
		(fp_line
			(start -0.15 0.55)
			(end 0.15 0.55)
			(stroke
				(width 0.15)
				(type solid)
			)
			(layer "F.SilkS")
		)
		(fp_line
			(start -0.15 -0.55)
			(end 0.15 -0.55)
			(stroke
				(width 0.15)
				(type solid)
			)
			(layer "F.SilkS")
		)
		(fp_rect
			(start -1.25 -0.65)
			(end 1.25 0.65)
			(stroke
				(width 0.05)
				(type solid)
			)
			(fill no)
			(layer "F.CrtYd")
		)
		(fp_rect
			(start -0.8 -0.45)
			(end 0.8 0.45)
			(stroke
				(width 0.15)
				(type solid)
			)
			(fill no)
			(layer "F.Fab")
		)
		(pad "1" smd roundrect
			(at -0.7 0 180)
			(size 0.8 1.1)
			(layers "F.Cu" "F.Mask" "F.Paste")
			(roundrect_rratio 0.2)
			(net 28 "GND")
			(pintype "passive")
		)
		(pad "2" smd roundrect
			(at 0.7 0 180)
			(size 0.8 1.1)
			(layers "F.Cu" "F.Mask" "F.Paste")
			(roundrect_rratio 0.2)
			(net 7 "+3V3")
			(pintype "passive")
		)
	)
	(footprint "antmicro-footprints:C_0603_1608Metric"
		(layer "F.Cu")
		(at 97.9 97.95 180)
		(descr "Capacitor SMD 0603")
		(tags "capacitor 0603")
		(property "Reference" "C146"
			(at -3.75 0.35 0)
			(layer "F.SilkS")
			(effects
				(font
					(size 0.7 0.7)
					(thickness 0.15)
				)
				(justify left top)
			)
		)
		(property "Value" "C_10u_10V_X7R_0603"
			(at -1.42757 1.770288 0)
			(layer "F.Fab")
			(hide yes)
			(effects
				(font
					(size 0.7 0.7)
					(thickness 0.15)
				)
				(justify right top)
			)
		)
		(property "Datasheet" "https://www.murata.com/products/productdetail?partno=GRM188Z71A106KA73%23"
			(at 0 0 0)
			(layer "F.Fab")
			(hide yes)
			(effects
				(font
					(size 1.27 1.27)
					(thickness 0.15)
				)
			)
		)
		(property "Description" "SMD Multilayer Ceramic Capacitor,  10µF, 10V, 0603, ±10%, X7R"
			(at 0 0 0)
			(layer "F.Fab")
			(hide yes)
			(effects
				(font
					(size 1.27 1.27)
					(thickness 0.15)
				)
			)
		)
		(property "MPN" "GRM188Z71A106KA73D"
			(at 0 0 180)
			(unlocked yes)
			(layer "F.Fab")
			(hide yes)
			(effects
				(font
					(size 1 1)
					(thickness 0.15)
				)
			)
		)
		(property "Val" "10u"
			(at 0 0 180)
			(unlocked yes)
			(layer "F.Fab")
			(hide yes)
			(effects
				(font
					(size 1 1)
					(thickness 0.15)
				)
			)
		)
		(property "Voltage" "10V"
			(at 0 0 180)
			(unlocked yes)
			(layer "F.Fab")
			(hide yes)
			(effects
				(font
					(size 1 1)
					(thickness 0.15)
				)
			)
		)
		(property "Dielectric" "X7R"
			(at 0 0 180)
			(unlocked yes)
			(layer "F.Fab")
			(hide yes)
			(effects
				(font
					(size 1 1)
					(thickness 0.15)
				)
			)
		)
		(property "Manufacturer" "Murata"
			(at 0 0 180)
			(unlocked yes)
			(layer "F.Fab")
			(hide yes)
			(effects
				(font
					(size 1 1)
					(thickness 0.15)
				)
			)
		)
		(property "License" "Apache-2.0"
			(at 0 0 180)
			(unlocked yes)
			(layer "F.Fab")
			(hide yes)
			(effects
				(font
					(size 1 1)
					(thickness 0.15)
				)
			)
		)
		(property "Author" "Antmicro"
			(at 0 0 180)
			(unlocked yes)
			(layer "F.Fab")
			(hide yes)
			(effects
				(font
					(size 1 1)
					(thickness 0.15)
				)
			)
		)
		(sheetname "/X710-AT2 power/")
		(sheetfile "x710-at2-power.kicad_sch")
		(attr smd)
		(fp_line
			(start -0.15 0.4)
			(end 0.15 0.4)
			(stroke
				(width 0.15)
				(type solid)
			)
			(layer "F.SilkS")
		)
		(fp_line
			(start -0.15 -0.4)
			(end 0.15 -0.4)
			(stroke
				(width 0.15)
				(type solid)
			)
			(layer "F.SilkS")
		)
		(fp_rect
			(start -1.25 -0.65)
			(end 1.25 0.65)
			(stroke
				(width 0.05)
				(type solid)
			)
			(fill no)
			(layer "F.CrtYd")
		)
		(fp_rect
			(start -0.8 -0.4)
			(end 0.8 0.4)
			(stroke
				(width 0.15)
				(type solid)
			)
			(fill no)
			(layer "F.Fab")
		)
		(pad "1" smd roundrect
			(at -0.7 0 180)
			(size 0.8 1)
			(layers "F.Cu" "F.Mask" "F.Paste")
			(roundrect_rratio 0.2)
			(net 28 "GND")
			(pintype "passive")
		)
		(pad "2" smd roundrect
			(at 0.7 0 180)
			(size 0.8 1)
			(layers "F.Cu" "F.Mask" "F.Paste")
			(roundrect_rratio 0.2)
			(net 7 "+3V3")
			(pintype "passive")
		)
	)
	(footprint "antmicro-footprints:C_0402_1005Metric"
		(layer "F.Cu")
		(at 57.099999 108.25 -90)
		(descr "Capacitor SMD 0402")
		(tags "capacitor SMD 0402")
		(property "Reference" "C33"
			(at 5.68 -1.750001 270)
			(layer "F.SilkS")
			(effects
				(font
					(size 0.7 0.7)
					(thickness 0.15)
				)
				(justify right top)
			)
		)
		(property "Value" "C_1u_25V_0402"
			(at -1.022927 2.155213 90)
			(layer "F.Fab")
			(hide yes)
			(effects
				(font
					(size 0.7 0.7)
					(thickness 0.15)
				)
				(justify right top)
			)
		)
		(property "Datasheet" "https://www.murata.com/products/productdetail?partno=GRM155R61E105KE11%23"
			(at 0 0 90)
			(layer "F.Fab")
			(hide yes)
			(effects
				(font
					(size 1.27 1.27)
					(thickness 0.15)
				)
			)
		)
		(property "Description" "SMD Multilayer Ceramic Capacitor, 1 µF, 25 V, 0402 [1005 Metric], ± 10%, X5R, GRM Series"
			(at 0 0 90)
			(layer "F.Fab")
			(hide yes)
			(effects
				(font
					(size 1.27 1.27)
					(thickness 0.15)
				)
			)
		)
		(property "MPN" "GRM155R61E105KE11J"
			(at 0 0 270)
			(unlocked yes)
			(layer "F.Fab")
			(hide yes)
			(effects
				(font
					(size 1 1)
					(thickness 0.15)
				)
			)
		)
		(property "Manufacturer" "Murata"
			(at 0 0 270)
			(unlocked yes)
			(layer "F.Fab")
			(hide yes)
			(effects
				(font
					(size 1 1)
					(thickness 0.15)
				)
			)
		)
		(property "License" "Apache-2.0"
			(at 0 0 270)
			(unlocked yes)
			(layer "F.Fab")
			(hide yes)
			(effects
				(font
					(size 1 1)
					(thickness 0.15)
				)
			)
		)
		(property "Author" "Antmicro"
			(at 0 0 270)
			(unlocked yes)
			(layer "F.Fab")
			(hide yes)
			(effects
				(font
					(size 1 1)
					(thickness 0.15)
				)
			)
		)
		(property "Val" "1u"
			(at 0 0 270)
			(unlocked yes)
			(layer "F.Fab")
			(hide yes)
			(effects
				(font
					(size 1 1)
					(thickness 0.15)
				)
			)
		)
		(property "Voltage" "25V"
			(at 0 0 270)
			(unlocked yes)
			(layer "F.Fab")
			(hide yes)
			(effects
				(font
					(size 1 1)
					(thickness 0.15)
				)
			)
		)
		(property "Dielectric" "X5R"
			(at 0 0 270)
			(unlocked yes)
			(layer "F.Fab")
			(hide yes)
			(effects
				(font
					(size 1 1)
					(thickness 0.15)
				)
			)
		)
		(sheetname "/Power/")
		(sheetfile "power.kicad_sch")
		(attr smd)
		(fp_rect
			(start -0.925 -0.47)
			(end 0.925 0.47)
			(stroke
				(width 0.05)
				(type default)
			)
			(fill no)
			(layer "F.CrtYd")
		)
		(fp_line
			(start -0.494 0.248)
			(end -0.494 -0.25)
			(stroke
				(width 0.15)
				(type solid)
			)
			(layer "F.Fab")
		)
		(fp_line
			(start 0.504 0.248)
			(end -0.494 0.248)
			(stroke
				(width 0.15)
				(type solid)
			)
			(layer "F.Fab")
		)
		(fp_line
			(start -0.494 -0.25)
			(end 0.504 -0.25)
			(stroke
				(width 0.15)
				(type solid)
			)
			(layer "F.Fab")
		)
		(fp_line
			(start 0.504 -0.25)
			(end 0.504 0.248)
			(stroke
				(width 0.15)
				(type solid)
			)
			(layer "F.Fab")
		)
		(pad "1" smd roundrect
			(at -0.48 0 270)
			(size 0.59 0.64)
			(layers "F.Cu" "F.Mask" "F.Paste")
			(roundrect_rratio 0.25)
			(net 28 "GND")
			(pintype "passive")
		)
		(pad "2" smd roundrect
			(at 0.48 0 270)
			(size 0.59 0.64)
			(layers "F.Cu" "F.Mask" "F.Paste")
			(roundrect_rratio 0.25)
			(net 328 "/Power/1V0_VCC")
			(pintype "passive")
		)
	)
	(footprint "antmicro-footprints:C_0402_1005Metric"
		(layer "F.Cu")
		(at 103 65.285 -90)
		(descr "Capacitor SMD 0402")
		(tags "capacitor SMD 0402")
		(property "Reference" "C192"
			(at 0.792273 -0.499995 270)
			(layer "F.SilkS")
			(effects
				(font
					(size 0.7 0.7)
					(thickness 0.15)
				)
				(justify right bottom)
			)
		)
		(property "Value" "C_220n_16V_0402"
			(at -1.022927 2.155213 270)
			(layer "F.Fab")
			(hide yes)
			(effects
				(font
					(size 0.7 0.7)
					(thickness 0.15)
				)
				(justify left bottom)
			)
		)
		(property "Datasheet" "https://www.murata.com/products/productdetail?partno=GRM155R71C224KA12%23"
			(at 0 0 270)
			(layer "F.Fab")
			(hide yes)
			(effects
				(font
					(size 1.27 1.27)
					(thickness 0.15)
				)
			)
		)
		(property "Description" "SMD Multilayer Ceramic Capacitor, 0.22 µF, 16 V, 0402 [1005 Metric], ± 10%, X7R, GRM Series"
			(at 0 0 270)
			(layer "F.Fab")
			(hide yes)
			(effects
				(font
					(size 1.27 1.27)
					(thickness 0.15)
				)
			)
		)
		(property "MPN" "GRM155R71C224KA12D"
			(at 0 0 270)
			(unlocked yes)
			(layer "F.Fab")
			(hide yes)
			(effects
				(font
					(size 1 1)
					(thickness 0.15)
				)
			)
		)
		(property "Manufacturer" "Murata"
			(at 0 0 270)
			(unlocked yes)
			(layer "F.Fab")
			(hide yes)
			(effects
				(font
					(size 1 1)
					(thickness 0.15)
				)
			)
		)
		(property "License" "Apache-2.0"
			(at 0 0 270)
			(unlocked yes)
			(layer "F.Fab")
			(hide yes)
			(effects
				(font
					(size 1 1)
					(thickness 0.15)
				)
			)
		)
		(property "Author" "Antmicro"
			(at 0 0 270)
			(unlocked yes)
			(layer "F.Fab")
			(hide yes)
			(effects
				(font
					(size 1 1)
					(thickness 0.15)
				)
			)
		)
		(property "Val" "220n"
			(at 0 0 270)
			(unlocked yes)
			(layer "F.Fab")
			(hide yes)
			(effects
				(font
					(size 1 1)
					(thickness 0.15)
				)
			)
		)
		(property "Voltage" "16V"
			(at 0 0 270)
			(unlocked yes)
			(layer "F.Fab")
			(hide yes)
			(effects
				(font
					(size 1 1)
					(thickness 0.15)
				)
			)
		)
		(property "Dielectric" "X7R"
			(at 0 0 270)
			(unlocked yes)
			(layer "F.Fab")
			(hide yes)
			(effects
				(font
					(size 1 1)
					(thickness 0.15)
				)
			)
		)
		(sheetname "/X710-AT2 PCIe/")
		(sheetfile "x710-at2-pcie.kicad_sch")
		(attr smd)
		(fp_rect
			(start -0.925 -0.47)
			(end 0.925 0.47)
			(stroke
				(width 0.05)
				(type default)
			)
			(fill no)
			(layer "F.CrtYd")
		)
		(fp_line
			(start -0.494 0.248)
			(end -0.494 -0.25)
			(stroke
				(width 0.15)
				(type solid)
			)
			(layer "F.Fab")
		)
		(fp_line
			(start 0.504 0.248)
			(end -0.494 0.248)
			(stroke
				(width 0.15)
				(type solid)
			)
			(layer "F.Fab")
		)
		(fp_line
			(start -0.494 -0.25)
			(end 0.504 -0.25)
			(stroke
				(width 0.15)
				(type solid)
			)
			(layer "F.Fab")
		)
		(fp_line
			(start 0.504 -0.25)
			(end 0.504 0.248)
			(stroke
				(width 0.15)
				(type solid)
			)
			(layer "F.Fab")
		)
		(pad "1" smd roundrect
			(at -0.48 0 270)
			(size 0.59 0.64)
			(layers "F.Cu" "F.Mask" "F.Paste")
			(roundrect_rratio 0.25)
			(net 19 "/OCuLink/PCIe_{x4}.TX1+")
			(pintype "passive")
		)
		(pad "2" smd roundrect
			(at 0.48 0 270)
			(size 0.59 0.64)
			(layers "F.Cu" "F.Mask" "F.Paste")
			(roundrect_rratio 0.25)
			(net 35 "/X710-AT2 PCIe/PCIe_{x4}_AC.TX1+")
			(pintype "passive")
		)
	)
	(footprint "antmicro-footprints:R_0402_1005Metric"
		(layer "F.Cu")
		(at 73.85 78.039994 180)
		(descr "Resistor SMD 0402")
		(tags "resistor SMD 0402")
		(property "Reference" "R6"
			(at -1 3.439994 0)
			(layer "F.SilkS")
			(effects
				(font
					(size 0.7 0.7)
					(thickness 0.15)
				)
				(justify right top)
			)
		)
		(property "Value" "R_20k_0402"
			(at -1.011843 1.772046 0)
			(layer "F.Fab")
			(hide yes)
			(effects
				(font
					(size 0.7 0.7)
					(thickness 0.15)
				)
				(justify right top)
			)
		)
		(property "Datasheet" "https://www.bourns.com/docs/product-datasheets/cr.pdf"
			(at 0 0 0)
			(layer "F.Fab")
			(hide yes)
			(effects
				(font
					(size 1.27 1.27)
					(thickness 0.15)
				)
			)
		)
		(property "Description" "SMD Chip Resistor, 20 kohm, ± 1%, 62.5 mW, 0402 [1005 Metric], Thick Film, General Purpose"
			(at 0 0 0)
			(layer "F.Fab")
			(hide yes)
			(effects
				(font
					(size 1.27 1.27)
					(thickness 0.15)
				)
			)
		)
		(property "MPN" "CR0402-FX-2002GLF"
			(at 0 0 180)
			(unlocked yes)
			(layer "F.Fab")
			(hide yes)
			(effects
				(font
					(size 1 1)
					(thickness 0.15)
				)
			)
		)
		(property "Manufacturer" "Bourns"
			(at 0 0 180)
			(unlocked yes)
			(layer "F.Fab")
			(hide yes)
			(effects
				(font
					(size 1 1)
					(thickness 0.15)
				)
			)
		)
		(property "License" "Apache-2.0"
			(at 0 0 180)
			(unlocked yes)
			(layer "F.Fab")
			(hide yes)
			(effects
				(font
					(size 1 1)
					(thickness 0.15)
				)
			)
		)
		(property "Author" "Antmicro"
			(at 0 0 180)
			(unlocked yes)
			(layer "F.Fab")
			(hide yes)
			(effects
				(font
					(size 1 1)
					(thickness 0.15)
				)
			)
		)
		(property "Val" "20k"
			(at 0 0 180)
			(unlocked yes)
			(layer "F.Fab")
			(hide yes)
			(effects
				(font
					(size 1 1)
					(thickness 0.15)
				)
			)
		)
		(property "Tolerance" "1%"
			(at 0 0 180)
			(unlocked yes)
			(layer "F.Fab")
			(hide yes)
			(effects
				(font
					(size 1 1)
					(thickness 0.15)
				)
			)
		)
		(sheetname "/Power/")
		(sheetfile "power.kicad_sch")
		(attr smd)
		(fp_rect
			(start -0.925 -0.47)
			(end 0.925 0.47)
			(stroke
				(width 0.05)
				(type default)
			)
			(fill no)
			(layer "F.CrtYd")
		)
		(fp_rect
			(start -0.5 -0.25)
			(end 0.5 0.25)
			(stroke
				(width 0.15)
				(type solid)
			)
			(fill no)
			(layer "F.Fab")
		)
		(pad "1" smd roundrect
			(at -0.48 0 180)
			(size 0.59 0.64)
			(layers "F.Cu" "F.Mask" "F.Paste")
			(roundrect_rratio 0.25)
			(net 28 "GND")
			(pintype "passive")
		)
		(pad "2" smd roundrect
			(at 0.48 0 180)
			(size 0.59 0.64)
			(layers "F.Cu" "F.Mask" "F.Paste")
			(roundrect_rratio 0.25)
			(net 317 "/Power/3V3_FB")
			(pintype "passive")
		)
	)
	(footprint "antmicro-footprints:C_0402_1005Metric"
		(layer "F.Cu")
		(at 86.8 68.38)
		(descr "Capacitor SMD 0402")
		(tags "capacitor SMD 0402")
		(property "Reference" "C203"
			(at -1.23 1.43 0)
			(layer "F.SilkS")
			(effects
				(font
					(size 0.7 0.7)
					(thickness 0.15)
				)
				(justify left bottom)
			)
		)
		(property "Value" "C_1u_25V_0402"
			(at -1.022927 2.155213 0)
			(layer "F.Fab")
			(hide yes)
			(effects
				(font
					(size 0.7 0.7)
					(thickness 0.15)
				)
				(justify left bottom)
			)
		)
		(property "Datasheet" "https://www.murata.com/products/productdetail?partno=GRM155R61E105KE11%23"
			(at 0 0 0)
			(layer "F.Fab")
			(hide yes)
			(effects
				(font
					(size 1.27 1.27)
					(thickness 0.15)
				)
			)
		)
		(property "Description" "SMD Multilayer Ceramic Capacitor, 1 µF, 25 V, 0402 [1005 Metric], ± 10%, X5R, GRM Series"
			(at 0 0 0)
			(layer "F.Fab")
			(hide yes)
			(effects
				(font
					(size 1.27 1.27)
					(thickness 0.15)
				)
			)
		)
		(property "MPN" "GRM155R61E105KE11J"
			(at 0 0 0)
			(unlocked yes)
			(layer "F.Fab")
			(hide yes)
			(effects
				(font
					(size 1 1)
					(thickness 0.15)
				)
			)
		)
		(property "Manufacturer" "Murata"
			(at 0 0 0)
			(unlocked yes)
			(layer "F.Fab")
			(hide yes)
			(effects
				(font
					(size 1 1)
					(thickness 0.15)
				)
			)
		)
		(property "License" "Apache-2.0"
			(at 0 0 0)
			(unlocked yes)
			(layer "F.Fab")
			(hide yes)
			(effects
				(font
					(size 1 1)
					(thickness 0.15)
				)
			)
		)
		(property "Author" "Antmicro"
			(at 0 0 0)
			(unlocked yes)
			(layer "F.Fab")
			(hide yes)
			(effects
				(font
					(size 1 1)
					(thickness 0.15)
				)
			)
		)
		(property "Val" "1u"
			(at 0 0 0)
			(unlocked yes)
			(layer "F.Fab")
			(hide yes)
			(effects
				(font
					(size 1 1)
					(thickness 0.15)
				)
			)
		)
		(property "Voltage" "25V"
			(at 0 0 0)
			(unlocked yes)
			(layer "F.Fab")
			(hide yes)
			(effects
				(font
					(size 1 1)
					(thickness 0.15)
				)
			)
		)
		(property "Dielectric" "X5R"
			(at 0 0 0)
			(unlocked yes)
			(layer "F.Fab")
			(hide yes)
			(effects
				(font
					(size 1 1)
					(thickness 0.15)
				)
			)
		)
		(sheetname "/Power/Ideal diode 2/")
		(sheetfile "ideal-diode.kicad_sch")
		(attr smd)
		(fp_rect
			(start -0.925 -0.47)
			(end 0.925 0.47)
			(stroke
				(width 0.05)
				(type default)
			)
			(fill no)
			(layer "F.CrtYd")
		)
		(fp_line
			(start -0.494 -0.25)
			(end 0.504 -0.25)
			(stroke
				(width 0.15)
				(type solid)
			)
			(layer "F.Fab")
		)
		(fp_line
			(start -0.494 0.248)
			(end -0.494 -0.25)
			(stroke
				(width 0.15)
				(type solid)
			)
			(layer "F.Fab")
		)
		(fp_line
			(start 0.504 -0.25)
			(end 0.504 0.248)
			(stroke
				(width 0.15)
				(type solid)
			)
			(layer "F.Fab")
		)
		(fp_line
			(start 0.504 0.248)
			(end -0.494 0.248)
			(stroke
				(width 0.15)
				(type solid)
			)
			(layer "F.Fab")
		)
		(pad "1" smd roundrect
			(at -0.48 0)
			(size 0.59 0.64)
			(layers "F.Cu" "F.Mask" "F.Paste")
			(roundrect_rratio 0.25)
			(net 28 "GND")
			(pintype "passive")
		)
		(pad "2" smd roundrect
			(at 0.48 0)
			(size 0.59 0.64)
			(layers "F.Cu" "F.Mask" "F.Paste")
			(roundrect_rratio 0.25)
			(net 314 "VCC")
			(pintype "passive")
		)
	)
	(footprint "antmicro-footprints:C_0402_1005Metric"
		(layer "F.Cu")
		(at 54.4 103.900001 -90)
		(descr "Capacitor SMD 0402")
		(tags "capacitor SMD 0402")
		(property "Reference" "C23"
			(at 1.259999 1.68 90)
			(layer "F.SilkS")
			(effects
				(font
					(size 0.7 0.7)
					(thickness 0.15)
				)
				(justify right top)
			)
		)
		(property "Value" "C_100n_0402"
			(at -1.022927 2.155213 90)
			(layer "F.Fab")
			(hide yes)
			(effects
				(font
					(size 0.7 0.7)
					(thickness 0.15)
				)
				(justify right top)
			)
		)
		(property "Datasheet" "https://www.murata.com/products/productdetail?partno=GRM155R61H104KE14%23"
			(at 0 0 90)
			(layer "F.Fab")
			(hide yes)
			(effects
				(font
					(size 1.27 1.27)
					(thickness 0.15)
				)
			)
		)
		(property "Description" "SMD Multilayer Ceramic Capacitor, 0.1 µF, 50 V, 0402 [1005 Metric], ± 10%, X5R, GRM Series"
			(at 0 0 90)
			(layer "F.Fab")
			(hide yes)
			(effects
				(font
					(size 1.27 1.27)
					(thickness 0.15)
				)
			)
		)
		(property "MPN" "GRM155R61H104KE14D"
			(at 0 0 270)
			(unlocked yes)
			(layer "F.Fab")
			(hide yes)
			(effects
				(font
					(size 1 1)
					(thickness 0.15)
				)
			)
		)
		(property "Manufacturer" "Murata"
			(at 0 0 270)
			(unlocked yes)
			(layer "F.Fab")
			(hide yes)
			(effects
				(font
					(size 1 1)
					(thickness 0.15)
				)
			)
		)
		(property "License" "Apache-2.0"
			(at 0 0 270)
			(unlocked yes)
			(layer "F.Fab")
			(hide yes)
			(effects
				(font
					(size 1 1)
					(thickness 0.15)
				)
			)
		)
		(property "Author" "Antmicro"
			(at 0 0 270)
			(unlocked yes)
			(layer "F.Fab")
			(hide yes)
			(effects
				(font
					(size 1 1)
					(thickness 0.15)
				)
			)
		)
		(property "Val" "100n"
			(at 0 0 270)
			(unlocked yes)
			(layer "F.Fab")
			(hide yes)
			(effects
				(font
					(size 1 1)
					(thickness 0.15)
				)
			)
		)
		(property "Voltage" "50V"
			(at 0 0 270)
			(unlocked yes)
			(layer "F.Fab")
			(hide yes)
			(effects
				(font
					(size 1 1)
					(thickness 0.15)
				)
			)
		)
		(property "Dielectric" "X5R"
			(at 0 0 270)
			(unlocked yes)
			(layer "F.Fab")
			(hide yes)
			(effects
				(font
					(size 1 1)
					(thickness 0.15)
				)
			)
		)
		(sheetname "/Power/")
		(sheetfile "power.kicad_sch")
		(attr smd)
		(fp_rect
			(start -0.925 -0.47)
			(end 0.925 0.47)
			(stroke
				(width 0.05)
				(type default)
			)
			(fill no)
			(layer "F.CrtYd")
		)
		(fp_line
			(start -0.494 0.248)
			(end -0.494 -0.25)
			(stroke
				(width 0.15)
				(type solid)
			)
			(layer "F.Fab")
		)
		(fp_line
			(start 0.504 0.248)
			(end -0.494 0.248)
			(stroke
				(width 0.15)
				(type solid)
			)
			(layer "F.Fab")
		)
		(fp_line
			(start -0.494 -0.25)
			(end 0.504 -0.25)
			(stroke
				(width 0.15)
				(type solid)
			)
			(layer "F.Fab")
		)
		(fp_line
			(start 0.504 -0.25)
			(end 0.504 0.248)
			(stroke
				(width 0.15)
				(type solid)
			)
			(layer "F.Fab")
		)
		(pad "1" smd roundrect
			(at -0.48 0 270)
			(size 0.59 0.64)
			(layers "F.Cu" "F.Mask" "F.Paste")
			(roundrect_rratio 0.25)
			(net 28 "GND")
			(pintype "passive")
		)
		(pad "2" smd roundrect
			(at 0.48 0 270)
			(size 0.59 0.64)
			(layers "F.Cu" "F.Mask" "F.Paste")
			(roundrect_rratio 0.25)
			(net 314 "VCC")
			(pintype "passive")
		)
	)
	(footprint "antmicro-footprints:C_0603_1608Metric_EIA"
		(layer "F.Cu")
		(at 73.549998 83.909996 -90)
		(descr "Capacitor SMD 0603, IPC-7351 Density Level A")
		(tags "Capacitor 0603")
		(property "Reference" "C7"
			(at 1.830004 1.529998 90)
			(layer "F.SilkS")
			(effects
				(font
					(size 0.7 0.7)
					(thickness 0.15)
				)
				(justify right top)
			)
		)
		(property "Value" "C_22u_16V_0603"
			(at -1.42757 1.770288 90)
			(layer "F.Fab")
			(hide yes)
			(effects
				(font
					(size 0.7 0.7)
					(thickness 0.15)
				)
				(justify right top)
			)
		)
		(property "Datasheet" "https://product.samsungsem.com/mlcc/CL10A226MO7JZN.do"
			(at 0 0 90)
			(layer "F.Fab")
			(hide yes)
			(effects
				(font
					(size 1.27 1.27)
					(thickness 0.15)
				)
			)
		)
		(property "Description" "SMD Multilayer Ceramic Capacitor"
			(at 0 0 90)
			(layer "F.Fab")
			(hide yes)
			(effects
				(font
					(size 1.27 1.27)
					(thickness 0.15)
				)
			)
		)
		(property "MPN" "CL10A226MO7JZNC"
			(at 0 0 270)
			(unlocked yes)
			(layer "F.Fab")
			(hide yes)
			(effects
				(font
					(size 1 1)
					(thickness 0.15)
				)
			)
		)
		(property "Manufacturer" "Samsung Electro-Mechanics"
			(at 0 0 270)
			(unlocked yes)
			(layer "F.Fab")
			(hide yes)
			(effects
				(font
					(size 1 1)
					(thickness 0.15)
				)
			)
		)
		(property "License" "Apache-2.0"
			(at 0 0 270)
			(unlocked yes)
			(layer "F.Fab")
			(hide yes)
			(effects
				(font
					(size 1 1)
					(thickness 0.15)
				)
			)
		)
		(property "Author" "Antmicro"
			(at 0 0 270)
			(unlocked yes)
			(layer "F.Fab")
			(hide yes)
			(effects
				(font
					(size 1 1)
					(thickness 0.15)
				)
			)
		)
		(property "Val" "22u"
			(at 0 0 270)
			(unlocked yes)
			(layer "F.Fab")
			(hide yes)
			(effects
				(font
					(size 1 1)
					(thickness 0.15)
				)
			)
		)
		(property "Voltage" "16V"
			(at 0 0 270)
			(unlocked yes)
			(layer "F.Fab")
			(hide yes)
			(effects
				(font
					(size 1 1)
					(thickness 0.15)
				)
			)
		)
		(property "Dielectric" ""
			(at 0 0 270)
			(unlocked yes)
			(layer "F.Fab")
			(hide yes)
			(effects
				(font
					(size 1 1)
					(thickness 0.15)
				)
			)
		)
		(property "Public" "False"
			(at 0 0 270)
			(unlocked yes)
			(layer "F.Fab")
			(hide yes)
			(effects
				(font
					(size 1 1)
					(thickness 0.15)
				)
			)
		)
		(sheetname "/Power/")
		(sheetfile "power.kicad_sch")
		(attr smd)
		(fp_line
			(start -0.15 0.55)
			(end 0.15 0.55)
			(stroke
				(width 0.15)
				(type solid)
			)
			(layer "F.SilkS")
		)
		(fp_line
			(start -0.15 -0.55)
			(end 0.15 -0.55)
			(stroke
				(width 0.15)
				(type solid)
			)
			(layer "F.SilkS")
		)
		(fp_rect
			(start -1.25 -0.65)
			(end 1.25 0.65)
			(stroke
				(width 0.05)
				(type solid)
			)
			(fill no)
			(layer "F.CrtYd")
		)
		(fp_rect
			(start -0.8 -0.45)
			(end 0.8 0.45)
			(stroke
				(width 0.15)
				(type solid)
			)
			(fill no)
			(layer "F.Fab")
		)
		(pad "1" smd roundrect
			(at -0.7 0 270)
			(size 0.8 1.1)
			(layers "F.Cu" "F.Mask" "F.Paste")
			(roundrect_rratio 0.2)
			(net 28 "GND")
			(pintype "passive")
		)
		(pad "2" smd roundrect
			(at 0.7 0 270)
			(size 0.8 1.1)
			(layers "F.Cu" "F.Mask" "F.Paste")
			(roundrect_rratio 0.2)
			(net 255 "/Power/+3V3_OUT")
			(pintype "passive")
		)
	)
	(footprint "antmicro-footprints:R_0402_1005Metric"
		(layer "F.Cu")
		(at 97.4 104.25)
		(descr "Resistor SMD 0402")
		(tags "resistor SMD 0402")
		(property "Reference" "R98"
			(at -2.25 15.175 0)
			(layer "F.SilkS")
			(effects
				(font
					(size 0.7 0.7)
					(thickness 0.15)
				)
				(justify left bottom)
			)
		)
		(property "Value" "R_10k_0402"
			(at -1.011843 1.772047 0)
			(layer "F.Fab")
			(hide yes)
			(effects
				(font
					(size 0.7 0.7)
					(thickness 0.15)
				)
				(justify left bottom)
			)
		)
		(property "Datasheet" "https://www.bourns.com/docs/product-datasheets/cr.pdf"
			(at 0 0 0)
			(layer "F.Fab")
			(hide yes)
			(effects
				(font
					(size 1.27 1.27)
					(thickness 0.15)
				)
			)
		)
		(property "Description" "SMD Chip Resistor, 10 kohm, ± 1%, 62.5 mW, 0402 [1005 Metric], Thick Film, General Purpose"
			(at 0 0 0)
			(layer "F.Fab")
			(hide yes)
			(effects
				(font
					(size 1.27 1.27)
					(thickness 0.15)
				)
			)
		)
		(property "MPN" "CR0402-FX-1002GLF"
			(at 0 0 0)
			(unlocked yes)
			(layer "F.Fab")
			(hide yes)
			(effects
				(font
					(size 1 1)
					(thickness 0.15)
				)
			)
		)
		(property "Manufacturer" "Bourns"
			(at 0 0 0)
			(unlocked yes)
			(layer "F.Fab")
			(hide yes)
			(effects
				(font
					(size 1 1)
					(thickness 0.15)
				)
			)
		)
		(property "License" "Apache-2.0"
			(at 0 0 0)
			(unlocked yes)
			(layer "F.Fab")
			(hide yes)
			(effects
				(font
					(size 1 1)
					(thickness 0.15)
				)
			)
		)
		(property "Author" "Antmicro"
			(at 0 0 0)
			(unlocked yes)
			(layer "F.Fab")
			(hide yes)
			(effects
				(font
					(size 1 1)
					(thickness 0.15)
				)
			)
		)
		(property "Val" "10k"
			(at 0 0 0)
			(unlocked yes)
			(layer "F.Fab")
			(hide yes)
			(effects
				(font
					(size 1 1)
					(thickness 0.15)
				)
			)
		)
		(property "Tolerance" "1%"
			(at 0 0 0)
			(unlocked yes)
			(layer "F.Fab")
			(hide yes)
			(effects
				(font
					(size 1 1)
					(thickness 0.15)
				)
			)
		)
		(sheetname "/X710-AT2 Misc/")
		(sheetfile "x710-at2-mics.kicad_sch")
		(attr smd)
		(fp_rect
			(start -0.925 -0.47)
			(end 0.925 0.47)
			(stroke
				(width 0.05)
				(type default)
			)
			(fill no)
			(layer "F.CrtYd")
		)
		(fp_rect
			(start -0.5 -0.25)
			(end 0.5 0.25)
			(stroke
				(width 0.15)
				(type solid)
			)
			(fill no)
			(layer "F.Fab")
		)
		(pad "1" smd roundrect
			(at -0.48 0)
			(size 0.59 0.64)
			(layers "F.Cu" "F.Mask" "F.Paste")
			(roundrect_rratio 0.25)
			(net 100 "/X710-AT2 Misc/AUX_PWR")
			(pintype "passive")
		)
		(pad "2" smd roundrect
			(at 0.48 0)
			(size 0.59 0.64)
			(layers "F.Cu" "F.Mask" "F.Paste")
			(roundrect_rratio 0.25)
			(net 7 "+3V3")
			(pintype "passive")
		)
	)
	(footprint "antmicro-footprints:LED_0603_1608Metric_G"
		(layer "F.Cu")
		(at 54.35 125.1 180)
		(descr "LED SMD 0603 Green")
		(tags "LED SMD 0603 Green")
		(property "Reference" "D17"
			(at -1.1 -0.75 0)
			(layer "F.SilkS")
			(effects
				(font
					(size 0.7 0.7)
					(thickness 0.15)
				)
				(justify right top)
			)
		)
		(property "Value" "LED_G_0603_LG_L29K-G2J1-24-Z"
			(at -0.001 1.599 0)
			(layer "F.Fab")
			(hide yes)
			(effects
				(font
					(size 0.7 0.7)
					(thickness 0.15)
				)
				(justify right top)
			)
		)
		(property "Datasheet" "https://look.ams-osram.com/m/19ee86b3ae0ee95b/original/LG-L29K.pdf"
			(at 0 0 0)
			(layer "F.Fab")
			(hide yes)
			(effects
				(font
					(size 1.27 1.27)
					(thickness 0.15)
				)
			)
		)
		(property "Description" "LED, Green, SMD, 0603, 20 mA, 1.7 V, 570 nm"
			(at 0 0 0)
			(layer "F.Fab")
			(hide yes)
			(effects
				(font
					(size 1.27 1.27)
					(thickness 0.15)
				)
			)
		)
		(property "MPN" "LG L29K-G2J1-24-Z"
			(at 0 0 180)
			(unlocked yes)
			(layer "F.Fab")
			(hide yes)
			(effects
				(font
					(size 1 1)
					(thickness 0.15)
				)
			)
		)
		(property "Manufacturer" "OSRAM"
			(at 0 0 180)
			(unlocked yes)
			(layer "F.Fab")
			(hide yes)
			(effects
				(font
					(size 1 1)
					(thickness 0.15)
				)
			)
		)
		(property "Color" "Green"
			(at 0 0 180)
			(unlocked yes)
			(layer "F.Fab")
			(hide yes)
			(effects
				(font
					(size 1 1)
					(thickness 0.15)
				)
			)
		)
		(property "Author" "Antmicro"
			(at 0 0 180)
			(unlocked yes)
			(layer "F.Fab")
			(hide yes)
			(effects
				(font
					(size 1 1)
					(thickness 0.15)
				)
			)
		)
		(property "License" "Apache-2.0"
			(at 0 0 180)
			(unlocked yes)
			(layer "F.Fab")
			(hide yes)
			(effects
				(font
					(size 1 1)
					(thickness 0.15)
				)
			)
		)
		(sheetname "/Power/")
		(sheetfile "power.kicad_sch")
		(attr smd)
		(fp_line
			(start 0.22 0.35)
			(end -0.22 0.35)
			(stroke
				(width 0.15)
				(type solid)
			)
			(layer "F.SilkS")
		)
		(fp_line
			(start 0.22 -0.35)
			(end -0.22 -0.35)
			(stroke
				(width 0.15)
				(type solid)
			)
			(layer "F.SilkS")
		)
		(fp_line
			(start 0.105328 0.201008)
			(end 0.105328 -0.198992)
			(stroke
				(width 0.1)
				(type solid)
			)
			(layer "F.SilkS")
		)
		(fp_line
			(start 0.105328 0.201008)
			(end -0.094672 0.001008)
			(stroke
				(width 0.1)
				(type solid)
			)
			(layer "F.SilkS")
		)
		(fp_line
			(start 0.105328 0.001008)
			(end 0.24 0.001)
			(stroke
				(width 0.1)
				(type solid)
			)
			(layer "F.SilkS")
		)
		(fp_line
			(start -0.094672 0.201008)
			(end -0.094672 -0.198992)
			(stroke
				(width 0.1)
				(type solid)
			)
			(layer "F.SilkS")
		)
		(fp_line
			(start -0.094672 0.001008)
			(end 0.105328 -0.198992)
			(stroke
				(width 0.1)
				(type solid)
			)
			(layer "F.SilkS")
		)
		(fp_line
			(start -0.094672 0.001008)
			(end -0.24 0.001008)
			(stroke
				(width 0.1)
				(type solid)
			)
			(layer "F.SilkS")
		)
		(fp_line
			(start -1.18 -0.319)
			(end -1.18 0.321)
			(stroke
				(width 0.15)
				(type solid)
			)
			(layer "F.SilkS")
		)
		(fp_rect
			(start 1.25 0.65)
			(end -1.25 -0.65)
			(stroke
				(width 0.05)
				(type solid)
			)
			(fill no)
			(layer "F.CrtYd")
		)
		(fp_line
			(start 0.599 0)
			(end 0.201 0)
			(stroke
				(width 0.15)
				(type solid)
			)
			(layer "F.Fab")
		)
		(fp_line
			(start 0.201 0.2)
			(end 0.201 0)
			(stroke
				(width 0.15)
				(type solid)
			)
			(layer "F.Fab")
		)
		(fp_line
			(start 0.201 0)
			(end 0.201 -0.202)
			(stroke
				(width 0.15)
				(type solid)
			)
			(layer "F.Fab")
		)
		(fp_line
			(start 0.201 -0.202)
			(end -0.101 0)
			(stroke
				(width 0.15)
				(type solid)
			)
			(layer "F.Fab")
		)
		(fp_line
			(start -0.101 0)
			(end 0.201 0.2)
			(stroke
				(width 0.15)
				(type solid)
			)
			(layer "F.Fab")
		)
		(fp_line
			(start -0.199 0.2)
			(end -0.199 0.1)
			(stroke
				(width 0.15)
				(type solid)
			)
			(layer "F.Fab")
		)
		(fp_line
			(start -0.199 0)
			(end -0.597 0)
			(stroke
				(width 0.15)
				(type solid)
			)
			(layer "F.Fab")
		)
		(fp_line
			(start -0.199 -0.202)
			(end -0.199 0.1)
			(stroke
				(width 0.15)
				(type solid)
			)
			(layer "F.Fab")
		)
		(fp_rect
			(start 0.848 0.4)
			(end -0.85 -0.402)
			(stroke
				(width 0.15)
				(type solid)
			)
			(fill no)
			(layer "F.Fab")
		)
		(fp_text user "Author: Antmicro"
			(at -1.4224 4.799 180)
			(layer "F.Fab")
			(effects
				(font
					(size 0.7 0.7)
					(thickness 0.15)
				)
				(justify left bottom)
			)
		)
		(fp_text user "License: Apache-2.0"
			(at -1.4224 3.599 180)
			(layer "F.Fab")
			(effects
				(font
					(size 0.7 0.7)
					(thickness 0.15)
				)
				(justify left bottom)
			)
		)
		(fp_text user "${REFERENCE}"
			(at -1.4224 5.999 180)
			(layer "F.Fab")
			(effects
				(font
					(size 0.7 0.7)
					(thickness 0.15)
				)
				(justify left bottom)
			)
		)
		(pad "1" smd roundrect
			(at -0.7 0)
			(size 0.8 1)
			(layers "F.Cu" "F.Mask" "F.Paste")
			(roundrect_rratio 0.2)
			(net 411 "Net-(D17-C)")
			(pinfunction "C")
			(pintype "passive")
		)
		(pad "2" smd roundrect
			(at 0.7 0)
			(size 0.8 1)
			(layers "F.Cu" "F.Mask" "F.Paste")
			(roundrect_rratio 0.2)
			(net 255 "/Power/+3V3_OUT")
			(pinfunction "A")
			(pintype "passive")
		)
	)
	(footprint "antmicro-footprints:FB_0603_1608Metric"
		(layer "F.Cu")
		(at 69.1 97.75)
		(property "Reference" "FB4"
			(at -3.19 0.41 0)
			(layer "F.SilkS")
			(effects
				(font
					(size 0.7 0.7)
					(thickness 0.15)
				)
				(justify left bottom)
			)
		)
		(property "Value" "FB_33Z_3A_Murata-BLM18PG_0603"
			(at 0 1.5 0)
			(layer "F.Fab")
			(hide yes)
			(effects
				(font
					(size 0.7 0.7)
					(thickness 0.15)
				)
				(justify left bottom)
			)
		)
		(property "Datasheet" "https://www.murata.com/products/productdata/8796737273886/QNFA9101.pdf?1649080818000"
			(at 0 0 0)
			(layer "F.Fab")
			(hide yes)
			(effects
				(font
					(size 1.27 1.27)
					(thickness 0.15)
				)
			)
		)
		(property "Description" "Ferrite Bead, 0603 [1608 Metric], 33 ohm, 3 A, BLM18PG, 0.025 ohm, ± 25%, DC power line"
			(at 0 0 0)
			(layer "F.Fab")
			(hide yes)
			(effects
				(font
					(size 1.27 1.27)
					(thickness 0.15)
				)
			)
		)
		(property "Val" "33Z/3A"
			(at 0 0 0)
			(unlocked yes)
			(layer "F.Fab")
			(hide yes)
			(effects
				(font
					(size 1 1)
					(thickness 0.15)
				)
			)
		)
		(property "MPN" "BLM18PG330SH1D"
			(at 0 0 0)
			(unlocked yes)
			(layer "F.Fab")
			(hide yes)
			(effects
				(font
					(size 1 1)
					(thickness 0.15)
				)
			)
		)
		(property "Manufacturer" "Murata"
			(at 0 0 0)
			(unlocked yes)
			(layer "F.Fab")
			(hide yes)
			(effects
				(font
					(size 1 1)
					(thickness 0.15)
				)
			)
		)
		(property "Current" ""
			(at 0 0 0)
			(unlocked yes)
			(layer "F.Fab")
			(hide yes)
			(effects
				(font
					(size 1 1)
					(thickness 0.15)
				)
			)
		)
		(property "Author" "Antmicro"
			(at 0 0 0)
			(unlocked yes)
			(layer "F.Fab")
			(hide yes)
			(effects
				(font
					(size 1 1)
					(thickness 0.15)
				)
			)
		)
		(property "License" "Apache-2.0"
			(at 0 0 0)
			(unlocked yes)
			(layer "F.Fab")
			(hide yes)
			(effects
				(font
					(size 1 1)
					(thickness 0.15)
				)
			)
		)
		(sheetname "/X710-AT2 power/")
		(sheetfile "x710-at2-power.kicad_sch")
		(attr smd)
		(fp_line
			(start -0.15 -0.4)
			(end 0.15 -0.4)
			(stroke
				(width 0.15)
				(type solid)
			)
			(layer "F.SilkS")
		)
		(fp_line
			(start -0.15 0.4)
			(end 0.15 0.4)
			(stroke
				(width 0.15)
				(type solid)
			)
			(layer "F.SilkS")
		)
		(fp_rect
			(start -1.25 -0.65)
			(end 1.25 0.65)
			(stroke
				(width 0.05)
				(type solid)
			)
			(fill no)
			(layer "F.CrtYd")
		)
		(fp_line
			(start -0.803 0.406)
			(end -0.803 -0.408)
			(stroke
				(width 0.15)
				(type solid)
			)
			(layer "F.Fab")
		)
		(fp_line
			(start 0.8 -0.408)
			(end -0.803 -0.408)
			(stroke
				(width 0.15)
				(type solid)
			)
			(layer "F.Fab")
		)
		(fp_line
			(start 0.8 -0.408)
			(end 0.8 0.406)
			(stroke
				(width 0.15)
				(type solid)
			)
			(layer "F.Fab")
		)
		(fp_line
			(start 0.8 0.406)
			(end -0.803 0.406)
			(stroke
				(width 0.15)
				(type solid)
			)
			(layer "F.Fab")
		)
		(pad "1" smd roundrect
			(at -0.7 0)
			(size 0.8 1)
			(layers "F.Cu" "F.Mask" "F.Paste")
			(roundrect_rratio 0.2)
			(net 18 "+1V88")
			(pintype "passive")
		)
		(pad "2" smd roundrect
			(at 0.7 0)
			(size 0.8 1)
			(layers "F.Cu" "F.Mask" "F.Paste")
			(roundrect_rratio 0.2)
			(net 10 "AVDDH")
			(pintype "passive")
		)
	)
	(footprint "antmicro-footprints:L_Bourns-SRP4021HMT"
		(layer "F.Cu")
		(at 60.249999 111.549999 180)
		(property "Reference" "L4"
			(at -2.620001 -2.240001 0)
			(layer "F.SilkS")
			(effects
				(font
					(size 0.7 0.7)
					(thickness 0.15)
				)
				(justify right top)
			)
		)
		(property "Value" "L_1u_10A_Bourns-SRP4021HMT"
			(at -2.85 3.4 0)
			(layer "F.Fab")
			(hide yes)
			(effects
				(font
					(size 0.7 0.7)
					(thickness 0.15)
				)
				(justify right top)
			)
		)
		(property "Datasheet" "https://www.mouser.com/datasheet/2/54/Bourns_04_01_2025_SRP4021HMT_Datasheet-3580094.pdf"
			(at 0 0 0)
			(layer "F.Fab")
			(hide yes)
			(effects
				(font
					(size 0.7 0.7)
					(thickness 0.15)
				)
				(justify right top)
			)
		)
		(property "Description" "Power Inductors - SMD Ind,4.1x4.2x1.9mm,1uH+/-20%,10A, Shielded"
			(at 0 0 0)
			(layer "F.Fab")
			(hide yes)
			(effects
				(font
					(size 0.7 0.7)
					(thickness 0.15)
				)
				(justify right top)
			)
		)
		(property "Val" "1u/10A"
			(at 0 0 180)
			(unlocked yes)
			(layer "F.Fab")
			(hide yes)
			(effects
				(font
					(size 1 1)
					(thickness 0.15)
				)
			)
		)
		(property "Manufacturer" "Bourns"
			(at 0 0 180)
			(unlocked yes)
			(layer "F.Fab")
			(hide yes)
			(effects
				(font
					(size 1 1)
					(thickness 0.15)
				)
			)
		)
		(property "MPN" "SRP4021HMT-1R0M"
			(at 0 0 180)
			(unlocked yes)
			(layer "F.Fab")
			(hide yes)
			(effects
				(font
					(size 1 1)
					(thickness 0.15)
				)
			)
		)
		(property "ISat" ""
			(at 0 0 180)
			(unlocked yes)
			(layer "F.Fab")
			(hide yes)
			(effects
				(font
					(size 1 1)
					(thickness 0.15)
				)
			)
		)
		(property "Isat" "8A"
			(at 0 0 180)
			(unlocked yes)
			(layer "F.Fab")
			(hide yes)
			(effects
				(font
					(size 1 1)
					(thickness 0.15)
				)
			)
		)
		(property "IMax" ""
			(at 0 0 180)
			(unlocked yes)
			(layer "F.Fab")
			(hide yes)
			(effects
				(font
					(size 1 1)
					(thickness 0.15)
				)
			)
		)
		(property "Imax" "10A"
			(at 0 0 180)
			(unlocked yes)
			(layer "F.Fab")
			(hide yes)
			(effects
				(font
					(size 1 1)
					(thickness 0.15)
				)
			)
		)
		(property "Size" "4.2x4.1"
			(at 0 0 180)
			(unlocked yes)
			(layer "F.Fab")
			(hide yes)
			(effects
				(font
					(size 1 1)
					(thickness 0.15)
				)
			)
		)
		(property "Author" "Antmicro"
			(at 0 0 180)
			(unlocked yes)
			(layer "F.Fab")
			(hide yes)
			(effects
				(font
					(size 1 1)
					(thickness 0.15)
				)
			)
		)
		(property "License" "Apache-2.0"
			(at 0 0 180)
			(unlocked yes)
			(layer "F.Fab")
			(hide yes)
			(effects
				(font
					(size 1 1)
					(thickness 0.15)
				)
			)
		)
		(sheetname "/Power/")
		(sheetfile "power.kicad_sch")
		(attr smd)
		(fp_line
			(start -0.8 2.05)
			(end 0.8 2.05)
			(stroke
				(width 0.15)
				(type solid)
			)
			(layer "F.SilkS")
		)
		(fp_line
			(start -0.8 -2.05)
			(end 0.8 -2.05)
			(stroke
				(width 0.15)
				(type solid)
			)
			(layer "F.SilkS")
		)
		(fp_rect
			(start -2.85 -2.3)
			(end 2.85 2.3)
			(stroke
				(width 0.05)
				(type solid)
			)
			(fill no)
			(layer "F.CrtYd")
		)
		(fp_rect
			(start -2 -2.05)
			(end 2 2.05)
			(stroke
				(width 0.15)
				(type solid)
			)
			(fill no)
			(layer "F.Fab")
		)
		(pad "1" smd rect
			(at 1.85 0)
			(size 1.5 3.5)
			(layers "F.Cu" "F.Mask" "F.Paste")
			(net 337 "/Power/1V0_SW")
			(pintype "passive")
		)
		(pad "2" smd rect
			(at -1.85 0)
			(size 1.5 3.5)
			(layers "F.Cu" "F.Mask" "F.Paste")
			(net 312 "/Power/+1V0_OUT")
			(pintype "passive")
		)
	)
	(footprint "antmicro-footprints:TSSOP-8_3x3mm_P0.65mm"
		(layer "F.Cu")
		(at 94.8 113.3 180)
		(property "Reference" "U7"
			(at -0.75 -1.9 0)
			(layer "F.SilkS")
			(effects
				(font
					(size 0.7 0.7)
					(thickness 0.15)
				)
				(justify right top)
			)
		)
		(property "Value" "NTS0102_TSSOP"
			(at 0 2.8 0)
			(layer "F.Fab")
			(hide yes)
			(effects
				(font
					(size 0.7 0.7)
					(thickness 0.15)
				)
				(justify right top)
			)
		)
		(property "Datasheet" "https://www.mouser.com/datasheet/2/302/NTS0102-1127324.pdf"
			(at 0 0 0)
			(layer "F.Fab")
			(hide yes)
			(effects
				(font
					(size 1.27 1.27)
					(thickness 0.15)
				)
			)
		)
		(property "Description" "Transceiver, 1.65 V to 3.6 V, TSSOP-8"
			(at 0 0 0)
			(layer "F.Fab")
			(hide yes)
			(effects
				(font
					(size 1.27 1.27)
					(thickness 0.15)
				)
			)
		)
		(property "MPN" "NTS0102DP"
			(at 0 0 180)
			(unlocked yes)
			(layer "F.Fab")
			(hide yes)
			(effects
				(font
					(size 1 1)
					(thickness 0.15)
				)
			)
		)
		(property "Manufacturer" "NXP"
			(at 0 0 180)
			(unlocked yes)
			(layer "F.Fab")
			(hide yes)
			(effects
				(font
					(size 1 1)
					(thickness 0.15)
				)
			)
		)
		(property "Author" "Antmicro"
			(at 0 0 180)
			(unlocked yes)
			(layer "F.Fab")
			(hide yes)
			(effects
				(font
					(size 1 1)
					(thickness 0.15)
				)
			)
		)
		(property "License" "Apache-2.0"
			(at 0 0 180)
			(unlocked yes)
			(layer "F.Fab")
			(hide yes)
			(effects
				(font
					(size 1 1)
					(thickness 0.15)
				)
			)
		)
		(sheetname "/X710-AT2 Misc/")
		(sheetfile "x710-at2-mics.kicad_sch")
		(attr smd)
		(fp_line
			(start -1.525 -1.537)
			(end 1.552 -1.539)
			(stroke
				(width 0.15)
				(type solid)
			)
			(layer "F.SilkS")
		)
		(fp_line
			(start -1.55 1.561)
			(end 1.552 1.561)
			(stroke
				(width 0.15)
				(type solid)
			)
			(layer "F.SilkS")
		)
		(fp_circle
			(center -1.87 -1.4)
			(end -1.82 -1.4)
			(stroke
				(width 0.15)
				(type solid)
			)
			(fill yes)
			(layer "F.SilkS")
		)
		(fp_rect
			(start -3.15 -1.789)
			(end 3.15 1.811)
			(stroke
				(width 0.05)
				(type solid)
			)
			(fill no)
			(layer "F.CrtYd")
		)
		(fp_line
			(start 1.552 -1.539)
			(end 1.552 1.561)
			(stroke
				(width 0.15)
				(type solid)
			)
			(layer "F.Fab")
		)
		(fp_line
			(start -0.949 -1.539)
			(end 1.552 -1.539)
			(stroke
				(width 0.15)
				(type solid)
			)
			(layer "F.Fab")
		)
		(fp_line
			(start -1.55 1.561)
			(end 1.552 1.561)
			(stroke
				(width 0.15)
				(type solid)
			)
			(layer "F.Fab")
		)
		(fp_line
			(start -1.55 -0.937)
			(end -0.949 -1.539)
			(stroke
				(width 0.15)
				(type solid)
			)
			(layer "F.Fab")
		)
		(fp_line
			(start -1.55 -0.937)
			(end -1.55 1.561)
			(stroke
				(width 0.15)
				(type solid)
			)
			(layer "F.Fab")
		)
		(pad "1" smd roundrect
			(at -2.148 -0.962 180)
			(size 1.47 0.4)
			(layers "F.Cu" "F.Mask" "F.Paste")
			(roundrect_rratio 0.25)
			(net 158 "Net-(U7-B_{2})")
			(pinfunction "B_{2}")
			(pintype "bidirectional")
		)
		(pad "2" smd roundrect
			(at -2.148 -0.313 180)
			(size 1.47 0.4)
			(layers "F.Cu" "F.Mask" "F.Paste")
			(roundrect_rratio 0.25)
			(net 28 "GND")
			(pinfunction "GND")
			(pintype "power_in")
		)
		(pad "3" smd roundrect
			(at -2.148 0.338 180)
			(size 1.47 0.4)
			(layers "F.Cu" "F.Mask" "F.Paste")
			(roundrect_rratio 0.25)
			(net 18 "+1V88")
			(pinfunction "VCC_{A}")
			(pintype "power_in")
		)
		(pad "4" smd roundrect
			(at -2.148 0.987 180)
			(size 1.47 0.4)
			(layers "F.Cu" "F.Mask" "F.Paste")
			(roundrect_rratio 0.25)
			(net 157 "Net-(U7-A_{2})")
			(pinfunction "A_{2}")
			(pintype "bidirectional")
		)
		(pad "5" smd roundrect
			(at 2.151 0.987 180)
			(size 1.47 0.4)
			(layers "F.Cu" "F.Mask" "F.Paste")
			(roundrect_rratio 0.25)
			(net 384 "/X710-AT2 Misc/~{PHY_RESET}")
			(pinfunction "A_{1}")
			(pintype "bidirectional")
		)
		(pad "6" smd roundrect
			(at 2.151 0.338 180)
			(size 1.47 0.4)
			(layers "F.Cu" "F.Mask" "F.Paste")
			(roundrect_rratio 0.25)
			(net 18 "+1V88")
			(pinfunction "OE")
			(pintype "input")
		)
		(pad "7" smd roundrect
			(at 2.151 -0.313 180)
			(size 1.47 0.4)
			(layers "F.Cu" "F.Mask" "F.Paste")
			(roundrect_rratio 0.25)
			(net 7 "+3V3")
			(pinfunction "VCC_{B}")
			(pintype "power_in")
		)
		(pad "8" smd roundrect
			(at 2.151 -0.962 180)
			(size 1.47 0.4)
			(layers "F.Cu" "F.Mask" "F.Paste")
			(roundrect_rratio 0.25)
			(net 380 "/X710-AT2 10GbE/~{PHY_RESET_3V3}")
			(pinfunction "B_{1}")
			(pintype "bidirectional")
		)
	)
	(footprint "antmicro-footprints:C_0603_1608Metric_EIA"
		(layer "F.Cu")
		(at 63.199999 85.450001 180)
		(descr "Capacitor SMD 0603, IPC-7351 Density Level A")
		(tags "Capacitor 0603")
		(property "Reference" "C17"
			(at -0.890001 2.760001 0)
			(layer "F.SilkS")
			(effects
				(font
					(size 0.7 0.7)
					(thickness 0.15)
				)
				(justify right top)
			)
		)
		(property "Value" "C_22u_16V_0603"
			(at -1.42757 1.770288 0)
			(layer "F.Fab")
			(hide yes)
			(effects
				(font
					(size 0.7 0.7)
					(thickness 0.15)
				)
				(justify right top)
			)
		)
		(property "Datasheet" "https://product.samsungsem.com/mlcc/CL10A226MO7JZN.do"
			(at 0 0 0)
			(layer "F.Fab")
			(hide yes)
			(effects
				(font
					(size 1.27 1.27)
					(thickness 0.15)
				)
			)
		)
		(property "Description" "SMD Multilayer Ceramic Capacitor"
			(at 0 0 0)
			(layer "F.Fab")
			(hide yes)
			(effects
				(font
					(size 1.27 1.27)
					(thickness 0.15)
				)
			)
		)
		(property "MPN" "CL10A226MO7JZNC"
			(at 0 0 180)
			(unlocked yes)
			(layer "F.Fab")
			(hide yes)
			(effects
				(font
					(size 1 1)
					(thickness 0.15)
				)
			)
		)
		(property "Manufacturer" "Samsung Electro-Mechanics"
			(at 0 0 180)
			(unlocked yes)
			(layer "F.Fab")
			(hide yes)
			(effects
				(font
					(size 1 1)
					(thickness 0.15)
				)
			)
		)
		(property "License" "Apache-2.0"
			(at 0 0 180)
			(unlocked yes)
			(layer "F.Fab")
			(hide yes)
			(effects
				(font
					(size 1 1)
					(thickness 0.15)
				)
			)
		)
		(property "Author" "Antmicro"
			(at 0 0 180)
			(unlocked yes)
			(layer "F.Fab")
			(hide yes)
			(effects
				(font
					(size 1 1)
					(thickness 0.15)
				)
			)
		)
		(property "Val" "22u"
			(at 0 0 180)
			(unlocked yes)
			(layer "F.Fab")
			(hide yes)
			(effects
				(font
					(size 1 1)
					(thickness 0.15)
				)
			)
		)
		(property "Voltage" "16V"
			(at 0 0 180)
			(unlocked yes)
			(layer "F.Fab")
			(hide yes)
			(effects
				(font
					(size 1 1)
					(thickness 0.15)
				)
			)
		)
		(property "Dielectric" ""
			(at 0 0 180)
			(unlocked yes)
			(layer "F.Fab")
			(hide yes)
			(effects
				(font
					(size 1 1)
					(thickness 0.15)
				)
			)
		)
		(property "Public" "False"
			(at 0 0 180)
			(unlocked yes)
			(layer "F.Fab")
			(hide yes)
			(effects
				(font
					(size 1 1)
					(thickness 0.15)
				)
			)
		)
		(sheetname "/Power/")
		(sheetfile "power.kicad_sch")
		(attr smd)
		(fp_line
			(start -0.15 0.55)
			(end 0.15 0.55)
			(stroke
				(width 0.15)
				(type solid)
			)
			(layer "F.SilkS")
		)
		(fp_line
			(start -0.15 -0.55)
			(end 0.15 -0.55)
			(stroke
				(width 0.15)
				(type solid)
			)
			(layer "F.SilkS")
		)
		(fp_rect
			(start -1.25 -0.65)
			(end 1.25 0.65)
			(stroke
				(width 0.05)
				(type solid)
			)
			(fill no)
			(layer "F.CrtYd")
		)
		(fp_rect
			(start -0.8 -0.45)
			(end 0.8 0.45)
			(stroke
				(width 0.15)
				(type solid)
			)
			(fill no)
			(layer "F.Fab")
		)
		(pad "1" smd roundrect
			(at -0.7 0 180)
			(size 0.8 1.1)
			(layers "F.Cu" "F.Mask" "F.Paste")
			(roundrect_rratio 0.2)
			(net 28 "GND")
			(pintype "passive")
		)
		(pad "2" smd roundrect
			(at 0.7 0 180)
			(size 0.8 1.1)
			(layers "F.Cu" "F.Mask" "F.Paste")
			(roundrect_rratio 0.2)
			(net 303 "/Power/+VCCD_OUT")
			(pintype "passive")
		)
	)
	(footprint "antmicro-footprints:C_0402_1005Metric"
		(layer "F.Cu")
		(at 69.1 98.95 180)
		(descr "Capacitor SMD 0402")
		(tags "capacitor SMD 0402")
		(property "Reference" "C138"
			(at 0.86 0.48 0)
			(layer "F.SilkS")
			(effects
				(font
					(size 0.7 0.7)
					(thickness 0.15)
				)
				(justify right top)
			)
		)
		(property "Value" "C_100n_0402"
			(at -1.022927 2.155213 0)
			(layer "F.Fab")
			(hide yes)
			(effects
				(font
					(size 0.7 0.7)
					(thickness 0.15)
				)
				(justify right top)
			)
		)
		(property "Datasheet" "https://www.murata.com/products/productdetail?partno=GRM155R61H104KE14%23"
			(at 0 0 0)
			(layer "F.Fab")
			(hide yes)
			(effects
				(font
					(size 1.27 1.27)
					(thickness 0.15)
				)
			)
		)
		(property "Description" "SMD Multilayer Ceramic Capacitor, 0.1 µF, 50 V, 0402 [1005 Metric], ± 10%, X5R, GRM Series"
			(at 0 0 0)
			(layer "F.Fab")
			(hide yes)
			(effects
				(font
					(size 1.27 1.27)
					(thickness 0.15)
				)
			)
		)
		(property "MPN" "GRM155R61H104KE14D"
			(at 0 0 180)
			(unlocked yes)
			(layer "F.Fab")
			(hide yes)
			(effects
				(font
					(size 1 1)
					(thickness 0.15)
				)
			)
		)
		(property "Val" "100n"
			(at 0 0 180)
			(unlocked yes)
			(layer "F.Fab")
			(hide yes)
			(effects
				(font
					(size 1 1)
					(thickness 0.15)
				)
			)
		)
		(property "Voltage" "50V"
			(at 0 0 180)
			(unlocked yes)
			(layer "F.Fab")
			(hide yes)
			(effects
				(font
					(size 1 1)
					(thickness 0.15)
				)
			)
		)
		(property "Dielectric" "X5R"
			(at 0 0 180)
			(unlocked yes)
			(layer "F.Fab")
			(hide yes)
			(effects
				(font
					(size 1 1)
					(thickness 0.15)
				)
			)
		)
		(property "Manufacturer" "Murata"
			(at 0 0 180)
			(unlocked yes)
			(layer "F.Fab")
			(hide yes)
			(effects
				(font
					(size 1 1)
					(thickness 0.15)
				)
			)
		)
		(property "License" "Apache-2.0"
			(at 0 0 180)
			(unlocked yes)
			(layer "F.Fab")
			(hide yes)
			(effects
				(font
					(size 1 1)
					(thickness 0.15)
				)
			)
		)
		(property "Author" "Antmicro"
			(at 0 0 180)
			(unlocked yes)
			(layer "F.Fab")
			(hide yes)
			(effects
				(font
					(size 1 1)
					(thickness 0.15)
				)
			)
		)
		(sheetname "/X710-AT2 power/")
		(sheetfile "x710-at2-power.kicad_sch")
		(attr smd)
		(fp_rect
			(start -0.925 -0.47)
			(end 0.925 0.47)
			(stroke
				(width 0.05)
				(type default)
			)
			(fill no)
			(layer "F.CrtYd")
		)
		(fp_line
			(start 0.504 0.248)
			(end -0.494 0.248)
			(stroke
				(width 0.15)
				(type solid)
			)
			(layer "F.Fab")
		)
		(fp_line
			(start 0.504 -0.25)
			(end 0.504 0.248)
			(stroke
				(width 0.15)
				(type solid)
			)
			(layer "F.Fab")
		)
		(fp_line
			(start -0.494 0.248)
			(end -0.494 -0.25)
			(stroke
				(width 0.15)
				(type solid)
			)
			(layer "F.Fab")
		)
		(fp_line
			(start -0.494 -0.25)
			(end 0.504 -0.25)
			(stroke
				(width 0.15)
				(type solid)
			)
			(layer "F.Fab")
		)
		(pad "1" smd roundrect
			(at -0.48 0 180)
			(size 0.59 0.64)
			(layers "F.Cu" "F.Mask" "F.Paste")
			(roundrect_rratio 0.25)
			(net 28 "GND")
			(pintype "passive")
		)
		(pad "2" smd roundrect
			(at 0.48 0 180)
			(size 0.59 0.64)
			(layers "F.Cu" "F.Mask" "F.Paste")
			(roundrect_rratio 0.25)
			(net 18 "+1V88")
			(pintype "passive")
		)
	)
	(footprint "antmicro-footprints:C_0603_1608Metric_EIA"
		(layer "F.Cu")
		(at 66.7 86.3 180)
		(descr "Capacitor SMD 0603, IPC-7351 Density Level A")
		(tags "Capacitor 0603")
		(property "Reference" "C127"
			(at -1.97 5.65 0)
			(layer "F.SilkS")
			(effects
				(font
					(size 0.7 0.7)
					(thickness 0.15)
				)
				(justify right top)
			)
		)
		(property "Value" "C_22u_16V_0603"
			(at -1.42757 1.770288 0)
			(layer "F.Fab")
			(hide yes)
			(effects
				(font
					(size 0.7 0.7)
					(thickness 0.15)
				)
				(justify right top)
			)
		)
		(property "Datasheet" "https://product.samsungsem.com/mlcc/CL10A226MO7JZN.do"
			(at 0 0 0)
			(layer "F.Fab")
			(hide yes)
			(effects
				(font
					(size 1.27 1.27)
					(thickness 0.15)
				)
			)
		)
		(property "Description" "SMD Multilayer Ceramic Capacitor"
			(at 0 0 0)
			(layer "F.Fab")
			(hide yes)
			(effects
				(font
					(size 1.27 1.27)
					(thickness 0.15)
				)
			)
		)
		(property "MPN" "CL10A226MO7JZNC"
			(at 0 0 180)
			(unlocked yes)
			(layer "F.Fab")
			(hide yes)
			(effects
				(font
					(size 1 1)
					(thickness 0.15)
				)
			)
		)
		(property "Manufacturer" "Samsung Electro-Mechanics"
			(at 0 0 180)
			(unlocked yes)
			(layer "F.Fab")
			(hide yes)
			(effects
				(font
					(size 1 1)
					(thickness 0.15)
				)
			)
		)
		(property "License" "Apache-2.0"
			(at 0 0 180)
			(unlocked yes)
			(layer "F.Fab")
			(hide yes)
			(effects
				(font
					(size 1 1)
					(thickness 0.15)
				)
			)
		)
		(property "Author" "Antmicro"
			(at 0 0 180)
			(unlocked yes)
			(layer "F.Fab")
			(hide yes)
			(effects
				(font
					(size 1 1)
					(thickness 0.15)
				)
			)
		)
		(property "Val" "22u"
			(at 0 0 180)
			(unlocked yes)
			(layer "F.Fab")
			(hide yes)
			(effects
				(font
					(size 1 1)
					(thickness 0.15)
				)
			)
		)
		(property "Voltage" "16V"
			(at 0 0 180)
			(unlocked yes)
			(layer "F.Fab")
			(hide yes)
			(effects
				(font
					(size 1 1)
					(thickness 0.15)
				)
			)
		)
		(property "Dielectric" ""
			(at 0 0 180)
			(unlocked yes)
			(layer "F.Fab")
			(hide yes)
			(effects
				(font
					(size 1 1)
					(thickness 0.15)
				)
			)
		)
		(sheetname "/X710-AT2 power/")
		(sheetfile "x710-at2-power.kicad_sch")
		(attr smd)
		(fp_line
			(start -0.15 0.55)
			(end 0.15 0.55)
			(stroke
				(width 0.15)
				(type solid)
			)
			(layer "F.SilkS")
		)
		(fp_line
			(start -0.15 -0.55)
			(end 0.15 -0.55)
			(stroke
				(width 0.15)
				(type solid)
			)
			(layer "F.SilkS")
		)
		(fp_rect
			(start -1.25 -0.65)
			(end 1.25 0.65)
			(stroke
				(width 0.05)
				(type solid)
			)
			(fill no)
			(layer "F.CrtYd")
		)
		(fp_rect
			(start -0.8 -0.45)
			(end 0.8 0.45)
			(stroke
				(width 0.15)
				(type solid)
			)
			(fill no)
			(layer "F.Fab")
		)
		(pad "1" smd roundrect
			(at -0.7 0 180)
			(size 0.8 1.1)
			(layers "F.Cu" "F.Mask" "F.Paste")
			(roundrect_rratio 0.2)
			(net 28 "GND")
			(pintype "passive")
		)
		(pad "2" smd roundrect
			(at 0.7 0 180)
			(size 0.8 1.1)
			(layers "F.Cu" "F.Mask" "F.Paste")
			(roundrect_rratio 0.2)
			(net 9 "VCCD")
			(pintype "passive")
		)
	)
	(footprint "antmicro-footprints:MP_Pad6mm_Drill3.2mm"
		(layer "F.Cu")
		(at 113 54.250001)
		(property "Reference" "MP3"
			(at 1.25 -2.950001 0)
			(layer "F.SilkS")
			(hide yes)
			(effects
				(font
					(size 0.7 0.7)
					(thickness 0.15)
				)
				(justify left bottom)
			)
		)
		(property "Value" "MP_Pad6mm_Drill3.2mm"
			(at 0 3.9 0)
			(layer "F.Fab")
			(hide yes)
			(effects
				(font
					(size 0.7 0.7)
					(thickness 0.15)
				)
				(justify left bottom)
			)
		)
		(property "Description" "Mechanical part"
			(at 0 0 0)
			(layer "F.Fab")
			(hide yes)
			(effects
				(font
					(size 1.27 1.27)
					(thickness 0.15)
				)
			)
		)
		(property "Author" "Antmicro"
			(at 0 0 0)
			(unlocked yes)
			(layer "F.Fab")
			(hide yes)
			(effects
				(font
					(size 1 1)
					(thickness 0.15)
				)
			)
		)
		(property "License" "Apache-2.0"
			(at 0 0 0)
			(unlocked yes)
			(layer "F.Fab")
			(hide yes)
			(effects
				(font
					(size 1 1)
					(thickness 0.15)
				)
			)
		)
		(sheetname "/")
		(sheetfile "oculink-to-10gbe-adapter.kicad_sch")
		(attr exclude_from_pos_files exclude_from_bom)
		(fp_circle
			(center 0 0)
			(end 3.25 0)
			(stroke
				(width 0.05)
				(type default)
			)
			(fill no)
			(layer "F.CrtYd")
		)
		(pad "1" thru_hole circle
			(at 0 0)
			(size 6 6)
			(drill 3.2)
			(layers "*.Cu" "*.Mask")
			(remove_unused_layers no)
			(net 28 "GND")
			(pintype "passive")
		)
	)
	(footprint "antmicro-footprints:C_0402_1005Metric"
		(layer "F.Cu")
		(at 73.849999 79.039995)
		(descr "Capacitor SMD 0402")
		(tags "capacitor SMD 0402")
		(property "Reference" "C2"
			(at -3.749999 -8.439995 0)
			(layer "F.SilkS")
			(effects
				(font
					(size 0.7 0.7)
					(thickness 0.15)
				)
				(justify left bottom)
			)
		)
		(property "Value" "C_33p_0402"
			(at -1.022927 2.155213 0)
			(layer "F.Fab")
			(hide yes)
			(effects
				(font
					(size 0.7 0.7)
					(thickness 0.15)
				)
				(justify left bottom)
			)
		)
		(property "Datasheet" "https://spicat.kyocera-avx.com/product/mlcc/chartview/04025A330FAT2A/"
			(at 0 0 0)
			(layer "F.Fab")
			(hide yes)
			(effects
				(font
					(size 1.27 1.27)
					(thickness 0.15)
				)
			)
		)
		(property "Description" "SMD Multilayer Ceramic Capacitor, 33 pF, 50 V, 0402 [1005 Metric], ± 5%, C0G / NP0, MC"
			(at 0 0 0)
			(layer "F.Fab")
			(hide yes)
			(effects
				(font
					(size 1.27 1.27)
					(thickness 0.15)
				)
			)
		)
		(property "MPN" "04025A330FAT2A"
			(at 0 0 0)
			(unlocked yes)
			(layer "F.Fab")
			(hide yes)
			(effects
				(font
					(size 1 1)
					(thickness 0.15)
				)
			)
		)
		(property "Manufacturer" "KYOCERA AVX"
			(at 0 0 0)
			(unlocked yes)
			(layer "F.Fab")
			(hide yes)
			(effects
				(font
					(size 1 1)
					(thickness 0.15)
				)
			)
		)
		(property "License" "Apache-2.0"
			(at 0 0 0)
			(unlocked yes)
			(layer "F.Fab")
			(hide yes)
			(effects
				(font
					(size 1 1)
					(thickness 0.15)
				)
			)
		)
		(property "Author" "Antmicro"
			(at 0 0 0)
			(unlocked yes)
			(layer "F.Fab")
			(hide yes)
			(effects
				(font
					(size 1 1)
					(thickness 0.15)
				)
			)
		)
		(property "Val" "33p"
			(at 0 0 0)
			(unlocked yes)
			(layer "F.Fab")
			(hide yes)
			(effects
				(font
					(size 1 1)
					(thickness 0.15)
				)
			)
		)
		(property "Voltage" ""
			(at 0 0 0)
			(unlocked yes)
			(layer "F.Fab")
			(hide yes)
			(effects
				(font
					(size 1 1)
					(thickness 0.15)
				)
			)
		)
		(property "Dielectric" ""
			(at 0 0 0)
			(unlocked yes)
			(layer "F.Fab")
			(hide yes)
			(effects
				(font
					(size 1 1)
					(thickness 0.15)
				)
			)
		)
		(sheetname "/Power/")
		(sheetfile "power.kicad_sch")
		(attr smd)
		(fp_rect
			(start -0.925 -0.47)
			(end 0.925 0.47)
			(stroke
				(width 0.05)
				(type default)
			)
			(fill no)
			(layer "F.CrtYd")
		)
		(fp_line
			(start -0.494 -0.25)
			(end 0.504 -0.25)
			(stroke
				(width 0.15)
				(type solid)
			)
			(layer "F.Fab")
		)
		(fp_line
			(start -0.494 0.248)
			(end -0.494 -0.25)
			(stroke
				(width 0.15)
				(type solid)
			)
			(layer "F.Fab")
		)
		(fp_line
			(start 0.504 -0.25)
			(end 0.504 0.248)
			(stroke
				(width 0.15)
				(type solid)
			)
			(layer "F.Fab")
		)
		(fp_line
			(start 0.504 0.248)
			(end -0.494 0.248)
			(stroke
				(width 0.15)
				(type solid)
			)
			(layer "F.Fab")
		)
		(pad "1" smd roundrect
			(at -0.48 0)
			(size 0.59 0.64)
			(layers "F.Cu" "F.Mask" "F.Paste")
			(roundrect_rratio 0.25)
			(net 317 "/Power/3V3_FB")
			(pintype "passive")
		)
		(pad "2" smd roundrect
			(at 0.48 0)
			(size 0.59 0.64)
			(layers "F.Cu" "F.Mask" "F.Paste")
			(roundrect_rratio 0.25)
			(net 255 "/Power/+3V3_OUT")
			(pintype "passive")
		)
	)
	(footprint "antmicro-footprints:R_0402_1005Metric"
		(layer "F.Cu")
		(at 56.100001 108.249997 90)
		(descr "Resistor SMD 0402")
		(tags "resistor SMD 0402")
		(property "Reference" "R21"
			(at -7.800003 2.709999 270)
			(layer "F.SilkS")
			(effects
				(font
					(size 0.7 0.7)
					(thickness 0.15)
				)
				(justify left bottom)
			)
		)
		(property "Value" "R_20k_0402"
			(at -1.011843 1.772046 90)
			(layer "F.Fab")
			(hide yes)
			(effects
				(font
					(size 0.7 0.7)
					(thickness 0.15)
				)
				(justify left bottom)
			)
		)
		(property "Datasheet" "https://www.bourns.com/docs/product-datasheets/cr.pdf"
			(at 0 0 90)
			(layer "F.Fab")
			(hide yes)
			(effects
				(font
					(size 1.27 1.27)
					(thickness 0.15)
				)
			)
		)
		(property "Description" "SMD Chip Resistor, 20 kohm, ± 1%, 62.5 mW, 0402 [1005 Metric], Thick Film, General Purpose"
			(at 0 0 90)
			(layer "F.Fab")
			(hide yes)
			(effects
				(font
					(size 1.27 1.27)
					(thickness 0.15)
				)
			)
		)
		(property "MPN" "CR0402-FX-2002GLF"
			(at 0 0 90)
			(unlocked yes)
			(layer "F.Fab")
			(hide yes)
			(effects
				(font
					(size 1 1)
					(thickness 0.15)
				)
			)
		)
		(property "Manufacturer" "Bourns"
			(at 0 0 90)
			(unlocked yes)
			(layer "F.Fab")
			(hide yes)
			(effects
				(font
					(size 1 1)
					(thickness 0.15)
				)
			)
		)
		(property "License" "Apache-2.0"
			(at 0 0 90)
			(unlocked yes)
			(layer "F.Fab")
			(hide yes)
			(effects
				(font
					(size 1 1)
					(thickness 0.15)
				)
			)
		)
		(property "Author" "Antmicro"
			(at 0 0 90)
			(unlocked yes)
			(layer "F.Fab")
			(hide yes)
			(effects
				(font
					(size 1 1)
					(thickness 0.15)
				)
			)
		)
		(property "Val" "20k"
			(at 0 0 90)
			(unlocked yes)
			(layer "F.Fab")
			(hide yes)
			(effects
				(font
					(size 1 1)
					(thickness 0.15)
				)
			)
		)
		(property "Tolerance" "1%"
			(at 0 0 90)
			(unlocked yes)
			(layer "F.Fab")
			(hide yes)
			(effects
				(font
					(size 1 1)
					(thickness 0.15)
				)
			)
		)
		(sheetname "/Power/")
		(sheetfile "power.kicad_sch")
		(attr smd)
		(fp_rect
			(start -0.925 -0.47)
			(end 0.925 0.47)
			(stroke
				(width 0.05)
				(type default)
			)
			(fill no)
			(layer "F.CrtYd")
		)
		(fp_rect
			(start -0.5 -0.25)
			(end 0.5 0.25)
			(stroke
				(width 0.15)
				(type solid)
			)
			(fill no)
			(layer "F.Fab")
		)
		(pad "1" smd roundrect
			(at -0.48 0 90)
			(size 0.59 0.64)
			(layers "F.Cu" "F.Mask" "F.Paste")
			(roundrect_rratio 0.25)
			(net 332 "/Power/1V0_FB")
			(pintype "passive")
		)
		(pad "2" smd roundrect
			(at 0.48 0 90)
			(size 0.59 0.64)
			(layers "F.Cu" "F.Mask" "F.Paste")
			(roundrect_rratio 0.25)
			(net 312 "/Power/+1V0_OUT")
			(pintype "passive")
		)
	)
	(footprint "antmicro-footprints:R_0402_1005Metric"
		(layer "F.Cu")
		(at 101.3 103.3)
		(descr "Resistor SMD 0402")
		(tags "resistor SMD 0402")
		(property "Reference" "R87"
			(at -0.8 15.05 0)
			(layer "F.SilkS")
			(effects
				(font
					(size 0.7 0.7)
					(thickness 0.15)
				)
				(justify left bottom)
			)
		)
		(property "Value" "R_100k_0402"
			(at -1.011843 1.772046 0)
			(layer "F.Fab")
			(hide yes)
			(effects
				(font
					(size 0.7 0.7)
					(thickness 0.15)
				)
				(justify left bottom)
			)
		)
		(property "Datasheet" "https://www.bourns.com/docs/product-datasheets/cr.pdf"
			(at 0 0 0)
			(layer "F.Fab")
			(hide yes)
			(effects
				(font
					(size 1.27 1.27)
					(thickness 0.15)
				)
			)
		)
		(property "Description" "SMD Chip Resistor, 100 kohm, ± 1%, 62.5 mW, 0402 [1005 Metric], Thick Film, General Purpose"
			(at 0 0 0)
			(layer "F.Fab")
			(hide yes)
			(effects
				(font
					(size 1.27 1.27)
					(thickness 0.15)
				)
			)
		)
		(property "MPN" "CR0402-FX-1003GLF"
			(at 0 0 0)
			(unlocked yes)
			(layer "F.Fab")
			(hide yes)
			(effects
				(font
					(size 1 1)
					(thickness 0.15)
				)
			)
		)
		(property "Manufacturer" "Bourns"
			(at 0 0 0)
			(unlocked yes)
			(layer "F.Fab")
			(hide yes)
			(effects
				(font
					(size 1 1)
					(thickness 0.15)
				)
			)
		)
		(property "License" "Apache-2.0"
			(at 0 0 0)
			(unlocked yes)
			(layer "F.Fab")
			(hide yes)
			(effects
				(font
					(size 1 1)
					(thickness 0.15)
				)
			)
		)
		(property "Author" "Antmicro"
			(at 0 0 0)
			(unlocked yes)
			(layer "F.Fab")
			(hide yes)
			(effects
				(font
					(size 1 1)
					(thickness 0.15)
				)
			)
		)
		(property "Val" "100k"
			(at 0 0 0)
			(unlocked yes)
			(layer "F.Fab")
			(hide yes)
			(effects
				(font
					(size 1 1)
					(thickness 0.15)
				)
			)
		)
		(property "Tolerance" "1%"
			(at 0 0 0)
			(unlocked yes)
			(layer "F.Fab")
			(hide yes)
			(effects
				(font
					(size 1 1)
					(thickness 0.15)
				)
			)
		)
		(sheetname "/X710-AT2 Misc/")
		(sheetfile "x710-at2-mics.kicad_sch")
		(attr smd)
		(fp_rect
			(start -0.925 -0.47)
			(end 0.925 0.47)
			(stroke
				(width 0.05)
				(type default)
			)
			(fill no)
			(layer "F.CrtYd")
		)
		(fp_rect
			(start -0.5 -0.25)
			(end 0.5 0.25)
			(stroke
				(width 0.15)
				(type solid)
			)
			(fill no)
			(layer "F.Fab")
		)
		(pad "1" smd roundrect
			(at -0.48 0)
			(size 0.59 0.64)
			(layers "F.Cu" "F.Mask" "F.Paste")
			(roundrect_rratio 0.25)
			(net 28 "GND")
			(pintype "passive")
		)
		(pad "2" smd roundrect
			(at 0.48 0)
			(size 0.59 0.64)
			(layers "F.Cu" "F.Mask" "F.Paste")
			(roundrect_rratio 0.25)
			(net 366 "/X710-AT2 Misc/NCSI.TX_EN")
			(pintype "passive")
		)
	)
	(footprint "antmicro-footprints:R_0402_1005Metric"
		(layer "F.Cu")
		(at 80.349999 83.15 180)
		(descr "Resistor SMD 0402")
		(tags "resistor SMD 0402")
		(property "Reference" "R105"
			(at -1.050001 1.6 0)
			(layer "F.SilkS")
			(effects
				(font
					(size 0.7 0.7)
					(thickness 0.15)
				)
				(justify right bottom)
			)
		)
		(property "Value" "R_0R_0402"
			(at -1.011843 1.772046 0)
			(layer "F.Fab")
			(hide yes)
			(effects
				(font
					(size 0.7 0.7)
					(thickness 0.15)
				)
				(justify right top)
			)
		)
		(property "Datasheet" "https://industrial.panasonic.com/cdbs/www-data/pdf/RDA0000/AOA0000C301.pdf"
			(at 0 0 0)
			(layer "F.Fab")
			(hide yes)
			(effects
				(font
					(size 1.27 1.27)
					(thickness 0.15)
				)
			)
		)
		(property "Description" "SMD Chip Resistor, Jumper, 0 ohm, 100 mW, 0402 [1005 Metric], Thick Film, General Purpose"
			(at 0 0 0)
			(layer "F.Fab")
			(hide yes)
			(effects
				(font
					(size 1.27 1.27)
					(thickness 0.15)
				)
			)
		)
		(property "MPN" "ERJ2GE0R00X"
			(at 0 0 180)
			(unlocked yes)
			(layer "F.Fab")
			(hide yes)
			(effects
				(font
					(size 1 1)
					(thickness 0.15)
				)
			)
		)
		(property "Manufacturer" "Panasonic"
			(at 0 0 180)
			(unlocked yes)
			(layer "F.Fab")
			(hide yes)
			(effects
				(font
					(size 1 1)
					(thickness 0.15)
				)
			)
		)
		(property "License" "Apache-2.0"
			(at 0 0 180)
			(unlocked yes)
			(layer "F.Fab")
			(hide yes)
			(effects
				(font
					(size 1 1)
					(thickness 0.15)
				)
			)
		)
		(property "Author" "Antmicro"
			(at 0 0 180)
			(unlocked yes)
			(layer "F.Fab")
			(hide yes)
			(effects
				(font
					(size 1 1)
					(thickness 0.15)
				)
			)
		)
		(property "Val" "0R"
			(at 0 0 180)
			(unlocked yes)
			(layer "F.Fab")
			(hide yes)
			(effects
				(font
					(size 1 1)
					(thickness 0.15)
				)
			)
		)
		(property "Tolerance" "~"
			(at 0 0 180)
			(unlocked yes)
			(layer "F.Fab")
			(hide yes)
			(effects
				(font
					(size 1 1)
					(thickness 0.15)
				)
			)
		)
		(property "Current" "1A"
			(at 0 0 180)
			(unlocked yes)
			(layer "F.Fab")
			(hide yes)
			(effects
				(font
					(size 1 1)
					(thickness 0.15)
				)
			)
		)
		(sheetname "/X710-AT2 Misc/")
		(sheetfile "x710-at2-mics.kicad_sch")
		(attr smd)
		(fp_rect
			(start -0.925 -0.47)
			(end 0.925 0.47)
			(stroke
				(width 0.05)
				(type default)
			)
			(fill no)
			(layer "F.CrtYd")
		)
		(fp_rect
			(start -0.5 -0.25)
			(end 0.5 0.25)
			(stroke
				(width 0.15)
				(type solid)
			)
			(fill no)
			(layer "F.Fab")
		)
		(pad "1" smd roundrect
			(at -0.48 0 180)
			(size 0.59 0.64)
			(layers "F.Cu" "F.Mask" "F.Paste")
			(roundrect_rratio 0.25)
			(net 308 "/OCuLink/~{PE_RST}")
			(pintype "passive")
		)
		(pad "2" smd roundrect
			(at 0.48 0 180)
			(size 0.59 0.64)
			(layers "F.Cu" "F.Mask" "F.Paste")
			(roundrect_rratio 0.25)
			(net 396 "Net-(U10-A)")
			(pintype "passive")
		)
	)
	(footprint "antmicro-footprints:Oscillator_SMD_Skyworks_SI511_5x3.2x1.17mm"
		(layer "F.Cu")
		(at 104.7 109.235 180)
		(property "Reference" "Y1"
			(at 1.7 2.785 0)
			(layer "F.SilkS")
			(effects
				(font
					(size 0.7 0.7)
					(thickness 0.15)
				)
				(justify left bottom)
			)
		)
		(property "Value" "Oscillator_25MHz_511ABA25M0000BAGR"
			(at -2.75 3.85 0)
			(layer "F.Fab")
			(hide yes)
			(effects
				(font
					(size 0.7 0.7)
					(thickness 0.15)
				)
				(justify right top)
			)
		)
		(property "Datasheet" "https://www.mouser.com/datasheet/2/472/si510_11-2507765.pdf"
			(at 0 0 0)
			(layer "F.Fab")
			(hide yes)
			(effects
				(font
					(size 0.7 0.7)
					(thickness 0.15)
				)
				(justify right top)
			)
		)
		(property "Description" "25 MHz XO (Standard) LVPECL Oscillator 3.3V Enable/Disable 6-SMD, No Lead"
			(at 0 0 0)
			(layer "F.Fab")
			(hide yes)
			(effects
				(font
					(size 0.7 0.7)
					(thickness 0.15)
				)
				(justify right top)
			)
		)
		(property "Manufacturer" "Skyworks Solutions"
			(at 0 0 180)
			(unlocked yes)
			(layer "F.Fab")
			(hide yes)
			(effects
				(font
					(size 1 1)
					(thickness 0.15)
				)
			)
		)
		(property "MPN" "511ABA25M0000BAGR"
			(at 0 0 180)
			(unlocked yes)
			(layer "F.Fab")
			(hide yes)
			(effects
				(font
					(size 1 1)
					(thickness 0.15)
				)
			)
		)
		(property "Val" "25 MHz"
			(at 0 0 180)
			(unlocked yes)
			(layer "F.Fab")
			(hide yes)
			(effects
				(font
					(size 1 1)
					(thickness 0.15)
				)
			)
		)
		(property "Author" "Antmicro"
			(at 0 0 180)
			(unlocked yes)
			(layer "F.Fab")
			(hide yes)
			(effects
				(font
					(size 1 1)
					(thickness 0.15)
				)
			)
		)
		(property "License" "Apache-2.0"
			(at 0 0 180)
			(unlocked yes)
			(layer "F.Fab")
			(hide yes)
			(effects
				(font
					(size 1 1)
					(thickness 0.15)
				)
			)
		)
		(sheetname "/X710-AT2 10GbE/")
		(sheetfile "x710-at2-10gbe.kicad_sch")
		(attr smd)
		(fp_line
			(start 1.6 2.5)
			(end 1.6 1.95)
			(stroke
				(width 0.15)
				(type solid)
			)
			(layer "F.SilkS")
		)
		(fp_line
			(start 1.6 -2.5)
			(end 1.6 -1.95)
			(stroke
				(width 0.15)
				(type solid)
			)
			(layer "F.SilkS")
		)
		(fp_line
			(start 1.6 -2.5)
			(end -1.6 -2.5)
			(stroke
				(width 0.15)
				(type solid)
			)
			(layer "F.SilkS")
		)
		(fp_line
			(start -1.6 2.5)
			(end 1.6 2.5)
			(stroke
				(width 0.15)
				(type solid)
			)
			(layer "F.SilkS")
		)
		(fp_line
			(start -1.6 2.5)
			(end -1.6 1.95)
			(stroke
				(width 0.15)
				(type solid)
			)
			(layer "F.SilkS")
		)
		(fp_line
			(start -1.6 -2.5)
			(end -1.6 -1.95)
			(stroke
				(width 0.15)
				(type solid)
			)
			(layer "F.SilkS")
		)
		(fp_circle
			(center -1.95 -1.875)
			(end -1.9 -1.875)
			(stroke
				(width 0.15)
				(type solid)
			)
			(fill yes)
			(layer "F.SilkS")
		)
		(fp_rect
			(start -2.25 -2.75)
			(end 2.25 2.75)
			(stroke
				(width 0.05)
				(type solid)
			)
			(fill no)
			(layer "F.CrtYd")
		)
		(fp_line
			(start -0.9 -2.5)
			(end -1.6 -1.8)
			(stroke
				(width 0.15)
				(type solid)
			)
			(layer "F.Fab")
		)
		(fp_rect
			(start -1.6 -2.5)
			(end 1.6 2.5)
			(stroke
				(width 0.15)
				(type solid)
			)
			(fill no)
			(layer "F.Fab")
		)
		(pad "1" smd rect
			(at -1.3 -1.27 180)
			(size 1.7 0.8)
			(layers "F.Cu" "F.Mask" "F.Paste")
			(net 149 "/X710-AT2 10GbE/EN_OSC")
			(pinfunction "EN")
			(pintype "input")
		)
		(pad "2" smd rect
			(at -1.3 0 180)
			(size 1.7 0.8)
			(layers "F.Cu" "F.Mask" "F.Paste")
			(net 285 "unconnected-(Y1-NC-Pad2)")
			(pinfunction "NC")
			(pintype "no_connect")
		)
		(pad "3" smd rect
			(at -1.3 1.27 180)
			(size 1.7 0.8)
			(layers "F.Cu" "F.Mask" "F.Paste")
			(net 28 "GND")
			(pinfunction "GND")
			(pintype "power_in")
		)
		(pad "4" smd rect
			(at 1.3 1.27 180)
			(size 1.7 0.8)
			(layers "F.Cu" "F.Mask" "F.Paste")
			(net 143 "/X710-AT2 10GbE/25MHZ_OSC_R.+")
			(pinfunction "OUT+")
			(pintype "output")
		)
		(pad "5" smd rect
			(at 1.3 0 180)
			(size 1.7 0.8)
			(layers "F.Cu" "F.Mask" "F.Paste")
			(net 150 "/X710-AT2 10GbE/25MHZ_OSC_R.-")
			(pinfunction "OUT-")
			(pintype "output")
		)
		(pad "6" smd rect
			(at 1.3 -1.27 180)
			(size 1.7 0.8)
			(layers "F.Cu" "F.Mask" "F.Paste")
			(net 74 "/X710-AT2 10GbE/3V3_OSC")
			(pinfunction "VCC")
			(pintype "power_in")
		)
	)
	(footprint "antmicro-footprints:LED_0603_1608Metric_G"
		(layer "F.Cu")
		(at 90.75 52.65 -90)
		(descr "LED SMD 0603 Green")
		(tags "LED SMD 0603 Green")
		(property "Reference" "D15"
			(at -1.08 0.69 90)
			(layer "F.SilkS")
			(effects
				(font
					(size 0.7 0.7)
					(thickness 0.15)
				)
				(justify right bottom)
			)
		)
		(property "Value" "LED_G_0603_LG_L29K-G2J1-24-Z"
			(at -0.001 1.599 90)
			(layer "F.Fab")
			(hide yes)
			(effects
				(font
					(size 0.7 0.7)
					(thickness 0.15)
				)
				(justify right top)
			)
		)
		(property "Datasheet" "https://look.ams-osram.com/m/19ee86b3ae0ee95b/original/LG-L29K.pdf"
			(at 0 0 90)
			(layer "F.Fab")
			(hide yes)
			(effects
				(font
					(size 1.27 1.27)
					(thickness 0.15)
				)
			)
		)
		(property "Description" "LED, Green, SMD, 0603, 20 mA, 1.7 V, 570 nm"
			(at 0 0 90)
			(layer "F.Fab")
			(hide yes)
			(effects
				(font
					(size 1.27 1.27)
					(thickness 0.15)
				)
			)
		)
		(property "MPN" "LG L29K-G2J1-24-Z"
			(at 0 0 270)
			(unlocked yes)
			(layer "F.Fab")
			(hide yes)
			(effects
				(font
					(size 1 1)
					(thickness 0.15)
				)
			)
		)
		(property "Manufacturer" "OSRAM"
			(at 0 0 270)
			(unlocked yes)
			(layer "F.Fab")
			(hide yes)
			(effects
				(font
					(size 1 1)
					(thickness 0.15)
				)
			)
		)
		(property "Color" "Green"
			(at 0 0 270)
			(unlocked yes)
			(layer "F.Fab")
			(hide yes)
			(effects
				(font
					(size 1 1)
					(thickness 0.15)
				)
			)
		)
		(property "Author" "Antmicro"
			(at 0 0 270)
			(unlocked yes)
			(layer "F.Fab")
			(hide yes)
			(effects
				(font
					(size 1 1)
					(thickness 0.15)
				)
			)
		)
		(property "License" "Apache-2.0"
			(at 0 0 270)
			(unlocked yes)
			(layer "F.Fab")
			(hide yes)
			(effects
				(font
					(size 1 1)
					(thickness 0.15)
				)
			)
		)
		(sheetname "/OCuLink/")
		(sheetfile "oculink.kicad_sch")
		(attr smd)
		(fp_line
			(start 0.22 0.35)
			(end -0.22 0.35)
			(stroke
				(width 0.15)
				(type solid)
			)
			(layer "F.SilkS")
		)
		(fp_line
			(start -0.094672 0.201008)
			(end -0.094672 -0.198992)
			(stroke
				(width 0.1)
				(type solid)
			)
			(layer "F.SilkS")
		)
		(fp_line
			(start 0.105328 0.201008)
			(end -0.094672 0.001008)
			(stroke
				(width 0.1)
				(type solid)
			)
			(layer "F.SilkS")
		)
		(fp_line
			(start 0.105328 0.201008)
			(end 0.105328 -0.198992)
			(stroke
				(width 0.1)
				(type solid)
			)
			(layer "F.SilkS")
		)
		(fp_line
			(start -0.094672 0.001008)
			(end -0.24 0.001008)
			(stroke
				(width 0.1)
				(type solid)
			)
			(layer "F.SilkS")
		)
		(fp_line
			(start -0.094672 0.001008)
			(end 0.105328 -0.198992)
			(stroke
				(width 0.1)
				(type solid)
			)
			(layer "F.SilkS")
		)
		(fp_line
			(start 0.105328 0.001008)
			(end 0.24 0.001)
			(stroke
				(width 0.1)
				(type solid)
			)
			(layer "F.SilkS")
		)
		(fp_line
			(start -1.18 -0.319)
			(end -1.18 0.321)
			(stroke
				(width 0.15)
				(type solid)
			)
			(layer "F.SilkS")
		)
		(fp_line
			(start 0.22 -0.35)
			(end -0.22 -0.35)
			(stroke
				(width 0.15)
				(type solid)
			)
			(layer "F.SilkS")
		)
		(fp_rect
			(start 1.25 0.65)
			(end -1.25 -0.65)
			(stroke
				(width 0.05)
				(type solid)
			)
			(fill no)
			(layer "F.CrtYd")
		)
		(fp_line
			(start -0.199 0.2)
			(end -0.199 0.1)
			(stroke
				(width 0.15)
				(type solid)
			)
			(layer "F.Fab")
		)
		(fp_line
			(start 0.201 0.2)
			(end 0.201 0)
			(stroke
				(width 0.15)
				(type solid)
			)
			(layer "F.Fab")
		)
		(fp_line
			(start -0.199 0)
			(end -0.597 0)
			(stroke
				(width 0.15)
				(type solid)
			)
			(layer "F.Fab")
		)
		(fp_line
			(start -0.101 0)
			(end 0.201 0.2)
			(stroke
				(width 0.15)
				(type solid)
			)
			(layer "F.Fab")
		)
		(fp_line
			(start 0.201 0)
			(end 0.201 -0.202)
			(stroke
				(width 0.15)
				(type solid)
			)
			(layer "F.Fab")
		)
		(fp_line
			(start 0.599 0)
			(end 0.201 0)
			(stroke
				(width 0.15)
				(type solid)
			)
			(layer "F.Fab")
		)
		(fp_line
			(start -0.199 -0.202)
			(end -0.199 0.1)
			(stroke
				(width 0.15)
				(type solid)
			)
			(layer "F.Fab")
		)
		(fp_line
			(start 0.201 -0.202)
			(end -0.101 0)
			(stroke
				(width 0.15)
				(type solid)
			)
			(layer "F.Fab")
		)
		(fp_rect
			(start 0.848 0.4)
			(end -0.85 -0.402)
			(stroke
				(width 0.15)
				(type solid)
			)
			(fill no)
			(layer "F.Fab")
		)
		(fp_text user "License: Apache-2.0"
			(at -1.4224 3.599 270)
			(layer "F.Fab")
			(effects
				(font
					(size 0.7 0.7)
					(thickness 0.15)
				)
				(justify left bottom)
			)
		)
		(fp_text user "${REFERENCE}"
			(at -1.4224 5.999 270)
			(layer "F.Fab")
			(effects
				(font
					(size 0.7 0.7)
					(thickness 0.15)
				)
				(justify left bottom)
			)
		)
		(fp_text user "Author: Antmicro"
			(at -1.4224 4.799 270)
			(layer "F.Fab")
			(effects
				(font
					(size 0.7 0.7)
					(thickness 0.15)
				)
				(justify left bottom)
			)
		)
		(pad "1" smd roundrect
			(at -0.7 0 90)
			(size 0.8 1)
			(layers "F.Cu" "F.Mask" "F.Paste")
			(roundrect_rratio 0.2)
			(net 28 "GND")
			(pinfunction "C")
			(pintype "passive")
		)
		(pad "2" smd roundrect
			(at 0.7 0 90)
			(size 0.8 1)
			(layers "F.Cu" "F.Mask" "F.Paste")
			(roundrect_rratio 0.2)
			(net 410 "Net-(D15-A)")
			(pinfunction "A")
			(pintype "passive")
		)
	)
	(footprint "antmicro-footprints:C_0402_1005Metric"
		(layer "F.Cu")
		(at 54.4 88.5 -90)
		(descr "Capacitor SMD 0402")
		(tags "capacitor SMD 0402")
		(property "Reference" "C14"
			(at 1.25 1.55 90)
			(layer "F.SilkS")
			(effects
				(font
					(size 0.7 0.7)
					(thickness 0.15)
				)
				(justify right top)
			)
		)
		(property "Value" "C_100n_0402"
			(at -1.022927 2.155213 90)
			(layer "F.Fab")
			(hide yes)
			(effects
				(font
					(size 0.7 0.7)
					(thickness 0.15)
				)
				(justify right top)
			)
		)
		(property "Datasheet" "https://www.murata.com/products/productdetail?partno=GRM155R61H104KE14%23"
			(at 0 0 90)
			(layer "F.Fab")
			(hide yes)
			(effects
				(font
					(size 1.27 1.27)
					(thickness 0.15)
				)
			)
		)
		(property "Description" "SMD Multilayer Ceramic Capacitor, 0.1 µF, 50 V, 0402 [1005 Metric], ± 10%, X5R, GRM Series"
			(at 0 0 90)
			(layer "F.Fab")
			(hide yes)
			(effects
				(font
					(size 1.27 1.27)
					(thickness 0.15)
				)
			)
		)
		(property "MPN" "GRM155R61H104KE14D"
			(at 0 0 270)
			(unlocked yes)
			(layer "F.Fab")
			(hide yes)
			(effects
				(font
					(size 1 1)
					(thickness 0.15)
				)
			)
		)
		(property "Manufacturer" "Murata"
			(at 0 0 270)
			(unlocked yes)
			(layer "F.Fab")
			(hide yes)
			(effects
				(font
					(size 1 1)
					(thickness 0.15)
				)
			)
		)
		(property "License" "Apache-2.0"
			(at 0 0 270)
			(unlocked yes)
			(layer "F.Fab")
			(hide yes)
			(effects
				(font
					(size 1 1)
					(thickness 0.15)
				)
			)
		)
		(property "Author" "Antmicro"
			(at 0 0 270)
			(unlocked yes)
			(layer "F.Fab")
			(hide yes)
			(effects
				(font
					(size 1 1)
					(thickness 0.15)
				)
			)
		)
		(property "Val" "100n"
			(at 0 0 270)
			(unlocked yes)
			(layer "F.Fab")
			(hide yes)
			(effects
				(font
					(size 1 1)
					(thickness 0.15)
				)
			)
		)
		(property "Voltage" "50V"
			(at 0 0 270)
			(unlocked yes)
			(layer "F.Fab")
			(hide yes)
			(effects
				(font
					(size 1 1)
					(thickness 0.15)
				)
			)
		)
		(property "Dielectric" "X5R"
			(at 0 0 270)
			(unlocked yes)
			(layer "F.Fab")
			(hide yes)
			(effects
				(font
					(size 1 1)
					(thickness 0.15)
				)
			)
		)
		(sheetname "/Power/")
		(sheetfile "power.kicad_sch")
		(attr smd)
		(fp_rect
			(start -0.925 -0.47)
			(end 0.925 0.47)
			(stroke
				(width 0.05)
				(type default)
			)
			(fill no)
			(layer "F.CrtYd")
		)
		(fp_line
			(start -0.494 0.248)
			(end -0.494 -0.25)
			(stroke
				(width 0.15)
				(type solid)
			)
			(layer "F.Fab")
		)
		(fp_line
			(start 0.504 0.248)
			(end -0.494 0.248)
			(stroke
				(width 0.15)
				(type solid)
			)
			(layer "F.Fab")
		)
		(fp_line
			(start -0.494 -0.25)
			(end 0.504 -0.25)
			(stroke
				(width 0.15)
				(type solid)
			)
			(layer "F.Fab")
		)
		(fp_line
			(start 0.504 -0.25)
			(end 0.504 0.248)
			(stroke
				(width 0.15)
				(type solid)
			)
			(layer "F.Fab")
		)
		(pad "1" smd roundrect
			(at -0.48 0 270)
			(size 0.59 0.64)
			(layers "F.Cu" "F.Mask" "F.Paste")
			(roundrect_rratio 0.25)
			(net 28 "GND")
			(pintype "passive")
		)
		(pad "2" smd roundrect
			(at 0.48 0 270)
			(size 0.59 0.64)
			(layers "F.Cu" "F.Mask" "F.Paste")
			(roundrect_rratio 0.25)
			(net 314 "VCC")
			(pintype "passive")
		)
	)
	(footprint "antmicro-footprints:USON-10_2.5x1mm_P0.5mm"
		(layer "F.Cu")
		(at 100.25 59.985 -90)
		(descr "USON-10 2.5x1mm_ Pitch 0.5mm")
		(tags "USON-10 2.5x1mm Pitch 0.5mm")
		(property "Reference" "D6"
			(at 1.7 0.7 180)
			(layer "F.SilkS")
			(effects
				(font
					(size 0.7 0.7)
					(thickness 0.15)
				)
				(justify left bottom)
			)
		)
		(property "Value" "ESD204DQAR"
			(at 0.018 2.499 90)
			(layer "F.Fab")
			(hide yes)
			(effects
				(font
					(size 0.7 0.7)
					(thickness 0.15)
				)
				(justify right top)
			)
		)
		(property "Datasheet" "https://www.ti.com/lit/ds/symlink/esd204.pdf?ts=1706004844383&ref_url=https%253A%252F%252Fwww.ti.com%252Finterface%252Fdiodes%252Fesd-protection-diodes%252Fproducts.html"
			(at 0 0 90)
			(layer "F.Fab")
			(hide yes)
			(effects
				(font
					(size 1.27 1.27)
					(thickness 0.15)
				)
			)
		)
		(property "Description" "TVS diode array, 30 kV, USON-10, 3.6 V, 0.55 pF"
			(at 0 0 90)
			(layer "F.Fab")
			(hide yes)
			(effects
				(font
					(size 1.27 1.27)
					(thickness 0.15)
				)
			)
		)
		(property "MPN" "ESD204DQAR"
			(at 0 0 270)
			(unlocked yes)
			(layer "F.Fab")
			(hide yes)
			(effects
				(font
					(size 1 1)
					(thickness 0.15)
				)
			)
		)
		(property "Manufacturer" "Texas Instruments"
			(at 0 0 270)
			(unlocked yes)
			(layer "F.Fab")
			(hide yes)
			(effects
				(font
					(size 1 1)
					(thickness 0.15)
				)
			)
		)
		(property "Author" "Antmicro"
			(at 0 0 270)
			(unlocked yes)
			(layer "F.Fab")
			(hide yes)
			(effects
				(font
					(size 1 1)
					(thickness 0.15)
				)
			)
		)
		(property "License" "Apache-2.0"
			(at 0 0 270)
			(unlocked yes)
			(layer "F.Fab")
			(hide yes)
			(effects
				(font
					(size 1 1)
					(thickness 0.15)
				)
			)
		)
		(sheetname "/OCuLink/")
		(sheetfile "oculink.kicad_sch")
		(attr smd)
		(fp_line
			(start 0.498 1.398)
			(end -0.5 1.398)
			(stroke
				(width 0.15)
				(type solid)
			)
			(layer "F.SilkS")
		)
		(fp_line
			(start 0.498 -1.401)
			(end -0.5 -1.401)
			(stroke
				(width 0.15)
				(type solid)
			)
			(layer "F.SilkS")
		)
		(fp_circle
			(center -0.68 -1.27)
			(end -0.63 -1.27)
			(stroke
				(width 0.15)
				(type solid)
			)
			(fill yes)
			(layer "F.SilkS")
		)
		(fp_rect
			(start -0.8 -1.5)
			(end 0.8 1.499)
			(stroke
				(width 0.05)
				(type solid)
			)
			(fill no)
			(layer "F.CrtYd")
		)
		(fp_line
			(start -0.5 1.249)
			(end 0.498 1.249)
			(stroke
				(width 0.15)
				(type solid)
			)
			(layer "F.Fab")
		)
		(fp_line
			(start -0.5 -1)
			(end -0.5 1.249)
			(stroke
				(width 0.15)
				(type solid)
			)
			(layer "F.Fab")
		)
		(fp_line
			(start -0.25 -1.25)
			(end -0.5 -1)
			(stroke
				(width 0.15)
				(type solid)
			)
			(layer "F.Fab")
		)
		(fp_line
			(start 0.498 -1.25)
			(end 0.498 1.249)
			(stroke
				(width 0.15)
				(type solid)
			)
			(layer "F.Fab")
		)
		(fp_line
			(start 0.498 -1.25)
			(end -0.25 -1.25)
			(stroke
				(width 0.15)
				(type solid)
			)
			(layer "F.Fab")
		)
		(pad "1" smd roundrect
			(at -0.387 -1 180)
			(size 0.25 0.55)
			(layers "F.Cu" "F.Mask" "F.Paste")
			(roundrect_rratio 0.25)
			(net 117 "unconnected-(D6-Pad1)")
			(pintype "passive+no_connect")
		)
		(pad "2" smd roundrect
			(at -0.387 -0.5 180)
			(size 0.25 0.55)
			(layers "F.Cu" "F.Mask" "F.Paste")
			(roundrect_rratio 0.25)
			(net 320 "/OCuLink/~{CWAKE}_R")
			(pintype "passive")
		)
		(pad "3" smd roundrect
			(at -0.387 0 180)
			(size 0.4 0.55)
			(layers "F.Cu" "F.Mask" "F.Paste")
			(roundrect_rratio 0.25)
			(net 28 "GND")
			(pintype "power_in")
		)
		(pad "4" smd roundrect
			(at -0.387 0.498 180)
			(size 0.25 0.55)
			(layers "F.Cu" "F.Mask" "F.Paste")
			(roundrect_rratio 0.25)
			(net 42 "/OCuLink/REFCLK.+")
			(pintype "passive")
		)
		(pad "5" smd roundrect
			(at -0.387 0.998 180)
			(size 0.25 0.55)
			(layers "F.Cu" "F.Mask" "F.Paste")
			(roundrect_rratio 0.25)
			(net 45 "/OCuLink/REFCLK.-")
			(pintype "passive")
		)
		(pad "6" smd roundrect
			(at 0.385 0.998 180)
			(size 0.25 0.55)
			(layers "F.Cu" "F.Mask" "F.Paste")
			(roundrect_rratio 0.25)
			(net 45 "/OCuLink/REFCLK.-")
			(pintype "passive")
		)
		(pad "7" smd roundrect
			(at 0.385 0.498 180)
			(size 0.25 0.55)
			(layers "F.Cu" "F.Mask" "F.Paste")
			(roundrect_rratio 0.25)
			(net 42 "/OCuLink/REFCLK.+")
			(pintype "passive")
		)
		(pad "8" smd roundrect
			(at 0.385 0 180)
			(size 0.4 0.55)
			(layers "F.Cu" "F.Mask" "F.Paste")
			(roundrect_rratio 0.25)
			(net 28 "GND")
			(pintype "passive")
		)
		(pad "9" smd roundrect
			(at 0.385 -0.5 180)
			(size 0.25 0.55)
			(layers "F.Cu" "F.Mask" "F.Paste")
			(roundrect_rratio 0.25)
			(net 320 "/OCuLink/~{CWAKE}_R")
			(pintype "passive")
		)
		(pad "10" smd roundrect
			(at 0.385 -1 180)
			(size 0.25 0.55)
			(layers "F.Cu" "F.Mask" "F.Paste")
			(roundrect_rratio 0.25)
			(net 118 "unconnected-(D6-Pad1)_1")
			(pintype "passive+no_connect")
		)
	)
	(footprint "antmicro-footprints:C_0402_1005Metric"
		(layer "F.Cu")
		(at 97 65.285 -90)
		(descr "Capacitor SMD 0402")
		(tags "capacitor SMD 0402")
		(property "Reference" "C196"
			(at 0.842273 -0.499995 270)
			(layer "F.SilkS")
			(effects
				(font
					(size 0.7 0.7)
					(thickness 0.15)
				)
				(justify right bottom)
			)
		)
		(property "Value" "C_220n_16V_0402"
			(at -1.022927 2.155213 270)
			(layer "F.Fab")
			(hide yes)
			(effects
				(font
					(size 0.7 0.7)
					(thickness 0.15)
				)
				(justify left bottom)
			)
		)
		(property "Datasheet" "https://www.murata.com/products/productdetail?partno=GRM155R71C224KA12%23"
			(at 0 0 270)
			(layer "F.Fab")
			(hide yes)
			(effects
				(font
					(size 1.27 1.27)
					(thickness 0.15)
				)
			)
		)
		(property "Description" "SMD Multilayer Ceramic Capacitor, 0.22 µF, 16 V, 0402 [1005 Metric], ± 10%, X7R, GRM Series"
			(at 0 0 270)
			(layer "F.Fab")
			(hide yes)
			(effects
				(font
					(size 1.27 1.27)
					(thickness 0.15)
				)
			)
		)
		(property "MPN" "GRM155R71C224KA12D"
			(at 0 0 270)
			(unlocked yes)
			(layer "F.Fab")
			(hide yes)
			(effects
				(font
					(size 1 1)
					(thickness 0.15)
				)
			)
		)
		(property "Manufacturer" "Murata"
			(at 0 0 270)
			(unlocked yes)
			(layer "F.Fab")
			(hide yes)
			(effects
				(font
					(size 1 1)
					(thickness 0.15)
				)
			)
		)
		(property "License" "Apache-2.0"
			(at 0 0 270)
			(unlocked yes)
			(layer "F.Fab")
			(hide yes)
			(effects
				(font
					(size 1 1)
					(thickness 0.15)
				)
			)
		)
		(property "Author" "Antmicro"
			(at 0 0 270)
			(unlocked yes)
			(layer "F.Fab")
			(hide yes)
			(effects
				(font
					(size 1 1)
					(thickness 0.15)
				)
			)
		)
		(property "Val" "220n"
			(at 0 0 270)
			(unlocked yes)
			(layer "F.Fab")
			(hide yes)
			(effects
				(font
					(size 1 1)
					(thickness 0.15)
				)
			)
		)
		(property "Voltage" "16V"
			(at 0 0 270)
			(unlocked yes)
			(layer "F.Fab")
			(hide yes)
			(effects
				(font
					(size 1 1)
					(thickness 0.15)
				)
			)
		)
		(property "Dielectric" "X7R"
			(at 0 0 270)
			(unlocked yes)
			(layer "F.Fab")
			(hide yes)
			(effects
				(font
					(size 1 1)
					(thickness 0.15)
				)
			)
		)
		(sheetname "/X710-AT2 PCIe/")
		(sheetfile "x710-at2-pcie.kicad_sch")
		(attr smd)
		(fp_rect
			(start -0.925 -0.47)
			(end 0.925 0.47)
			(stroke
				(width 0.05)
				(type default)
			)
			(fill no)
			(layer "F.CrtYd")
		)
		(fp_line
			(start -0.494 0.248)
			(end -0.494 -0.25)
			(stroke
				(width 0.15)
				(type solid)
			)
			(layer "F.Fab")
		)
		(fp_line
			(start 0.504 0.248)
			(end -0.494 0.248)
			(stroke
				(width 0.15)
				(type solid)
			)
			(layer "F.Fab")
		)
		(fp_line
			(start -0.494 -0.25)
			(end 0.504 -0.25)
			(stroke
				(width 0.15)
				(type solid)
			)
			(layer "F.Fab")
		)
		(fp_line
			(start 0.504 -0.25)
			(end 0.504 0.248)
			(stroke
				(width 0.15)
				(type solid)
			)
			(layer "F.Fab")
		)
		(pad "1" smd roundrect
			(at -0.48 0 270)
			(size 0.59 0.64)
			(layers "F.Cu" "F.Mask" "F.Paste")
			(roundrect_rratio 0.25)
			(net 25 "/OCuLink/PCIe_{x4}.TX3+")
			(pintype "passive")
		)
		(pad "2" smd roundrect
			(at 0.48 0 270)
			(size 0.59 0.64)
			(layers "F.Cu" "F.Mask" "F.Paste")
			(roundrect_rratio 0.25)
			(net 44 "/X710-AT2 PCIe/PCIe_{x4}_AC.TX3+")
			(pintype "passive")
		)
	)
	(footprint "antmicro-footprints:LED_0603_1608Metric_G"
		(layer "F.Cu")
		(at 54.35 118.05 180)
		(descr "LED SMD 0603 Green")
		(tags "LED SMD 0603 Green")
		(property "Reference" "D20"
			(at -1.1 -0.75 0)
			(layer "F.SilkS")
			(effects
				(font
					(size 0.7 0.7)
					(thickness 0.15)
				)
				(justify right top)
			)
		)
		(property "Value" "LED_G_0603_LG_L29K-G2J1-24-Z"
			(at -0.001 1.599 0)
			(layer "F.Fab")
			(hide yes)
			(effects
				(font
					(size 0.7 0.7)
					(thickness 0.15)
				)
				(justify right top)
			)
		)
		(property "Datasheet" "https://look.ams-osram.com/m/19ee86b3ae0ee95b/original/LG-L29K.pdf"
			(at 0 0 0)
			(layer "F.Fab")
			(hide yes)
			(effects
				(font
					(size 1.27 1.27)
					(thickness 0.15)
				)
			)
		)
		(property "Description" "LED, Green, SMD, 0603, 20 mA, 1.7 V, 570 nm"
			(at 0 0 0)
			(layer "F.Fab")
			(hide yes)
			(effects
				(font
					(size 1.27 1.27)
					(thickness 0.15)
				)
			)
		)
		(property "MPN" "LG L29K-G2J1-24-Z"
			(at 0 0 180)
			(unlocked yes)
			(layer "F.Fab")
			(hide yes)
			(effects
				(font
					(size 1 1)
					(thickness 0.15)
				)
			)
		)
		(property "Manufacturer" "OSRAM"
			(at 0 0 180)
			(unlocked yes)
			(layer "F.Fab")
			(hide yes)
			(effects
				(font
					(size 1 1)
					(thickness 0.15)
				)
			)
		)
		(property "Color" "Green"
			(at 0 0 180)
			(unlocked yes)
			(layer "F.Fab")
			(hide yes)
			(effects
				(font
					(size 1 1)
					(thickness 0.15)
				)
			)
		)
		(property "Author" "Antmicro"
			(at 0 0 180)
			(unlocked yes)
			(layer "F.Fab")
			(hide yes)
			(effects
				(font
					(size 1 1)
					(thickness 0.15)
				)
			)
		)
		(property "License" "Apache-2.0"
			(at 0 0 180)
			(unlocked yes)
			(layer "F.Fab")
			(hide yes)
			(effects
				(font
					(size 1 1)
					(thickness 0.15)
				)
			)
		)
		(sheetname "/Power/")
		(sheetfile "power.kicad_sch")
		(attr smd)
		(fp_line
			(start 0.22 0.35)
			(end -0.22 0.35)
			(stroke
				(width 0.15)
				(type solid)
			)
			(layer "F.SilkS")
		)
		(fp_line
			(start 0.22 -0.35)
			(end -0.22 -0.35)
			(stroke
				(width 0.15)
				(type solid)
			)
			(layer "F.SilkS")
		)
		(fp_line
			(start 0.105328 0.201008)
			(end 0.105328 -0.198992)
			(stroke
				(width 0.1)
				(type solid)
			)
			(layer "F.SilkS")
		)
		(fp_line
			(start 0.105328 0.201008)
			(end -0.094672 0.001008)
			(stroke
				(width 0.1)
				(type solid)
			)
			(layer "F.SilkS")
		)
		(fp_line
			(start 0.105328 0.001008)
			(end 0.24 0.001)
			(stroke
				(width 0.1)
				(type solid)
			)
			(layer "F.SilkS")
		)
		(fp_line
			(start -0.094672 0.201008)
			(end -0.094672 -0.198992)
			(stroke
				(width 0.1)
				(type solid)
			)
			(layer "F.SilkS")
		)
		(fp_line
			(start -0.094672 0.001008)
			(end 0.105328 -0.198992)
			(stroke
				(width 0.1)
				(type solid)
			)
			(layer "F.SilkS")
		)
		(fp_line
			(start -0.094672 0.001008)
			(end -0.24 0.001008)
			(stroke
				(width 0.1)
				(type solid)
			)
			(layer "F.SilkS")
		)
		(fp_line
			(start -1.18 -0.319)
			(end -1.18 0.321)
			(stroke
				(width 0.15)
				(type solid)
			)
			(layer "F.SilkS")
		)
		(fp_rect
			(start 1.25 0.65)
			(end -1.25 -0.65)
			(stroke
				(width 0.05)
				(type solid)
			)
			(fill no)
			(layer "F.CrtYd")
		)
		(fp_line
			(start 0.599 0)
			(end 0.201 0)
			(stroke
				(width 0.15)
				(type solid)
			)
			(layer "F.Fab")
		)
		(fp_line
			(start 0.201 0.2)
			(end 0.201 0)
			(stroke
				(width 0.15)
				(type solid)
			)
			(layer "F.Fab")
		)
		(fp_line
			(start 0.201 0)
			(end 0.201 -0.202)
			(stroke
				(width 0.15)
				(type solid)
			)
			(layer "F.Fab")
		)
		(fp_line
			(start 0.201 -0.202)
			(end -0.101 0)
			(stroke
				(width 0.15)
				(type solid)
			)
			(layer "F.Fab")
		)
		(fp_line
			(start -0.101 0)
			(end 0.201 0.2)
			(stroke
				(width 0.15)
				(type solid)
			)
			(layer "F.Fab")
		)
		(fp_line
			(start -0.199 0.2)
			(end -0.199 0.1)
			(stroke
				(width 0.15)
				(type solid)
			)
			(layer "F.Fab")
		)
		(fp_line
			(start -0.199 0)
			(end -0.597 0)
			(stroke
				(width 0.15)
				(type solid)
			)
			(layer "F.Fab")
		)
		(fp_line
			(start -0.199 -0.202)
			(end -0.199 0.1)
			(stroke
				(width 0.15)
				(type solid)
			)
			(layer "F.Fab")
		)
		(fp_rect
			(start 0.848 0.4)
			(end -0.85 -0.402)
			(stroke
				(width 0.15)
				(type solid)
			)
			(fill no)
			(layer "F.Fab")
		)
		(fp_text user "Author: Antmicro"
			(at -1.4224 4.799 180)
			(layer "F.Fab")
			(effects
				(font
					(size 0.7 0.7)
					(thickness 0.15)
				)
				(justify left bottom)
			)
		)
		(fp_text user "${REFERENCE}"
			(at -1.4224 5.999 180)
			(layer "F.Fab")
			(effects
				(font
					(size 0.7 0.7)
					(thickness 0.15)
				)
				(justify left bottom)
			)
		)
		(fp_text user "License: Apache-2.0"
			(at -1.4224 3.599 180)
			(layer "F.Fab")
			(effects
				(font
					(size 0.7 0.7)
					(thickness 0.15)
				)
				(justify left bottom)
			)
		)
		(pad "1" smd roundrect
			(at -0.7 0)
			(size 0.8 1)
			(layers "F.Cu" "F.Mask" "F.Paste")
			(roundrect_rratio 0.2)
			(net 414 "Net-(D20-C)")
			(pinfunction "C")
			(pintype "passive")
		)
		(pad "2" smd roundrect
			(at 0.7 0)
			(size 0.8 1)
			(layers "F.Cu" "F.Mask" "F.Paste")
			(roundrect_rratio 0.2)
			(net 255 "/Power/+3V3_OUT")
			(pinfunction "A")
			(pintype "passive")
		)
	)
	(footprint "antmicro-footprints:C_0603_1608Metric"
		(layer "F.Cu")
		(at 72.9 114.3 90)
		(descr "Capacitor SMD 0603")
		(tags "capacitor 0603")
		(property "Reference" "C174"
			(at -2.35 3.74 90)
			(layer "F.SilkS")
			(effects
				(font
					(size 0.7 0.7)
					(thickness 0.15)
				)
				(justify left bottom)
			)
		)
		(property "Value" "C_10u_10V_X7R_0603"
			(at -1.42757 1.770288 90)
			(layer "F.Fab")
			(hide yes)
			(effects
				(font
					(size 0.7 0.7)
					(thickness 0.15)
				)
				(justify left bottom)
			)
		)
		(property "Datasheet" "https://www.murata.com/products/productdetail?partno=GRM188Z71A106KA73%23"
			(at 0 0 90)
			(layer "F.Fab")
			(hide yes)
			(effects
				(font
					(size 1.27 1.27)
					(thickness 0.15)
				)
			)
		)
		(property "Description" "SMD Multilayer Ceramic Capacitor,  10µF, 10V, 0603, ±10%, X7R"
			(at 0 0 90)
			(layer "F.Fab")
			(hide yes)
			(effects
				(font
					(size 1.27 1.27)
					(thickness 0.15)
				)
			)
		)
		(property "MPN" "GRM188Z71A106KA73D"
			(at 0 0 90)
			(unlocked yes)
			(layer "F.Fab")
			(hide yes)
			(effects
				(font
					(size 1 1)
					(thickness 0.15)
				)
			)
		)
		(property "Val" "10u"
			(at 0 0 90)
			(unlocked yes)
			(layer "F.Fab")
			(hide yes)
			(effects
				(font
					(size 1 1)
					(thickness 0.15)
				)
			)
		)
		(property "Voltage" "10V"
			(at 0 0 90)
			(unlocked yes)
			(layer "F.Fab")
			(hide yes)
			(effects
				(font
					(size 1 1)
					(thickness 0.15)
				)
			)
		)
		(property "Dielectric" "X7R"
			(at 0 0 90)
			(unlocked yes)
			(layer "F.Fab")
			(hide yes)
			(effects
				(font
					(size 1 1)
					(thickness 0.15)
				)
			)
		)
		(property "Manufacturer" "Murata"
			(at 0 0 90)
			(unlocked yes)
			(layer "F.Fab")
			(hide yes)
			(effects
				(font
					(size 1 1)
					(thickness 0.15)
				)
			)
		)
		(property "License" "Apache-2.0"
			(at 0 0 90)
			(unlocked yes)
			(layer "F.Fab")
			(hide yes)
			(effects
				(font
					(size 1 1)
					(thickness 0.15)
				)
			)
		)
		(property "Author" "Antmicro"
			(at 0 0 90)
			(unlocked yes)
			(layer "F.Fab")
			(hide yes)
			(effects
				(font
					(size 1 1)
					(thickness 0.15)
				)
			)
		)
		(sheetname "/X710-AT2 power/")
		(sheetfile "x710-at2-power.kicad_sch")
		(attr smd)
		(fp_line
			(start -0.15 -0.4)
			(end 0.15 -0.4)
			(stroke
				(width 0.15)
				(type solid)
			)
			(layer "F.SilkS")
		)
		(fp_line
			(start -0.15 0.4)
			(end 0.15 0.4)
			(stroke
				(width 0.15)
				(type solid)
			)
			(layer "F.SilkS")
		)
		(fp_rect
			(start -1.25 -0.65)
			(end 1.25 0.65)
			(stroke
				(width 0.05)
				(type solid)
			)
			(fill no)
			(layer "F.CrtYd")
		)
		(fp_rect
			(start -0.8 -0.4)
			(end 0.8 0.4)
			(stroke
				(width 0.15)
				(type solid)
			)
			(fill no)
			(layer "F.Fab")
		)
		(pad "1" smd roundrect
			(at -0.7 0 90)
			(size 0.8 1)
			(layers "F.Cu" "F.Mask" "F.Paste")
			(roundrect_rratio 0.2)
			(net 28 "GND")
			(pintype "passive")
		)
		(pad "2" smd roundrect
			(at 0.7 0 90)
			(size 0.8 1)
			(layers "F.Cu" "F.Mask" "F.Paste")
			(roundrect_rratio 0.2)
			(net 14 "P1_AVDDL")
			(pintype "passive")
		)
	)
	(footprint "antmicro-footprints:R_0402_1005Metric"
		(layer "F.Cu")
		(at 86.1 112.45 -90)
		(descr "Resistor SMD 0402")
		(tags "resistor SMD 0402")
		(property "Reference" "R72"
			(at -1.05 0.5 90)
			(layer "F.SilkS")
			(effects
				(font
					(size 0.7 0.7)
					(thickness 0.15)
				)
				(justify right bottom)
			)
		)
		(property "Value" "R_1k_0402"
			(at -1.011843 1.772046 90)
			(layer "F.Fab")
			(hide yes)
			(effects
				(font
					(size 0.7 0.7)
					(thickness 0.15)
				)
				(justify right top)
			)
		)
		(property "Datasheet" "https://www.bourns.com/docs/product-datasheets/cr.pdf"
			(at 0 0 90)
			(layer "F.Fab")
			(hide yes)
			(effects
				(font
					(size 1.27 1.27)
					(thickness 0.15)
				)
			)
		)
		(property "Description" "SMD Chip Resistor, 1 kohm, ± 1%, 63 mW, 0402 [1005 Metric], Thick Film, General Purpose"
			(at 0 0 90)
			(layer "F.Fab")
			(hide yes)
			(effects
				(font
					(size 1.27 1.27)
					(thickness 0.15)
				)
			)
		)
		(property "MPN" "CR0402-FX-1001GLF"
			(at 0 0 270)
			(unlocked yes)
			(layer "F.Fab")
			(hide yes)
			(effects
				(font
					(size 1 1)
					(thickness 0.15)
				)
			)
		)
		(property "Manufacturer" "Bourns"
			(at 0 0 270)
			(unlocked yes)
			(layer "F.Fab")
			(hide yes)
			(effects
				(font
					(size 1 1)
					(thickness 0.15)
				)
			)
		)
		(property "License" "Apache-2.0"
			(at 0 0 270)
			(unlocked yes)
			(layer "F.Fab")
			(hide yes)
			(effects
				(font
					(size 1 1)
					(thickness 0.15)
				)
			)
		)
		(property "Author" "Antmicro"
			(at 0 0 270)
			(unlocked yes)
			(layer "F.Fab")
			(hide yes)
			(effects
				(font
					(size 1 1)
					(thickness 0.15)
				)
			)
		)
		(property "Val" "1k"
			(at 0 0 270)
			(unlocked yes)
			(layer "F.Fab")
			(hide yes)
			(effects
				(font
					(size 1 1)
					(thickness 0.15)
				)
			)
		)
		(property "Tolerance" "1%"
			(at 0 0 270)
			(unlocked yes)
			(layer "F.Fab")
			(hide yes)
			(effects
				(font
					(size 1 1)
					(thickness 0.15)
				)
			)
		)
		(sheetname "/X710-AT2 10GbE/")
		(sheetfile "x710-at2-10gbe.kicad_sch")
		(attr smd exclude_from_pos_files exclude_from_bom dnp)
		(fp_rect
			(start -0.925 -0.47)
			(end 0.925 0.47)
			(stroke
				(width 0.05)
				(type default)
			)
			(fill no)
			(layer "F.CrtYd")
		)
		(fp_rect
			(start -0.5 -0.25)
			(end 0.5 0.25)
			(stroke
				(width 0.15)
				(type solid)
			)
			(fill no)
			(layer "F.Fab")
		)
		(pad "1" smd roundrect
			(at -0.48 0 270)
			(size 0.59 0.64)
			(layers "F.Cu" "F.Mask" "F.Paste")
			(roundrect_rratio 0.25)
			(net 293 "/X710-AT2 10GbE/TPIN_3")
			(pintype "passive")
		)
		(pad "2" smd roundrect
			(at 0.48 0 270)
			(size 0.59 0.64)
			(layers "F.Cu" "F.Mask" "F.Paste")
			(roundrect_rratio 0.25)
			(net 18 "+1V88")
			(pintype "passive")
		)
	)
	(footprint "antmicro-footprints:MP_Pad6mm_Drill3.2mm"
		(layer "F.Cu")
		(at 106.975 121.995)
		(property "Reference" "MP8"
			(at 0 -3.2 0)
			(layer "F.SilkS")
			(hide yes)
			(effects
				(font
					(size 0.7 0.7)
					(thickness 0.15)
				)
				(justify left bottom)
			)
		)
		(property "Value" "MP_Pad6mm_Drill3.2mm"
			(at 0 3.9 0)
			(layer "F.Fab")
			(hide yes)
			(effects
				(font
					(size 0.7 0.7)
					(thickness 0.15)
				)
				(justify left bottom)
			)
		)
		(property "Description" "Mechanical part"
			(at 0 0 0)
			(layer "F.Fab")
			(hide yes)
			(effects
				(font
					(size 1.27 1.27)
					(thickness 0.15)
				)
			)
		)
		(property "Author" "Antmicro"
			(at 0 0 0)
			(unlocked yes)
			(layer "F.Fab")
			(hide yes)
			(effects
				(font
					(size 1 1)
					(thickness 0.15)
				)
			)
		)
		(property "License" "Apache-2.0"
			(at 0 0 0)
			(unlocked yes)
			(layer "F.Fab")
			(hide yes)
			(effects
				(font
					(size 1 1)
					(thickness 0.15)
				)
			)
		)
		(sheetname "/")
		(sheetfile "oculink-to-10gbe-adapter.kicad_sch")
		(attr exclude_from_pos_files exclude_from_bom)
		(fp_circle
			(center 0 0)
			(end 3.25 0)
			(stroke
				(width 0.05)
				(type default)
			)
			(fill no)
			(layer "F.CrtYd")
		)
		(fp_text user "Author: Antmicro"
			(at -0.178 7.225 0)
			(layer "F.Fab")
			(effects
				(font
					(size 0.7 0.7)
					(thickness 0.15)
				)
				(justify left bottom)
			)
		)
		(fp_text user "License: Apache-2.0"
			(at -0.178 8.425 0)
			(layer "F.Fab")
			(effects
				(font
					(size 0.7 0.7)
					(thickness 0.15)
				)
				(justify left bottom)
			)
		)
		(fp_text user "${REFERENCE}"
			(at -0.178 6.025 0)
			(layer "F.Fab")
			(effects
				(font
					(size 0.7 0.7)
					(thickness 0.15)
				)
				(justify left bottom)
			)
		)
		(pad "1" thru_hole circle
			(at 0 0)
			(size 6 6)
			(drill 3.2)
			(layers "*.Cu" "*.Mask")
			(remove_unused_layers no)
			(net 28 "GND")
			(pintype "passive")
		)
	)
	(footprint "antmicro-footprints:C_0603_1608Metric"
		(layer "F.Cu")
		(at 71.1 98.3 90)
		(descr "Capacitor SMD 0603")
		(tags "capacitor 0603")
		(property "Reference" "C139"
			(at 1.04 0.73 90)
			(layer "F.SilkS")
			(effects
				(font
					(size 0.7 0.7)
					(thickness 0.15)
				)
				(justify left bottom)
			)
		)
		(property "Value" "C_10u_10V_X7R_0603"
			(at -1.42757 1.770288 90)
			(layer "F.Fab")
			(hide yes)
			(effects
				(font
					(size 0.7 0.7)
					(thickness 0.15)
				)
				(justify left bottom)
			)
		)
		(property "Datasheet" "https://www.murata.com/products/productdetail?partno=GRM188Z71A106KA73%23"
			(at 0 0 90)
			(layer "F.Fab")
			(hide yes)
			(effects
				(font
					(size 1.27 1.27)
					(thickness 0.15)
				)
			)
		)
		(property "Description" "SMD Multilayer Ceramic Capacitor,  10µF, 10V, 0603, ±10%, X7R"
			(at 0 0 90)
			(layer "F.Fab")
			(hide yes)
			(effects
				(font
					(size 1.27 1.27)
					(thickness 0.15)
				)
			)
		)
		(property "MPN" "GRM188Z71A106KA73D"
			(at 0 0 90)
			(unlocked yes)
			(layer "F.Fab")
			(hide yes)
			(effects
				(font
					(size 1 1)
					(thickness 0.15)
				)
			)
		)
		(property "Val" "10u"
			(at 0 0 90)
			(unlocked yes)
			(layer "F.Fab")
			(hide yes)
			(effects
				(font
					(size 1 1)
					(thickness 0.15)
				)
			)
		)
		(property "Voltage" "10V"
			(at 0 0 90)
			(unlocked yes)
			(layer "F.Fab")
			(hide yes)
			(effects
				(font
					(size 1 1)
					(thickness 0.15)
				)
			)
		)
		(property "Dielectric" "X7R"
			(at 0 0 90)
			(unlocked yes)
			(layer "F.Fab")
			(hide yes)
			(effects
				(font
					(size 1 1)
					(thickness 0.15)
				)
			)
		)
		(property "Manufacturer" "Murata"
			(at 0 0 90)
			(unlocked yes)
			(layer "F.Fab")
			(hide yes)
			(effects
				(font
					(size 1 1)
					(thickness 0.15)
				)
			)
		)
		(property "License" "Apache-2.0"
			(at 0 0 90)
			(unlocked yes)
			(layer "F.Fab")
			(hide yes)
			(effects
				(font
					(size 1 1)
					(thickness 0.15)
				)
			)
		)
		(property "Author" "Antmicro"
			(at 0 0 90)
			(unlocked yes)
			(layer "F.Fab")
			(hide yes)
			(effects
				(font
					(size 1 1)
					(thickness 0.15)
				)
			)
		)
		(sheetname "/X710-AT2 power/")
		(sheetfile "x710-at2-power.kicad_sch")
		(attr smd)
		(fp_line
			(start -0.15 -0.4)
			(end 0.15 -0.4)
			(stroke
				(width 0.15)
				(type solid)
			)
			(layer "F.SilkS")
		)
		(fp_line
			(start -0.15 0.4)
			(end 0.15 0.4)
			(stroke
				(width 0.15)
				(type solid)
			)
			(layer "F.SilkS")
		)
		(fp_rect
			(start -1.25 -0.65)
			(end 1.25 0.65)
			(stroke
				(width 0.05)
				(type solid)
			)
			(fill no)
			(layer "F.CrtYd")
		)
		(fp_rect
			(start -0.8 -0.4)
			(end 0.8 0.4)
			(stroke
				(width 0.15)
				(type solid)
			)
			(fill no)
			(layer "F.Fab")
		)
		(pad "1" smd roundrect
			(at -0.7 0 90)
			(size 0.8 1)
			(layers "F.Cu" "F.Mask" "F.Paste")
			(roundrect_rratio 0.2)
			(net 28 "GND")
			(pintype "passive")
		)
		(pad "2" smd roundrect
			(at 0.7 0 90)
			(size 0.8 1)
			(layers "F.Cu" "F.Mask" "F.Paste")
			(roundrect_rratio 0.2)
			(net 10 "AVDDH")
			(pintype "passive")
		)
	)
	(footprint "antmicro-footprints:R_0402_1005Metric"
		(layer "F.Cu")
		(at 73.85 80.039996)
		(descr "Resistor SMD 0402")
		(tags "resistor SMD 0402")
		(property "Reference" "R3"
			(at -3.86 -8.469996 0)
			(layer "F.SilkS")
			(effects
				(font
					(size 0.7 0.7)
					(thickness 0.15)
				)
				(justify left bottom)
			)
		)
		(property "Value" "R_90k9_0402"
			(at -1.011843 1.772046 0)
			(layer "F.Fab")
			(hide yes)
			(effects
				(font
					(size 0.7 0.7)
					(thickness 0.15)
				)
				(justify left bottom)
			)
		)
		(property "Datasheet" "https://www.bourns.com/docs/product-datasheets/cr.pdf"
			(at 0 0 0)
			(layer "F.Fab")
			(hide yes)
			(effects
				(font
					(size 1.27 1.27)
					(thickness 0.15)
				)
			)
		)
		(property "Description" "SMD Chip Resistor"
			(at 0 0 0)
			(layer "F.Fab")
			(hide yes)
			(effects
				(font
					(size 1.27 1.27)
					(thickness 0.15)
				)
			)
		)
		(property "MPN" "CR0402-FX-9092GLF"
			(at 0 0 0)
			(unlocked yes)
			(layer "F.Fab")
			(hide yes)
			(effects
				(font
					(size 1 1)
					(thickness 0.15)
				)
			)
		)
		(property "Manufacturer" "Bourns"
			(at 0 0 0)
			(unlocked yes)
			(layer "F.Fab")
			(hide yes)
			(effects
				(font
					(size 1 1)
					(thickness 0.15)
				)
			)
		)
		(property "License" "Apache-2.0"
			(at 0 0 0)
			(unlocked yes)
			(layer "F.Fab")
			(hide yes)
			(effects
				(font
					(size 1 1)
					(thickness 0.15)
				)
			)
		)
		(property "Author" "Antmicro"
			(at 0 0 0)
			(unlocked yes)
			(layer "F.Fab")
			(hide yes)
			(effects
				(font
					(size 1 1)
					(thickness 0.15)
				)
			)
		)
		(property "Val" "90k9"
			(at 0 0 0)
			(unlocked yes)
			(layer "F.Fab")
			(hide yes)
			(effects
				(font
					(size 1 1)
					(thickness 0.15)
				)
			)
		)
		(property "Tolerance" "1%"
			(at 0 0 0)
			(unlocked yes)
			(layer "F.Fab")
			(hide yes)
			(effects
				(font
					(size 1 1)
					(thickness 0.15)
				)
			)
		)
		(sheetname "/Power/")
		(sheetfile "power.kicad_sch")
		(attr smd)
		(fp_rect
			(start -0.925 -0.47)
			(end 0.925 0.47)
			(stroke
				(width 0.05)
				(type default)
			)
			(fill no)
			(layer "F.CrtYd")
		)
		(fp_rect
			(start -0.5 -0.25)
			(end 0.5 0.25)
			(stroke
				(width 0.15)
				(type solid)
			)
			(fill no)
			(layer "F.Fab")
		)
		(pad "1" smd roundrect
			(at -0.48 0)
			(size 0.59 0.64)
			(layers "F.Cu" "F.Mask" "F.Paste")
			(roundrect_rratio 0.25)
			(net 317 "/Power/3V3_FB")
			(pintype "passive")
		)
		(pad "2" smd roundrect
			(at 0.48 0)
			(size 0.59 0.64)
			(layers "F.Cu" "F.Mask" "F.Paste")
			(roundrect_rratio 0.25)
			(net 255 "/Power/+3V3_OUT")
			(pintype "passive")
		)
	)
	(footprint "antmicro-footprints:C_0402_1005Metric"
		(layer "F.Cu")
		(at 67.27 110.35 180)
		(descr "Capacitor SMD 0402")
		(tags "capacitor SMD 0402")
		(property "Reference" "C162"
			(at 0.69 0.31 0)
			(layer "F.SilkS")
			(effects
				(font
					(size 0.7 0.7)
					(thickness 0.15)
				)
				(justify right top)
			)
		)
		(property "Value" "C_100n_0402"
			(at -1.022927 2.155213 0)
			(layer "F.Fab")
			(hide yes)
			(effects
				(font
					(size 0.7 0.7)
					(thickness 0.15)
				)
				(justify right top)
			)
		)
		(property "Datasheet" "https://www.murata.com/products/productdetail?partno=GRM155R61H104KE14%23"
			(at 0 0 0)
			(layer "F.Fab")
			(hide yes)
			(effects
				(font
					(size 1.27 1.27)
					(thickness 0.15)
				)
			)
		)
		(property "Description" "SMD Multilayer Ceramic Capacitor, 0.1 µF, 50 V, 0402 [1005 Metric], ± 10%, X5R, GRM Series"
			(at 0 0 0)
			(layer "F.Fab")
			(hide yes)
			(effects
				(font
					(size 1.27 1.27)
					(thickness 0.15)
				)
			)
		)
		(property "MPN" "GRM155R61H104KE14D"
			(at 0 0 180)
			(unlocked yes)
			(layer "F.Fab")
			(hide yes)
			(effects
				(font
					(size 1 1)
					(thickness 0.15)
				)
			)
		)
		(property "Val" "100n"
			(at 0 0 180)
			(unlocked yes)
			(layer "F.Fab")
			(hide yes)
			(effects
				(font
					(size 1 1)
					(thickness 0.15)
				)
			)
		)
		(property "Voltage" "50V"
			(at 0 0 180)
			(unlocked yes)
			(layer "F.Fab")
			(hide yes)
			(effects
				(font
					(size 1 1)
					(thickness 0.15)
				)
			)
		)
		(property "Dielectric" "X5R"
			(at 0 0 180)
			(unlocked yes)
			(layer "F.Fab")
			(hide yes)
			(effects
				(font
					(size 1 1)
					(thickness 0.15)
				)
			)
		)
		(property "Manufacturer" "Murata"
			(at 0 0 180)
			(unlocked yes)
			(layer "F.Fab")
			(hide yes)
			(effects
				(font
					(size 1 1)
					(thickness 0.15)
				)
			)
		)
		(property "License" "Apache-2.0"
			(at 0 0 180)
			(unlocked yes)
			(layer "F.Fab")
			(hide yes)
			(effects
				(font
					(size 1 1)
					(thickness 0.15)
				)
			)
		)
		(property "Author" "Antmicro"
			(at 0 0 180)
			(unlocked yes)
			(layer "F.Fab")
			(hide yes)
			(effects
				(font
					(size 1 1)
					(thickness 0.15)
				)
			)
		)
		(sheetname "/X710-AT2 power/")
		(sheetfile "x710-at2-power.kicad_sch")
		(attr smd)
		(fp_rect
			(start -0.925 -0.47)
			(end 0.925 0.47)
			(stroke
				(width 0.05)
				(type default)
			)
			(fill no)
			(layer "F.CrtYd")
		)
		(fp_line
			(start 0.504 0.248)
			(end -0.494 0.248)
			(stroke
				(width 0.15)
				(type solid)
			)
			(layer "F.Fab")
		)
		(fp_line
			(start 0.504 -0.25)
			(end 0.504 0.248)
			(stroke
				(width 0.15)
				(type solid)
			)
			(layer "F.Fab")
		)
		(fp_line
			(start -0.494 0.248)
			(end -0.494 -0.25)
			(stroke
				(width 0.15)
				(type solid)
			)
			(layer "F.Fab")
		)
		(fp_line
			(start -0.494 -0.25)
			(end 0.504 -0.25)
			(stroke
				(width 0.15)
				(type solid)
			)
			(layer "F.Fab")
		)
		(pad "1" smd roundrect
			(at -0.48 0 180)
			(size 0.59 0.64)
			(layers "F.Cu" "F.Mask" "F.Paste")
			(roundrect_rratio 0.25)
			(net 28 "GND")
			(pintype "passive")
		)
		(pad "2" smd roundrect
			(at 0.48 0 180)
			(size 0.59 0.64)
			(layers "F.Cu" "F.Mask" "F.Paste")
			(roundrect_rratio 0.25)
			(net 302 "+1V0")
			(pintype "passive")
		)
	)
	(footprint "antmicro-footprints:MP_Pad6mm_Drill3.2mm"
		(layer "F.Cu")
		(at 62.975 121.995)
		(property "Reference" "MP7"
			(at 0 -3.2 0)
			(layer "F.SilkS")
			(hide yes)
			(effects
				(font
					(size 0.7 0.7)
					(thickness 0.15)
				)
				(justify left bottom)
			)
		)
		(property "Value" "MP_Pad6mm_Drill3.2mm"
			(at 0 3.9 0)
			(layer "F.Fab")
			(hide yes)
			(effects
				(font
					(size 0.7 0.7)
					(thickness 0.15)
				)
				(justify left bottom)
			)
		)
		(property "Description" "Mechanical part"
			(at 0 0 0)
			(layer "F.Fab")
			(hide yes)
			(effects
				(font
					(size 1.27 1.27)
					(thickness 0.15)
				)
			)
		)
		(property "Author" "Antmicro"
			(at 0 0 0)
			(unlocked yes)
			(layer "F.Fab")
			(hide yes)
			(effects
				(font
					(size 1 1)
					(thickness 0.15)
				)
			)
		)
		(property "License" "Apache-2.0"
			(at 0 0 0)
			(unlocked yes)
			(layer "F.Fab")
			(hide yes)
			(effects
				(font
					(size 1 1)
					(thickness 0.15)
				)
			)
		)
		(sheetname "/")
		(sheetfile "oculink-to-10gbe-adapter.kicad_sch")
		(attr exclude_from_pos_files exclude_from_bom)
		(fp_circle
			(center 0 0)
			(end 3.25 0)
			(stroke
				(width 0.05)
				(type default)
			)
			(fill no)
			(layer "F.CrtYd")
		)
		(fp_text user "License: Apache-2.0"
			(at -0.178 8.425 0)
			(layer "F.Fab")
			(effects
				(font
					(size 0.7 0.7)
					(thickness 0.15)
				)
				(justify left bottom)
			)
		)
		(fp_text user "${REFERENCE}"
			(at -0.178 6.025 0)
			(layer "F.Fab")
			(effects
				(font
					(size 0.7 0.7)
					(thickness 0.15)
				)
				(justify left bottom)
			)
		)
		(fp_text user "Author: Antmicro"
			(at -0.178 7.225 0)
			(layer "F.Fab")
			(effects
				(font
					(size 0.7 0.7)
					(thickness 0.15)
				)
				(justify left bottom)
			)
		)
		(pad "1" thru_hole circle
			(at 0 0)
			(size 6 6)
			(drill 3.2)
			(layers "*.Cu" "*.Mask")
			(remove_unused_layers no)
			(net 28 "GND")
			(pintype "passive")
		)
	)
	(footprint "antmicro-footprints:R_0402_1005Metric"
		(layer "F.Cu")
		(at 57.15 118.05 180)
		(descr "Resistor SMD 0402")
		(tags "resistor SMD 0402")
		(property "Reference" "R148"
			(at -1.45 -0.772697 0)
			(layer "F.SilkS")
			(effects
				(font
					(size 0.7 0.7)
					(thickness 0.15)
				)
				(justify right top)
			)
		)
		(property "Value" "R_1k_0402"
			(at -1.011843 1.772046 0)
			(layer "F.Fab")
			(hide yes)
			(effects
				(font
					(size 0.7 0.7)
					(thickness 0.15)
				)
				(justify right top)
			)
		)
		(property "Datasheet" "https://www.bourns.com/docs/product-datasheets/cr.pdf"
			(at 0 0 0)
			(layer "F.Fab")
			(hide yes)
			(effects
				(font
					(size 1.27 1.27)
					(thickness 0.15)
				)
			)
		)
		(property "Description" "SMD Chip Resistor, 1 kohm, ± 1%, 63 mW, 0402 [1005 Metric], Thick Film, General Purpose"
			(at 0 0 0)
			(layer "F.Fab")
			(hide yes)
			(effects
				(font
					(size 1.27 1.27)
					(thickness 0.15)
				)
			)
		)
		(property "MPN" "CR0402-FX-1001GLF"
			(at 0 0 180)
			(unlocked yes)
			(layer "F.Fab")
			(hide yes)
			(effects
				(font
					(size 1 1)
					(thickness 0.15)
				)
			)
		)
		(property "Manufacturer" "Bourns"
			(at 0 0 180)
			(unlocked yes)
			(layer "F.Fab")
			(hide yes)
			(effects
				(font
					(size 1 1)
					(thickness 0.15)
				)
			)
		)
		(property "License" "Apache-2.0"
			(at 0 0 180)
			(unlocked yes)
			(layer "F.Fab")
			(hide yes)
			(effects
				(font
					(size 1 1)
					(thickness 0.15)
				)
			)
		)
		(property "Author" "Antmicro"
			(at 0 0 180)
			(unlocked yes)
			(layer "F.Fab")
			(hide yes)
			(effects
				(font
					(size 1 1)
					(thickness 0.15)
				)
			)
		)
		(property "Val" "1k"
			(at 0 0 180)
			(unlocked yes)
			(layer "F.Fab")
			(hide yes)
			(effects
				(font
					(size 1 1)
					(thickness 0.15)
				)
			)
		)
		(property "Tolerance" "1%"
			(at 0 0 180)
			(unlocked yes)
			(layer "F.Fab")
			(hide yes)
			(effects
				(font
					(size 1 1)
					(thickness 0.15)
				)
			)
		)
		(sheetname "/Power/")
		(sheetfile "power.kicad_sch")
		(attr smd)
		(fp_poly
			(pts
				(xy -0.925 -0.47) (xy 0.925 -0.47) (xy 0.925 0.47) (xy -0.925 0.47)
			)
			(stroke
				(width 0.05)
				(type default)
			)
			(fill no)
			(layer "F.CrtYd")
		)
		(fp_poly
			(pts
				(xy -0.5 -0.25) (xy 0.5 -0.25) (xy 0.5 0.25) (xy -0.5 0.25)
			)
			(stroke
				(width 0.15)
				(type solid)
			)
			(fill no)
			(layer "F.Fab")
		)
		(pad "1" smd roundrect
			(at -0.48 0 180)
			(size 0.59 0.64)
			(layers "F.Cu" "F.Mask" "F.Paste")
			(roundrect_rratio 0.25)
			(net 419 "Net-(Q9-C)")
			(pintype "passive")
		)
		(pad "2" smd roundrect
			(at 0.48 0 180)
			(size 0.59 0.64)
			(layers "F.Cu" "F.Mask" "F.Paste")
			(roundrect_rratio 0.25)
			(net 414 "Net-(D20-C)")
			(pintype "passive")
		)
	)
	(footprint "antmicro-footprints:R_0402_1005Metric"
		(layer "F.Cu")
		(at 79.96 58.9)
		(descr "Resistor SMD 0402")
		(tags "resistor SMD 0402")
		(property "Reference" "R20"
			(at 1.09 1.55 0)
			(layer "F.SilkS")
			(effects
				(font
					(size 0.7 0.7)
					(thickness 0.15)
				)
				(justify right top)
			)
		)
		(property "Value" "R_1k_0402"
			(at -1.011843 1.772046 0)
			(layer "F.Fab")
			(hide yes)
			(effects
				(font
					(size 0.7 0.7)
					(thickness 0.15)
				)
				(justify left bottom)
			)
		)
		(property "Datasheet" "https://www.bourns.com/docs/product-datasheets/cr.pdf"
			(at 0 0 0)
			(layer "F.Fab")
			(hide yes)
			(effects
				(font
					(size 1.27 1.27)
					(thickness 0.15)
				)
			)
		)
		(property "Description" "SMD Chip Resistor, 1 kohm, ± 1%, 63 mW, 0402 [1005 Metric], Thick Film, General Purpose"
			(at 0 0 0)
			(layer "F.Fab")
			(hide yes)
			(effects
				(font
					(size 1.27 1.27)
					(thickness 0.15)
				)
			)
		)
		(property "MPN" "CR0402-FX-1001GLF"
			(at 0 0 0)
			(unlocked yes)
			(layer "F.Fab")
			(hide yes)
			(effects
				(font
					(size 1 1)
					(thickness 0.15)
				)
			)
		)
		(property "Manufacturer" "Bourns"
			(at 0 0 0)
			(unlocked yes)
			(layer "F.Fab")
			(hide yes)
			(effects
				(font
					(size 1 1)
					(thickness 0.15)
				)
			)
		)
		(property "License" "Apache-2.0"
			(at 0 0 0)
			(unlocked yes)
			(layer "F.Fab")
			(hide yes)
			(effects
				(font
					(size 1 1)
					(thickness 0.15)
				)
			)
		)
		(property "Author" "Antmicro"
			(at 0 0 0)
			(unlocked yes)
			(layer "F.Fab")
			(hide yes)
			(effects
				(font
					(size 1 1)
					(thickness 0.15)
				)
			)
		)
		(property "Val" "1k"
			(at 0 0 0)
			(unlocked yes)
			(layer "F.Fab")
			(hide yes)
			(effects
				(font
					(size 1 1)
					(thickness 0.15)
				)
			)
		)
		(property "Tolerance" "1%"
			(at 0 0 0)
			(unlocked yes)
			(layer "F.Fab")
			(hide yes)
			(effects
				(font
					(size 1 1)
					(thickness 0.15)
				)
			)
		)
		(sheetname "/Power/")
		(sheetfile "power.kicad_sch")
		(attr smd)
		(fp_rect
			(start -0.925 -0.47)
			(end 0.925 0.47)
			(stroke
				(width 0.05)
				(type default)
			)
			(fill no)
			(layer "F.CrtYd")
		)
		(fp_rect
			(start -0.5 -0.25)
			(end 0.5 0.25)
			(stroke
				(width 0.15)
				(type solid)
			)
			(fill no)
			(layer "F.Fab")
		)
		(pad "1" smd roundrect
			(at -0.48 0)
			(size 0.59 0.64)
			(layers "F.Cu" "F.Mask" "F.Paste")
			(roundrect_rratio 0.25)
			(net 75 "Net-(D3-A)")
			(pintype "passive")
		)
		(pad "2" smd roundrect
			(at 0.48 0)
			(size 0.59 0.64)
			(layers "F.Cu" "F.Mask" "F.Paste")
			(roundrect_rratio 0.25)
			(net 351 "/Power/+5V_USB")
			(pintype "passive")
		)
	)
	(footprint "antmicro-footprints:RJ45_JTH-0024NL"
		(layer "F.Cu")
		(at 101.05 132.39 180)
		(property "Reference" "J6"
			(at -2.455 4.45 0)
			(unlocked yes)
			(layer "F.SilkS")
			(effects
				(font
					(size 0.7 0.7)
					(thickness 0.15)
				)
				(justify left bottom)
			)
		)
		(property "Value" "Bus_RJ45_JTH-0024NL"
			(at 5.06 1 180)
			(unlocked yes)
			(layer "F.Fab")
			(hide yes)
			(effects
				(font
					(size 0.7 0.7)
					(thickness 0.15)
				)
				(justify left bottom)
			)
		)
		(property "Datasheet" "https://www.mouser.com/datasheet/2/447/JTH_0024NL-3072047.pdf"
			(at 0 0 0)
			(layer "F.Fab")
			(hide yes)
			(effects
				(font
					(size 1.27 1.27)
					(thickness 0.15)
				)
			)
		)
		(property "Description" "Modular Connectors / Ethernet Connectors 1X1 TAB DOWN W/LED'S ETHERNET (NON PoE)"
			(at 0 0 0)
			(layer "F.Fab")
			(hide yes)
			(effects
				(font
					(size 1.27 1.27)
					(thickness 0.15)
				)
			)
		)
		(property "MPN" "JTH-0024NL"
			(at 0 0 180)
			(unlocked yes)
			(layer "F.Fab")
			(hide yes)
			(effects
				(font
					(size 1 1)
					(thickness 0.15)
				)
			)
		)
		(property "Manufacturer" "Pulse Electronics"
			(at 0 0 180)
			(unlocked yes)
			(layer "F.Fab")
			(hide yes)
			(effects
				(font
					(size 1 1)
					(thickness 0.15)
				)
			)
		)
		(property "Author" "Antmicro"
			(at 0 0 180)
			(unlocked yes)
			(layer "F.Fab")
			(hide yes)
			(effects
				(font
					(size 1 1)
					(thickness 0.15)
				)
			)
		)
		(property "License" "Apache-2.0"
			(at 0 0 180)
			(unlocked yes)
			(layer "F.Fab")
			(hide yes)
			(effects
				(font
					(size 1 1)
					(thickness 0.15)
				)
			)
		)
		(property ki_fp_filters "CONN18_5-2337992-8_TEC")
		(sheetname "/2xRJ45/")
		(sheetfile "2xrj45.kicad_sch")
		(attr through_hole)
		(fp_line
			(start 14 4)
			(end 14 -5.25)
			(stroke
				(width 0.1)
				(type default)
			)
			(layer "F.SilkS")
		)
		(fp_line
			(start -3.75 4)
			(end 14 4)
			(stroke
				(width 0.1)
				(type default)
			)
			(layer "F.SilkS")
		)
		(fp_line
			(start -3.75 -5.25)
			(end -3.75 4)
			(stroke
				(width 0.1)
				(type default)
			)
			(layer "F.SilkS")
		)
		(fp_rect
			(start -5.4 -20.72)
			(end 15.58 4.45)
			(stroke
				(width 0.05)
				(type solid)
			)
			(fill no)
			(layer "F.CrtYd")
		)
		(fp_text user "Author: Antmicro"
			(at -5.75 8.85 180)
			(layer "F.Fab")
			(effects
				(font
					(size 0.7 0.7)
					(thickness 0.15)
				)
				(justify left bottom)
			)
		)
		(fp_text user "${REFERENCE}"
			(at -5.75 6.45 180)
			(unlocked yes)
			(layer "F.Fab")
			(effects
				(font
					(size 0.7 0.7)
					(thickness 0.15)
				)
				(justify left bottom)
			)
		)
		(fp_text user "License: Apache-2.0"
			(at -5.75 7.65 180)
			(layer "F.Fab")
			(effects
				(font
					(size 0.7 0.7)
					(thickness 0.15)
				)
				(justify left bottom)
			)
		)
		(pad "" np_thru_hole circle
			(at 0.245 -6.6 180)
			(size 3.2 3.2)
			(drill 3.2)
			(layers "*.Cu" "*.Mask")
		)
		(pad "" np_thru_hole circle
			(at 9.895 -6.6 180)
			(size 3.2 3.2)
			(drill 3.2)
			(layers "*.Cu" "*.Mask")
		)
		(pad "1" thru_hole circle
			(at 0 0 180)
			(size 1.39 1.39)
			(drill 0.89)
			(layers "*.Cu" "*.Mask")
			(remove_unused_layers no)
			(net 300 "/2xRJ45/P1_CT")
			(pinfunction "CT3")
			(pintype "bidirectional")
		)
		(pad "2" thru_hole circle
			(at 2.03 0 180)
			(size 1.39 1.39)
			(drill 0.89)
			(layers "*.Cu" "*.Mask")
			(remove_unused_layers no)
			(net 60 "/2xRJ45/Ethernet_P1.D2-")
			(pinfunction "T2-")
			(pintype "bidirectional")
		)
		(pad "3" thru_hole circle
			(at 4.06 0 180)
			(size 1.39 1.39)
			(drill 0.89)
			(layers "*.Cu" "*.Mask")
			(remove_unused_layers no)
			(net 62 "/2xRJ45/Ethernet_P1.D2+")
			(pinfunction "T2+")
			(pintype "bidirectional")
		)
		(pad "4" thru_hole circle
			(at 6.09 0 180)
			(size 1.39 1.39)
			(drill 0.89)
			(layers "*.Cu" "*.Mask")
			(remove_unused_layers no)
			(net 63 "/2xRJ45/Ethernet_P1.D3+")
			(pinfunction "T3+")
			(pintype "bidirectional")
		)
		(pad "5" thru_hole circle
			(at 8.12 0 180)
			(size 1.39 1.39)
			(drill 0.89)
			(layers "*.Cu" "*.Mask")
			(remove_unused_layers no)
			(net 65 "/2xRJ45/Ethernet_P1.D3-")
			(pinfunction "T3-")
			(pintype "bidirectional")
		)
		(pad "6" thru_hole circle
			(at 10.15 0 180)
			(size 1.39 1.39)
			(drill 0.89)
			(layers "*.Cu" "*.Mask")
			(remove_unused_layers no)
			(net 300 "/2xRJ45/P1_CT")
			(pinfunction "CT2")
			(pintype "bidirectional")
		)
		(pad "7" thru_hole circle
			(at -1.02 2.54 180)
			(size 1.39 1.39)
			(drill 0.89)
			(layers "*.Cu" "*.Mask")
			(remove_unused_layers no)
			(net 300 "/2xRJ45/P1_CT")
			(pinfunction "CT4")
			(pintype "bidirectional")
		)
		(pad "8" thru_hole circle
			(at 1.01 2.54 180)
			(size 1.39 1.39)
			(drill 0.89)
			(layers "*.Cu" "*.Mask")
			(remove_unused_layers no)
			(net 69 "/2xRJ45/Ethernet_P1.D1+")
			(pinfunction "T1+")
			(pintype "bidirectional")
		)
		(pad "9" thru_hole circle
			(at 3.04 2.54 180)
			(size 1.39 1.39)
			(drill 0.89)
			(layers "*.Cu" "*.Mask")
			(remove_unused_layers no)
			(net 59 "/2xRJ45/Ethernet_P1.D1-")
			(pinfunction "T1-")
			(pintype "bidirectional")
		)
		(pad "10" thru_hole circle
			(at 7.11 2.54 180)
			(size 1.39 1.39)
			(drill 0.89)
			(layers "*.Cu" "*.Mask")
			(remove_unused_layers no)
			(net 68 "/2xRJ45/Ethernet_P1.D4-")
			(pinfunction "T4-")
			(pintype "bidirectional")
		)
		(pad "11" thru_hole circle
			(at 9.14 2.54 180)
			(size 1.39 1.39)
			(drill 0.89)
			(layers "*.Cu" "*.Mask")
			(remove_unused_layers no)
			(net 67 "/2xRJ45/Ethernet_P1.D4+")
			(pinfunction "T4+")
			(pintype "bidirectional")
		)
		(pad "12" thru_hole circle
			(at 11.17 2.54 180)
			(size 1.39 1.39)
			(drill 0.89)
			(layers "*.Cu" "*.Mask")
			(remove_unused_layers no)
			(net 300 "/2xRJ45/P1_CT")
			(pinfunction "CT1")
			(pintype "bidirectional")
		)
		(pad "13" thru_hole circle
			(at 12.59 -12.95 180)
			(size 1.77 1.77)
			(drill 1.27)
			(layers "*.Cu" "*.Mask")
			(remove_unused_layers no)
			(net 66 "Net-(J6-LED_GRN-)")
			(pinfunction "LED_GRN-")
			(pintype "passive")
		)
		(pad "14" thru_hole circle
			(at 12.59 -15.49 180)
			(size 1.77 1.77)
			(drill 1.27)
			(layers "*.Cu" "*.Mask")
			(remove_unused_layers no)
			(net 7 "+3V3")
			(pinfunction "LED_GRN+")
			(pintype "passive")
		)
		(pad "15" thru_hole circle
			(at -2.45 -10.41 180)
			(size 1.77 1.77)
			(drill 1.27)
			(layers "*.Cu" "*.Mask")
			(remove_unused_layers no)
			(net 61 "Net-(J6-LED_YG_Y-)")
			(pinfunction "LED_YG_Y-")
			(pintype "passive")
		)
		(pad "16" thru_hole circle
			(at -2.45 -12.95 180)
			(size 1.77 1.77)
			(drill 1.27)
			(layers "*.Cu" "*.Mask")
			(remove_unused_layers no)
			(net 7 "+3V3")
			(pinfunction "LED_COM+")
			(pintype "passive")
		)
		(pad "17" thru_hole circle
			(at -2.45 -15.49 180)
			(size 1.77 1.77)
			(drill 1.27)
			(layers "*.Cu" "*.Mask")
			(remove_unused_layers no)
			(net 64 "Net-(J6-LED_YG_G-)")
			(pinfunction "LED_YG_G-")
			(pintype "passive")
		)
		(pad "SH" thru_hole circle
			(at -3.72 -6.6 180)
			(size 2.07 2.07)
			(drill 1.57)
			(layers "*.Cu" "*.Mask")
			(remove_unused_layers no)
			(net 28 "GND")
			(pinfunction "SHIELD")
			(pintype "passive")
		)
		(pad "SH" thru_hole circle
			(at 13.86 -6.6 180)
			(size 2.07 2.07)
			(drill 1.57)
			(layers "*.Cu" "*.Mask")
			(remove_unused_layers no)
			(net 28 "GND")
			(pinfunction "SHIELD")
			(pintype "passive")
		)
	)
	(footprint "antmicro-footprints:TP_SMD_0.75mm"
		(layer "F.Cu")
		(at 113.2 105.226 180)
		(property "Reference" "TP26"
			(at 0.8 -0.474 90)
			(layer "F.SilkS")
			(effects
				(font
					(size 0.7 0.7)
					(thickness 0.15)
				)
				(justify right top)
			)
		)
		(property "Value" "TP_0.75mm_SMD"
			(at 0 1.2 0)
			(layer "F.Fab")
			(hide yes)
			(effects
				(font
					(size 0.7 0.7)
					(thickness 0.15)
				)
				(justify right top)
			)
		)
		(property "Description" "SMT test point"
			(at 0 0 0)
			(layer "F.Fab")
			(hide yes)
			(effects
				(font
					(size 1.27 1.27)
					(thickness 0.15)
				)
			)
		)
		(property "MPN" ""
			(at 0 0 180)
			(unlocked yes)
			(layer "F.Fab")
			(hide yes)
			(effects
				(font
					(size 1 1)
					(thickness 0.15)
				)
			)
		)
		(property "Manufacturer" ""
			(at 0 0 180)
			(unlocked yes)
			(layer "F.Fab")
			(hide yes)
			(effects
				(font
					(size 1 1)
					(thickness 0.15)
				)
			)
		)
		(property "Author" "Antmicro"
			(at 0 0 180)
			(unlocked yes)
			(layer "F.Fab")
			(hide yes)
			(effects
				(font
					(size 1 1)
					(thickness 0.15)
				)
			)
		)
		(property "License" "Apache-2.0"
			(at 0 0 180)
			(unlocked yes)
			(layer "F.Fab")
			(hide yes)
			(effects
				(font
					(size 1 1)
					(thickness 0.15)
				)
			)
		)
		(sheetname "/Fan controller/")
		(sheetfile "fan-controller.kicad_sch")
		(attr exclude_from_pos_files exclude_from_bom dnp)
		(fp_circle
			(center 0 0)
			(end 0.475 0)
			(stroke
				(width 0.05)
				(type default)
			)
			(fill no)
			(layer "F.CrtYd")
		)
		(pad "1" smd circle
			(at 0 0 180)
			(size 0.75 0.75)
			(layers "F.Cu" "F.Mask")
			(net 388 "/Fan controller/+5V")
			(pinfunction "1")
			(pintype "passive")
		)
	)
	(footprint "antmicro-footprints:C_0603_1608Metric_EIA"
		(layer "F.Cu")
		(at 70.499998 75.839995 180)
		(descr "Capacitor SMD 0603, IPC-7351 Density Level A")
		(tags "Capacitor 0603")
		(property "Reference" "C3"
			(at 1.199998 0.339995 0)
			(layer "F.SilkS")
			(effects
				(font
					(size 0.7 0.7)
					(thickness 0.15)
				)
				(justify right top)
			)
		)
		(property "Value" "C_22u_16V_0603"
			(at -1.42757 1.770288 0)
			(layer "F.Fab")
			(hide yes)
			(effects
				(font
					(size 0.7 0.7)
					(thickness 0.15)
				)
				(justify right top)
			)
		)
		(property "Datasheet" "https://product.samsungsem.com/mlcc/CL10A226MO7JZN.do"
			(at 0 0 0)
			(layer "F.Fab")
			(hide yes)
			(effects
				(font
					(size 1.27 1.27)
					(thickness 0.15)
				)
			)
		)
		(property "Description" "SMD Multilayer Ceramic Capacitor"
			(at 0 0 0)
			(layer "F.Fab")
			(hide yes)
			(effects
				(font
					(size 1.27 1.27)
					(thickness 0.15)
				)
			)
		)
		(property "MPN" "CL10A226MO7JZNC"
			(at 0 0 180)
			(unlocked yes)
			(layer "F.Fab")
			(hide yes)
			(effects
				(font
					(size 1 1)
					(thickness 0.15)
				)
			)
		)
		(property "Manufacturer" "Samsung Electro-Mechanics"
			(at 0 0 180)
			(unlocked yes)
			(layer "F.Fab")
			(hide yes)
			(effects
				(font
					(size 1 1)
					(thickness 0.15)
				)
			)
		)
		(property "License" "Apache-2.0"
			(at 0 0 180)
			(unlocked yes)
			(layer "F.Fab")
			(hide yes)
			(effects
				(font
					(size 1 1)
					(thickness 0.15)
				)
			)
		)
		(property "Author" "Antmicro"
			(at 0 0 180)
			(unlocked yes)
			(layer "F.Fab")
			(hide yes)
			(effects
				(font
					(size 1 1)
					(thickness 0.15)
				)
			)
		)
		(property "Val" "22u"
			(at 0 0 180)
			(unlocked yes)
			(layer "F.Fab")
			(hide yes)
			(effects
				(font
					(size 1 1)
					(thickness 0.15)
				)
			)
		)
		(property "Voltage" "16V"
			(at 0 0 180)
			(unlocked yes)
			(layer "F.Fab")
			(hide yes)
			(effects
				(font
					(size 1 1)
					(thickness 0.15)
				)
			)
		)
		(property "Dielectric" ""
			(at 0 0 180)
			(unlocked yes)
			(layer "F.Fab")
			(hide yes)
			(effects
				(font
					(size 1 1)
					(thickness 0.15)
				)
			)
		)
		(property "Public" "False"
			(at 0 0 180)
			(unlocked yes)
			(layer "F.Fab")
			(hide yes)
			(effects
				(font
					(size 1 1)
					(thickness 0.15)
				)
			)
		)
		(sheetname "/Power/")
		(sheetfile "power.kicad_sch")
		(attr smd)
		(fp_line
			(start -0.15 0.55)
			(end 0.15 0.55)
			(stroke
				(width 0.15)
				(type solid)
			)
			(layer "F.SilkS")
		)
		(fp_line
			(start -0.15 -0.55)
			(end 0.15 -0.55)
			(stroke
				(width 0.15)
				(type solid)
			)
			(layer "F.SilkS")
		)
		(fp_rect
			(start -1.25 -0.65)
			(end 1.25 0.65)
			(stroke
				(width 0.05)
				(type solid)
			)
			(fill no)
			(layer "F.CrtYd")
		)
		(fp_rect
			(start -0.8 -0.45)
			(end 0.8 0.45)
			(stroke
				(width 0.15)
				(type solid)
			)
			(fill no)
			(layer "F.Fab")
		)
		(pad "1" smd roundrect
			(at -0.7 0 180)
			(size 0.8 1.1)
			(layers "F.Cu" "F.Mask" "F.Paste")
			(roundrect_rratio 0.2)
			(net 28 "GND")
			(pintype "passive")
		)
		(pad "2" smd roundrect
			(at 0.7 0 180)
			(size 0.8 1.1)
			(layers "F.Cu" "F.Mask" "F.Paste")
			(roundrect_rratio 0.2)
			(net 314 "VCC")
			(pintype "passive")
		)
	)
	(footprint "antmicro-footprints:C_0402_1005Metric"
		(layer "F.Cu")
		(at 118.33 103.87 -90)
		(descr "Capacitor SMD 0402")
		(tags "capacitor SMD 0402")
		(property "Reference" "C212"
			(at -1.39 -0.56 90)
			(layer "F.SilkS")
			(effects
				(font
					(size 0.7 0.7)
					(thickness 0.15)
				)
				(justify right top)
			)
		)
		(property "Value" "C_1u_25V_0402"
			(at -1.022927 2.155213 90)
			(layer "F.Fab")
			(effects
				(font
					(size 0.7 0.7)
					(thickness 0.15)
				)
				(justify right top)
			)
		)
		(property "Datasheet" "https://www.murata.com/products/productdetail?partno=GRM155R61E105KE11%23"
			(at 0 0 90)
			(layer "F.Fab")
			(hide yes)
			(effects
				(font
					(size 1.27 1.27)
					(thickness 0.15)
				)
			)
		)
		(property "Description" "SMD Multilayer Ceramic Capacitor, 1 µF, 25 V, 0402 [1005 Metric], ± 10%, X5R, GRM Series"
			(at 0 0 90)
			(layer "F.Fab")
			(hide yes)
			(effects
				(font
					(size 1.27 1.27)
					(thickness 0.15)
				)
			)
		)
		(property "MPN" "GRM155R61E105KE11J"
			(at 0 0 270)
			(unlocked yes)
			(layer "F.Fab")
			(hide yes)
			(effects
				(font
					(size 1 1)
					(thickness 0.15)
				)
			)
		)
		(property "Manufacturer" "Murata"
			(at 0 0 270)
			(unlocked yes)
			(layer "F.Fab")
			(hide yes)
			(effects
				(font
					(size 1 1)
					(thickness 0.15)
				)
			)
		)
		(property "License" "Apache-2.0"
			(at 0 0 270)
			(unlocked yes)
			(layer "F.Fab")
			(hide yes)
			(effects
				(font
					(size 1 1)
					(thickness 0.15)
				)
			)
		)
		(property "Author" "Antmicro"
			(at 0 0 270)
			(unlocked yes)
			(layer "F.Fab")
			(hide yes)
			(effects
				(font
					(size 1 1)
					(thickness 0.15)
				)
			)
		)
		(property "Val" "1u"
			(at 0 0 270)
			(unlocked yes)
			(layer "F.Fab")
			(hide yes)
			(effects
				(font
					(size 1 1)
					(thickness 0.15)
				)
			)
		)
		(property "Voltage" "25V"
			(at 0 0 270)
			(unlocked yes)
			(layer "F.Fab")
			(hide yes)
			(effects
				(font
					(size 1 1)
					(thickness 0.15)
				)
			)
		)
		(property "Dielectric" "X5R"
			(at 0 0 270)
			(unlocked yes)
			(layer "F.Fab")
			(hide yes)
			(effects
				(font
					(size 1 1)
					(thickness 0.15)
				)
			)
		)
		(sheetname "/Fan controller/")
		(sheetfile "fan-controller.kicad_sch")
		(attr smd exclude_from_pos_files exclude_from_bom dnp)
		(fp_rect
			(start -0.925 -0.47)
			(end 0.925 0.47)
			(stroke
				(width 0.05)
				(type default)
			)
			(fill no)
			(layer "F.CrtYd")
		)
		(fp_line
			(start -0.494 0.248)
			(end -0.494 -0.25)
			(stroke
				(width 0.15)
				(type solid)
			)
			(layer "F.Fab")
		)
		(fp_line
			(start 0.504 0.248)
			(end -0.494 0.248)
			(stroke
				(width 0.15)
				(type solid)
			)
			(layer "F.Fab")
		)
		(fp_line
			(start -0.494 -0.25)
			(end 0.504 -0.25)
			(stroke
				(width 0.15)
				(type solid)
			)
			(layer "F.Fab")
		)
		(fp_line
			(start 0.504 -0.25)
			(end 0.504 0.248)
			(stroke
				(width 0.15)
				(type solid)
			)
			(layer "F.Fab")
		)
		(fp_text user "Author: Antmicro"
			(at -0.939 3.399 90)
			(layer "F.Fab")
			(effects
				(font
					(size 0.7 0.7)
					(thickness 0.15)
				)
				(justify right top)
			)
		)
		(fp_text user "${REFERENCE}"
			(at -0.939 4.599 90)
			(layer "F.Fab")
			(effects
				(font
					(size 0.7 0.7)
					(thickness 0.15)
				)
				(justify right top)
			)
		)
		(fp_text user "License: Apache-2.0"
			(at -0.939 5.799 90)
			(layer "F.Fab")
			(effects
				(font
					(size 0.7 0.7)
					(thickness 0.15)
				)
				(justify right top)
			)
		)
		(pad "1" smd roundrect
			(at -0.48 0 270)
			(size 0.59 0.64)
			(layers "F.Cu" "F.Mask" "F.Paste")
			(roundrect_rratio 0.25)
			(net 28 "GND")
			(pintype "passive")
		)
		(pad "2" smd roundrect
			(at 0.48 0 270)
			(size 0.59 0.64)
			(layers "F.Cu" "F.Mask" "F.Paste")
			(roundrect_rratio 0.25)
			(net 314 "VCC")
			(pintype "passive")
		)
	)
	(footprint "antmicro-footprints:R_0402_1005Metric"
		(layer "F.Cu")
		(at 73.849999 77.039994 180)
		(descr "Resistor SMD 0402")
		(tags "resistor SMD 0402")
		(property "Reference" "R5"
			(at -1 3.439994 0)
			(layer "F.SilkS")
			(effects
				(font
					(size 0.7 0.7)
					(thickness 0.15)
				)
				(justify right top)
			)
		)
		(property "Value" "R_100k_0402"
			(at -1.011843 1.772046 0)
			(layer "F.Fab")
			(hide yes)
			(effects
				(font
					(size 0.7 0.7)
					(thickness 0.15)
				)
				(justify right top)
			)
		)
		(property "Datasheet" "https://www.bourns.com/docs/product-datasheets/cr.pdf"
			(at 0 0 0)
			(layer "F.Fab")
			(hide yes)
			(effects
				(font
					(size 1.27 1.27)
					(thickness 0.15)
				)
			)
		)
		(property "Description" "SMD Chip Resistor, 100 kohm, ± 1%, 62.5 mW, 0402 [1005 Metric], Thick Film, General Purpose"
			(at 0 0 0)
			(layer "F.Fab")
			(hide yes)
			(effects
				(font
					(size 1.27 1.27)
					(thickness 0.15)
				)
			)
		)
		(property "MPN" "CR0402-FX-1003GLF"
			(at 0 0 180)
			(unlocked yes)
			(layer "F.Fab")
			(hide yes)
			(effects
				(font
					(size 1 1)
					(thickness 0.15)
				)
			)
		)
		(property "Manufacturer" "Bourns"
			(at 0 0 180)
			(unlocked yes)
			(layer "F.Fab")
			(hide yes)
			(effects
				(font
					(size 1 1)
					(thickness 0.15)
				)
			)
		)
		(property "License" "Apache-2.0"
			(at 0 0 180)
			(unlocked yes)
			(layer "F.Fab")
			(hide yes)
			(effects
				(font
					(size 1 1)
					(thickness 0.15)
				)
			)
		)
		(property "Author" "Antmicro"
			(at 0 0 180)
			(unlocked yes)
			(layer "F.Fab")
			(hide yes)
			(effects
				(font
					(size 1 1)
					(thickness 0.15)
				)
			)
		)
		(property "Val" "100k"
			(at 0 0 180)
			(unlocked yes)
			(layer "F.Fab")
			(hide yes)
			(effects
				(font
					(size 1 1)
					(thickness 0.15)
				)
			)
		)
		(property "Tolerance" "1%"
			(at 0 0 180)
			(unlocked yes)
			(layer "F.Fab")
			(hide yes)
			(effects
				(font
					(size 1 1)
					(thickness 0.15)
				)
			)
		)
		(sheetname "/Power/")
		(sheetfile "power.kicad_sch")
		(attr smd)
		(fp_rect
			(start -0.925 -0.47)
			(end 0.925 0.47)
			(stroke
				(width 0.05)
				(type default)
			)
			(fill no)
			(layer "F.CrtYd")
		)
		(fp_rect
			(start -0.5 -0.25)
			(end 0.5 0.25)
			(stroke
				(width 0.15)
				(type solid)
			)
			(fill no)
			(layer "F.Fab")
		)
		(pad "1" smd roundrect
			(at -0.48 0 180)
			(size 0.59 0.64)
			(layers "F.Cu" "F.Mask" "F.Paste")
			(roundrect_rratio 0.25)
			(net 28 "GND")
			(pintype "passive")
		)
		(pad "2" smd roundrect
			(at 0.48 0 180)
			(size 0.59 0.64)
			(layers "F.Cu" "F.Mask" "F.Paste")
			(roundrect_rratio 0.25)
			(net 379 "/Power/3V3_EN")
			(pintype "passive")
		)
	)
	(footprint "antmicro-footprints:TP_SMD_0.75mm"
		(layer "F.Cu")
		(at 52.05 123.850001 180)
		(property "Reference" "TP19"
			(at 0.34 0.16 0)
			(layer "F.SilkS")
			(hide yes)
			(effects
				(font
					(size 0.7 0.7)
					(thickness 0.15)
				)
				(justify right top)
			)
		)
		(property "Value" "TP_0.75mm_SMD"
			(at 0 1.2 0)
			(layer "F.Fab")
			(hide yes)
			(effects
				(font
					(size 0.7 0.7)
					(thickness 0.15)
				)
				(justify right top)
			)
		)
		(property "Description" "SMT test point"
			(at 0 0 0)
			(layer "F.Fab")
			(hide yes)
			(effects
				(font
					(size 1.27 1.27)
					(thickness 0.15)
				)
			)
		)
		(property "MPN" ""
			(at 0 0 180)
			(unlocked yes)
			(layer "F.Fab")
			(hide yes)
			(effects
				(font
					(size 1 1)
					(thickness 0.15)
				)
			)
		)
		(property "Manufacturer" ""
			(at 0 0 180)
			(unlocked yes)
			(layer "F.Fab")
			(hide yes)
			(effects
				(font
					(size 1 1)
					(thickness 0.15)
				)
			)
		)
		(property "Author" "Antmicro"
			(at 0 0 180)
			(unlocked yes)
			(layer "F.Fab")
			(hide yes)
			(effects
				(font
					(size 1 1)
					(thickness 0.15)
				)
			)
		)
		(property "License" "Apache-2.0"
			(at 0 0 180)
			(unlocked yes)
			(layer "F.Fab")
			(hide yes)
			(effects
				(font
					(size 1 1)
					(thickness 0.15)
				)
			)
		)
		(sheetname "/Power/")
		(sheetfile "power.kicad_sch")
		(attr exclude_from_pos_files exclude_from_bom)
		(fp_circle
			(center 0 0)
			(end 0.475 0)
			(stroke
				(width 0.05)
				(type default)
			)
			(fill no)
			(layer "F.CrtYd")
		)
		(pad "1" smd circle
			(at 0 0 180)
			(size 0.75 0.75)
			(layers "F.Cu" "F.Mask")
			(net 310 "/Power/+1V88_OUT")
			(pinfunction "1")
			(pintype "passive")
		)
	)
	(footprint "antmicro-footprints:C_0402_1005Metric"
		(layer "F.Cu")
		(at 68.9 80.339994 -90)
		(descr "Capacitor SMD 0402")
		(tags "capacitor SMD 0402")
		(property "Reference" "C1"
			(at -2.279994 -0.58 270)
			(layer "F.SilkS")
			(effects
				(font
					(size 0.7 0.7)
					(thickness 0.15)
				)
				(justify right bottom)
			)
		)
		(property "Value" "C_100n_0402"
			(at -1.022927 2.155213 90)
			(layer "F.Fab")
			(hide yes)
			(effects
				(font
					(size 0.7 0.7)
					(thickness 0.15)
				)
				(justify right top)
			)
		)
		(property "Datasheet" "https://www.murata.com/products/productdetail?partno=GRM155R61H104KE14%23"
			(at 0 0 90)
			(layer "F.Fab")
			(hide yes)
			(effects
				(font
					(size 1.27 1.27)
					(thickness 0.15)
				)
			)
		)
		(property "Description" "SMD Multilayer Ceramic Capacitor, 0.1 µF, 50 V, 0402 [1005 Metric], ± 10%, X5R, GRM Series"
			(at 0 0 90)
			(layer "F.Fab")
			(hide yes)
			(effects
				(font
					(size 1.27 1.27)
					(thickness 0.15)
				)
			)
		)
		(property "MPN" "GRM155R61H104KE14D"
			(at 0 0 270)
			(unlocked yes)
			(layer "F.Fab")
			(hide yes)
			(effects
				(font
					(size 1 1)
					(thickness 0.15)
				)
			)
		)
		(property "Manufacturer" "Murata"
			(at 0 0 270)
			(unlocked yes)
			(layer "F.Fab")
			(hide yes)
			(effects
				(font
					(size 1 1)
					(thickness 0.15)
				)
			)
		)
		(property "License" "Apache-2.0"
			(at 0 0 270)
			(unlocked yes)
			(layer "F.Fab")
			(hide yes)
			(effects
				(font
					(size 1 1)
					(thickness 0.15)
				)
			)
		)
		(property "Author" "Antmicro"
			(at 0 0 270)
			(unlocked yes)
			(layer "F.Fab")
			(hide yes)
			(effects
				(font
					(size 1 1)
					(thickness 0.15)
				)
			)
		)
		(property "Val" "100n"
			(at 0 0 270)
			(unlocked yes)
			(layer "F.Fab")
			(hide yes)
			(effects
				(font
					(size 1 1)
					(thickness 0.15)
				)
			)
		)
		(property "Voltage" "50V"
			(at 0 0 270)
			(unlocked yes)
			(layer "F.Fab")
			(hide yes)
			(effects
				(font
					(size 1 1)
					(thickness 0.15)
				)
			)
		)
		(property "Dielectric" "X5R"
			(at 0 0 270)
			(unlocked yes)
			(layer "F.Fab")
			(hide yes)
			(effects
				(font
					(size 1 1)
					(thickness 0.15)
				)
			)
		)
		(sheetname "/Power/")
		(sheetfile "power.kicad_sch")
		(attr smd)
		(fp_rect
			(start -0.925 -0.47)
			(end 0.925 0.47)
			(stroke
				(width 0.05)
				(type default)
			)
			(fill no)
			(layer "F.CrtYd")
		)
		(fp_line
			(start -0.494 0.248)
			(end -0.494 -0.25)
			(stroke
				(width 0.15)
				(type solid)
			)
			(layer "F.Fab")
		)
		(fp_line
			(start 0.504 0.248)
			(end -0.494 0.248)
			(stroke
				(width 0.15)
				(type solid)
			)
			(layer "F.Fab")
		)
		(fp_line
			(start -0.494 -0.25)
			(end 0.504 -0.25)
			(stroke
				(width 0.15)
				(type solid)
			)
			(layer "F.Fab")
		)
		(fp_line
			(start 0.504 -0.25)
			(end 0.504 0.248)
			(stroke
				(width 0.15)
				(type solid)
			)
			(layer "F.Fab")
		)
		(pad "1" smd roundrect
			(at -0.48 0 270)
			(size 0.59 0.64)
			(layers "F.Cu" "F.Mask" "F.Paste")
			(roundrect_rratio 0.25)
			(net 316 "/Power/3V3_BST")
			(pintype "passive")
		)
		(pad "2" smd roundrect
			(at 0.48 0 270)
			(size 0.59 0.64)
			(layers "F.Cu" "F.Mask" "F.Paste")
			(roundrect_rratio 0.25)
			(net 333 "/Power/3V3_SW")
			(pintype "passive")
		)
	)
	(footprint "antmicro-footprints:VQFN-HR-9_2x1.5mm"
		(layer "F.Cu")
		(at 56.1 111.15 -90)
		(property "Reference" "U4"
			(at 1.41 1.25 90)
			(layer "F.SilkS")
			(effects
				(font
					(size 0.7 0.7)
					(thickness 0.15)
				)
				(justify right top)
			)
		)
		(property "Value" "TPS566231P"
			(at -1.45 2.45 90)
			(layer "F.Fab")
			(hide yes)
			(effects
				(font
					(size 0.7 0.7)
					(thickness 0.15)
				)
				(justify right top)
			)
		)
		(property "Datasheet" "https://www.ti.com/lit/ds/symlink/tps566231.pdf"
			(at 0 -0.045 90)
			(layer "F.Fab")
			(hide yes)
			(effects
				(font
					(size 0.7 0.7)
					(thickness 0.15)
				)
				(justify right top)
			)
		)
		(property "Description" "Switching Voltage Regulators 3-V to 18-V, 6-A synchronous buck converter"
			(at -1.45 3.65 90)
			(layer "F.Fab")
			(hide yes)
			(effects
				(font
					(size 0.7 0.7)
					(thickness 0.15)
				)
				(justify right top)
			)
		)
		(property "Manufacturer" "Texas Instruments"
			(at 0 0 270)
			(unlocked yes)
			(layer "F.Fab")
			(hide yes)
			(effects
				(font
					(size 1 1)
					(thickness 0.15)
				)
			)
		)
		(property "MPN" "TPS566231PRQFR"
			(at 0 0 270)
			(unlocked yes)
			(layer "F.Fab")
			(hide yes)
			(effects
				(font
					(size 1 1)
					(thickness 0.15)
				)
			)
		)
		(property "Author" "Antmicro"
			(at 0 0 270)
			(unlocked yes)
			(layer "F.Fab")
			(hide yes)
			(effects
				(font
					(size 1 1)
					(thickness 0.15)
				)
			)
		)
		(property "License" "Apache-2.0"
			(at 0 0 270)
			(unlocked yes)
			(layer "F.Fab")
			(hide yes)
			(effects
				(font
					(size 1 1)
					(thickness 0.15)
				)
			)
		)
		(sheetname "/Power/")
		(sheetfile "power.kicad_sch")
		(attr smd)
		(fp_line
			(start -1 0.945)
			(end -0.695 0.945)
			(stroke
				(width 0.15)
				(type solid)
			)
			(layer "F.SilkS")
		)
		(fp_line
			(start 1 0.945)
			(end 0.2 0.945)
			(stroke
				(width 0.15)
				(type solid)
			)
			(layer "F.SilkS")
		)
		(fp_line
			(start -1 -0.945)
			(end -0.695 -0.945)
			(stroke
				(width 0.15)
				(type solid)
			)
			(layer "F.SilkS")
		)
		(fp_line
			(start 1 -0.945)
			(end 0.695 -0.945)
			(stroke
				(width 0.15)
				(type solid)
			)
			(layer "F.SilkS")
		)
		(fp_circle
			(center -1.18 -0.77)
			(end -1.13 -0.77)
			(stroke
				(width 0.15)
				(type solid)
			)
			(fill yes)
			(layer "F.SilkS")
		)
		(fp_rect
			(start -1.3 -1.05)
			(end 1.3 1.05)
			(stroke
				(width 0.05)
				(type solid)
			)
			(fill no)
			(layer "F.CrtYd")
		)
		(fp_rect
			(start -1 -0.75)
			(end 1 0.75)
			(stroke
				(width 0.15)
				(type solid)
			)
			(fill no)
			(layer "F.Fab")
		)
		(pad "1" smd roundrect
			(at -0.925 -0.5 270)
			(size 0.55 0.25)
			(layers "F.Cu" "F.Mask" "F.Paste")
			(roundrect_rratio 0.125)
			(net 328 "/Power/1V0_VCC")
			(pinfunction "V_{CC}")
			(pintype "passive")
		)
		(pad "2" smd roundrect
			(at -0.925 0 270)
			(size 0.55 0.25)
			(layers "F.Cu" "F.Mask" "F.Paste")
			(roundrect_rratio 0.125)
			(net 332 "/Power/1V0_FB")
			(pinfunction "FB")
			(pintype "input")
		)
		(pad "3" smd roundrect
			(at -0.925 0.5 270)
			(size 0.55 0.25)
			(layers "F.Cu" "F.Mask" "F.Paste")
			(roundrect_rratio 0.125)
			(net 377 "/Power/1V0_EN")
			(pinfunction "EN")
			(pintype "input")
		)
		(pad "4" smd roundrect
			(at -0.25 0.45 270)
			(size 0.25 1)
			(layers "F.Cu" "F.Mask" "F.Paste")
			(roundrect_rratio 0.125)
			(net 28 "GND")
			(pinfunction "PGND")
			(pintype "power_in")
		)
		(pad "5" smd roundrect
			(at 0.925 0.5 270)
			(size 0.55 0.25)
			(layers "F.Cu" "F.Mask" "F.Paste")
			(roundrect_rratio 0.125)
			(net 314 "VCC")
			(pinfunction "V_{IN}")
			(pintype "power_in")
		)
		(pad "6" smd roundrect
			(at 0.925 0 270)
			(size 0.55 0.25)
			(layers "F.Cu" "F.Mask" "F.Paste")
			(roundrect_rratio 0.125)
			(net 314 "VCC")
			(pinfunction "V_{IN}")
			(pintype "passive")
		)
		(pad "7" smd roundrect
			(at 0.925 -0.5 270)
			(size 0.55 0.25)
			(layers "F.Cu" "F.Mask" "F.Paste")
			(roundrect_rratio 0.125)
			(net 327 "/Power/1V0_BST")
			(pinfunction "BST")
			(pintype "passive")
		)
		(pad "8" smd roundrect
			(at 0.25 -0.3 270)
			(size 0.25 1.3)
			(layers "F.Cu" "F.Mask" "F.Paste")
			(roundrect_rratio 0.125)
			(net 337 "/Power/1V0_SW")
			(pinfunction "SW")
			(pintype "power_out")
		)
		(pad "9" smd roundrect
			(at -0.25 -0.675 270)
			(size 0.25 0.55)
			(layers "F.Cu" "F.Mask" "F.Paste")
			(roundrect_rratio 0.125)
			(net 341 "/Power/1V0_PG")
			(pinfunction "PG")
			(pintype "passive")
		)
	)
	(footprint "antmicro-footprints:SOD-123FL"
		(layer "F.Cu")
		(at 111.265 116.355 -90)
		(property "Reference" "D14"
			(at -0.2 2.05 90)
			(layer "F.SilkS")
			(effects
				(font
					(size 0.7 0.7)
					(thickness 0.15)
				)
				(justify right top)
			)
		)
		(property "Value" "SZSMF4L14AT3G"
			(at 0 1.967 90)
			(layer "F.Fab")
			(hide yes)
			(effects
				(font
					(size 0.7 0.7)
					(thickness 0.15)
				)
				(justify right top)
			)
		)
		(property "Datasheet" "https://www.mouser.com/datasheet/2/240/media-3320461.pdf"
			(at 0 0 90)
			(layer "F.Fab")
			(hide yes)
			(effects
				(font
					(size 1.27 1.27)
					(thickness 0.15)
				)
			)
		)
		(property "Description" "ESD, TVS Diode, 14V, UNI, 400W, SOD-123FL"
			(at 0 0 90)
			(layer "F.Fab")
			(hide yes)
			(effects
				(font
					(size 1.27 1.27)
					(thickness 0.15)
				)
			)
		)
		(property "MPN" "SZSMF4L12AT3G"
			(at 0 0 270)
			(unlocked yes)
			(layer "F.Fab")
			(hide yes)
			(effects
				(font
					(size 1 1)
					(thickness 0.15)
				)
			)
		)
		(property "Author" "Antmicro"
			(at 0 0 270)
			(unlocked yes)
			(layer "F.Fab")
			(hide yes)
			(effects
				(font
					(size 1 1)
					(thickness 0.15)
				)
			)
		)
		(property "License" "Apache-2.0"
			(at 0 0 270)
			(unlocked yes)
			(layer "F.Fab")
			(hide yes)
			(effects
				(font
					(size 1 1)
					(thickness 0.15)
				)
			)
		)
		(property "Manufacturer" "Littelfuse"
			(at 0 0 270)
			(unlocked yes)
			(layer "F.Fab")
			(hide yes)
			(effects
				(font
					(size 1 1)
					(thickness 0.15)
				)
			)
		)
		(sheetname "/Fan controller/")
		(sheetfile "fan-controller.kicad_sch")
		(attr smd exclude_from_pos_files exclude_from_bom dnp)
		(fp_line
			(start -2.3 1.1)
			(end 0 1.1)
			(stroke
				(width 0.15)
				(type solid)
			)
			(layer "F.SilkS")
		)
		(fp_line
			(start -2.3 -1.1)
			(end -2.3 1.1)
			(stroke
				(width 0.15)
				(type solid)
			)
			(layer "F.SilkS")
		)
		(fp_line
			(start 0 -1.1)
			(end -2.3 -1.1)
			(stroke
				(width 0.15)
				(type solid)
			)
			(layer "F.SilkS")
		)
		(fp_rect
			(start -2.35 -1.125)
			(end 2.35 1.125)
			(stroke
				(width 0.05)
				(type solid)
			)
			(fill no)
			(layer "F.CrtYd")
		)
		(fp_rect
			(start -1.825 -0.875)
			(end 1.824 0.873)
			(stroke
				(width 0.15)
				(type solid)
			)
			(fill no)
			(layer "F.Fab")
		)
		(fp_rect
			(start -0.775 -0.875)
			(end -0.525 0.875)
			(stroke
				(width 0.15)
				(type solid)
			)
			(fill yes)
			(layer "F.Fab")
		)
		(pad "1" smd roundrect
			(at -1.43 0 270)
			(size 1.34 1.8)
			(layers "F.Cu" "F.Mask" "F.Paste")
			(roundrect_rratio 0.14)
			(net 389 "/Fan controller/V_{FAN}")
			(pinfunction "C")
			(pintype "passive")
		)
		(pad "2" smd roundrect
			(at 1.429 0 270)
			(size 1.34 1.8)
			(layers "F.Cu" "F.Mask" "F.Paste")
			(roundrect_rratio 0.14)
			(net 28 "GND")
			(pinfunction "A")
			(pintype "passive")
		)
	)
	(footprint "antmicro-footprints:TSSOP-8_3x3mm_P0.65mm"
		(layer "F.Cu")
		(at 106.975 94.4 -90)
		(property "Reference" "U8"
			(at -3.1 -0.825 90)
			(layer "F.SilkS")
			(effects
				(font
					(size 0.7 0.7)
					(thickness 0.15)
				)
				(justify left bottom)
			)
		)
		(property "Value" "NTS0102_TSSOP"
			(at 0 2.8 90)
			(layer "F.Fab")
			(hide yes)
			(effects
				(font
					(size 0.7 0.7)
					(thickness 0.15)
				)
				(justify right top)
			)
		)
		(property "Datasheet" "https://www.mouser.com/datasheet/2/302/NTS0102-1127324.pdf"
			(at 0 0 90)
			(layer "F.Fab")
			(hide yes)
			(effects
				(font
					(size 1.27 1.27)
					(thickness 0.15)
				)
			)
		)
		(property "Description" "Transceiver, 1.65 V to 3.6 V, TSSOP-8"
			(at 0 0 90)
			(layer "F.Fab")
			(hide yes)
			(effects
				(font
					(size 1.27 1.27)
					(thickness 0.15)
				)
			)
		)
		(property "MPN" "NTS0102DP"
			(at 0 0 270)
			(unlocked yes)
			(layer "F.Fab")
			(hide yes)
			(effects
				(font
					(size 1 1)
					(thickness 0.15)
				)
			)
		)
		(property "Manufacturer" "NXP"
			(at 0 0 270)
			(unlocked yes)
			(layer "F.Fab")
			(hide yes)
			(effects
				(font
					(size 1 1)
					(thickness 0.15)
				)
			)
		)
		(property "Author" "Antmicro"
			(at 0 0 270)
			(unlocked yes)
			(layer "F.Fab")
			(hide yes)
			(effects
				(font
					(size 1 1)
					(thickness 0.15)
				)
			)
		)
		(property "License" "Apache-2.0"
			(at 0 0 270)
			(unlocked yes)
			(layer "F.Fab")
			(hide yes)
			(effects
				(font
					(size 1 1)
					(thickness 0.15)
				)
			)
		)
		(sheetname "/X710-AT2 Misc/")
		(sheetfile "x710-at2-mics.kicad_sch")
		(attr smd)
		(fp_line
			(start -1.55 1.561)
			(end 1.552 1.561)
			(stroke
				(width 0.15)
				(type solid)
			)
			(layer "F.SilkS")
		)
		(fp_line
			(start -1.525 -1.537)
			(end 1.552 -1.539)
			(stroke
				(width 0.15)
				(type solid)
			)
			(layer "F.SilkS")
		)
		(fp_circle
			(center -1.87 -1.4)
			(end -1.82 -1.4)
			(stroke
				(width 0.15)
				(type solid)
			)
			(fill yes)
			(layer "F.SilkS")
		)
		(fp_rect
			(start -3.15 -1.789)
			(end 3.15 1.811)
			(stroke
				(width 0.05)
				(type solid)
			)
			(fill no)
			(layer "F.CrtYd")
		)
		(fp_line
			(start -1.55 1.561)
			(end 1.552 1.561)
			(stroke
				(width 0.15)
				(type solid)
			)
			(layer "F.Fab")
		)
		(fp_line
			(start -1.55 -0.937)
			(end -1.55 1.561)
			(stroke
				(width 0.15)
				(type solid)
			)
			(layer "F.Fab")
		)
		(fp_line
			(start -1.55 -0.937)
			(end -0.949 -1.539)
			(stroke
				(width 0.15)
				(type solid)
			)
			(layer "F.Fab")
		)
		(fp_line
			(start -0.949 -1.539)
			(end 1.552 -1.539)
			(stroke
				(width 0.15)
				(type solid)
			)
			(layer "F.Fab")
		)
		(fp_line
			(start 1.552 -1.539)
			(end 1.552 1.561)
			(stroke
				(width 0.15)
				(type solid)
			)
			(layer "F.Fab")
		)
		(pad "1" smd roundrect
			(at -2.148 -0.962 270)
			(size 1.47 0.4)
			(layers "F.Cu" "F.Mask" "F.Paste")
			(roundrect_rratio 0.25)
			(net 215 "/X710-AT2 10GbE/MDIO0_I2C0.MDIO")
			(pinfunction "B_{2}")
			(pintype "bidirectional")
		)
		(pad "2" smd roundrect
			(at -2.148 -0.313 270)
			(size 1.47 0.4)
			(layers "F.Cu" "F.Mask" "F.Paste")
			(roundrect_rratio 0.25)
			(net 28 "GND")
			(pinfunction "GND")
			(pintype "power_in")
		)
		(pad "3" smd roundrect
			(at -2.148 0.338 270)
			(size 1.47 0.4)
			(layers "F.Cu" "F.Mask" "F.Paste")
			(roundrect_rratio 0.25)
			(net 18 "+1V88")
			(pinfunction "VCC_{A}")
			(pintype "power_in")
		)
		(pad "4" smd roundrect
			(at -2.148 0.987 270)
			(size 1.47 0.4)
			(layers "F.Cu" "F.Mask" "F.Paste")
			(roundrect_rratio 0.25)
			(net 381 "/X710-AT2 Misc/MDIO.MDIO")
			(pinfunction "A_{2}")
			(pintype "bidirectional")
		)
		(pad "5" smd roundrect
			(at 2.151 0.987 270)
			(size 1.47 0.4)
			(layers "F.Cu" "F.Mask" "F.Paste")
			(roundrect_rratio 0.25)
			(net 382 "/X710-AT2 Misc/MDIO.MDC")
			(pinfunction "A_{1}")
			(pintype "bidirectional")
		)
		(pad "6" smd roundrect
			(at 2.151 0.338 270)
			(size 1.47 0.4)
			(layers "F.Cu" "F.Mask" "F.Paste")
			(roundrect_rratio 0.25)
			(net 18 "+1V88")
			(pinfunction "OE")
			(pintype "input")
		)
		(pad "7" smd roundrect
			(at 2.151 -0.313 270)
			(size 1.47 0.4)
			(layers "F.Cu" "F.Mask" "F.Paste")
			(roundrect_rratio 0.25)
			(net 7 "+3V3")
			(pinfunction "VCC_{B}")
			(pintype "power_in")
		)
		(pad "8" smd roundrect
			(at 2.151 -0.962 270)
			(size 1.47 0.4)
			(layers "F.Cu" "F.Mask" "F.Paste")
			(roundrect_rratio 0.25)
			(net 288 "/X710-AT2 10GbE/MDIO0_I2C0.MDC")
			(pinfunction "B_{1}")
			(pintype "bidirectional")
		)
	)
	(footprint "antmicro-footprints:Conn_Molex_Nano-Fit_1x2_SMD_1054301202"
		(layer "F.Cu")
		(at 68.1 54.564 180)
		(descr "Molex Nano-Fit Power Connectors, 105430-xx02, 2 Pins per row")
		(tags "connector Molex Nano-Fit")
		(property "Reference" "J1"
			(at -4.59 -4.71 0)
			(layer "F.SilkS")
			(effects
				(font
					(size 0.7 0.7)
					(thickness 0.15)
				)
				(justify right top)
			)
		)
		(property "Value" "Molex_Nano-Fit_1x2_SMD_1054301202"
			(at 0 7.1 0)
			(layer "F.Fab")
			(hide yes)
			(effects
				(font
					(size 0.7 0.7)
					(thickness 0.15)
				)
				(justify right top)
			)
		)
		(property "Datasheet" "https://www.farnell.com/cad/3578051.pdf"
			(at 0 0 0)
			(layer "F.Fab")
			(hide yes)
			(effects
				(font
					(size 1.27 1.27)
					(thickness 0.15)
				)
			)
		)
		(property "Description" "Pin Header, Pitch 2.5 mm, 1 Row, 2 Contacts, Nano-Fit"
			(at 0 0 0)
			(layer "F.Fab")
			(hide yes)
			(effects
				(font
					(size 1.27 1.27)
					(thickness 0.15)
				)
			)
		)
		(property "Manufacturer" "Molex"
			(at 0 0 180)
			(unlocked yes)
			(layer "F.Fab")
			(hide yes)
			(effects
				(font
					(size 1 1)
					(thickness 0.15)
				)
			)
		)
		(property "MPN" "105430-1202"
			(at 0 0 180)
			(unlocked yes)
			(layer "F.Fab")
			(hide yes)
			(effects
				(font
					(size 1 1)
					(thickness 0.15)
				)
			)
		)
		(property "Author" "Antmicro"
			(at 0 0 180)
			(unlocked yes)
			(layer "F.Fab")
			(hide yes)
			(effects
				(font
					(size 1 1)
					(thickness 0.15)
				)
			)
		)
		(property "License" "Apache-2.0"
			(at 0 0 180)
			(unlocked yes)
			(layer "F.Fab")
			(hide yes)
			(effects
				(font
					(size 1 1)
					(thickness 0.15)
				)
			)
		)
		(sheetname "/Power/")
		(sheetfile "power.kicad_sch")
		(attr smd)
		(fp_line
			(start 4.48 2.298)
			(end 4.48 -4.5)
			(stroke
				(width 0.15)
				(type solid)
			)
			(layer "F.SilkS")
		)
		(fp_line
			(start 4.48 2.298)
			(end 4.28 2.698)
			(stroke
				(width 0.15)
				(type solid)
			)
			(layer "F.SilkS")
		)
		(fp_line
			(start 4.48 -4.5)
			(end 2.68 -4.5)
			(stroke
				(width 0.15)
				(type solid)
			)
			(layer "F.SilkS")
		)
		(fp_line
			(start 4.28 2.698)
			(end 4.28 4.299)
			(stroke
				(width 0.15)
				(type solid)
			)
			(layer "F.SilkS")
		)
		(fp_line
			(start -0.22 -4.5)
			(end 0.78 -4.5)
			(stroke
				(width 0.15)
				(type solid)
			)
			(layer "F.SilkS")
		)
		(fp_line
			(start -1.72 -4.5)
			(end -4.47 -4.5)
			(stroke
				(width 0.15)
				(type solid)
			)
			(layer "F.SilkS")
		)
		(fp_line
			(start -4.321 4.299)
			(end 4.28 4.299)
			(stroke
				(width 0.15)
				(type solid)
			)
			(layer "F.SilkS")
		)
		(fp_line
			(start -4.321 2.499)
			(end -4.321 4.299)
			(stroke
				(width 0.15)
				(type solid)
			)
			(layer "F.SilkS")
		)
		(fp_line
			(start -4.47 2.099)
			(end -4.321 2.499)
			(stroke
				(width 0.15)
				(type solid)
			)
			(layer "F.SilkS")
		)
		(fp_line
			(start -4.47 -4.5)
			(end -4.47 2.099)
			(stroke
				(width 0.15)
				(type solid)
			)
			(layer "F.SilkS")
		)
		(fp_circle
			(center 2.428 -4.91)
			(end 2.478 -4.91)
			(stroke
				(width 0.15)
				(type solid)
			)
			(fill yes)
			(layer "F.SilkS")
		)
		(fp_rect
			(start -4.77 -6.21)
			(end 4.77 6.11)
			(stroke
				(width 0.05)
				(type solid)
			)
			(fill no)
			(layer "F.CrtYd")
		)
		(pad "1" smd roundrect
			(at 1.528 -4.901 270)
			(size 2.5 1.24)
			(layers "F.Cu" "F.Mask" "F.Paste")
			(roundrect_rratio 0.25)
			(net 350 "/Power/+12V_IN")
			(pintype "passive")
		)
		(pad "2" smd roundrect
			(at -0.97 -4.901 270)
			(size 2.5 1.24)
			(layers "F.Cu" "F.Mask" "F.Paste")
			(roundrect_rratio 0.25)
			(net 28 "GND")
			(pintype "passive")
		)
		(pad "MP" smd roundrect
			(at -3.54 0.029 180)
			(size 1.1 8.2)
			(layers "F.Cu" "F.Mask" "F.Paste")
			(roundrect_rratio 0.25)
			(net 28 "GND")
			(pintype "passive")
		)
		(pad "MP" smd roundrect
			(at 3.499 0.029 180)
			(size 1.1 8.2)
			(layers "F.Cu" "F.Mask" "F.Paste")
			(roundrect_rratio 0.25)
			(net 28 "GND")
			(pintype "passive")
		)
	)
	(footprint "antmicro-footprints:R_0402_1005Metric"
		(layer "F.Cu")
		(at 58.1 108.25 90)
		(descr "Resistor SMD 0402")
		(tags "resistor SMD 0402")
		(property "Reference" "R25"
			(at -1.32 1.25 90)
			(layer "F.SilkS")
			(effects
				(font
					(size 0.7 0.7)
					(thickness 0.15)
				)
				(justify left bottom)
			)
		)
		(property "Value" "R_100k_0402"
			(at -1.011843 1.772046 90)
			(layer "F.Fab")
			(hide yes)
			(effects
				(font
					(size 0.7 0.7)
					(thickness 0.15)
				)
				(justify left bottom)
			)
		)
		(property "Datasheet" "https://www.bourns.com/docs/product-datasheets/cr.pdf"
			(at 0 0 90)
			(layer "F.Fab")
			(hide yes)
			(effects
				(font
					(size 1.27 1.27)
					(thickness 0.15)
				)
			)
		)
		(property "Description" "SMD Chip Resistor, 100 kohm, ± 1%, 62.5 mW, 0402 [1005 Metric], Thick Film, General Purpose"
			(at 0 0 90)
			(layer "F.Fab")
			(hide yes)
			(effects
				(font
					(size 1.27 1.27)
					(thickness 0.15)
				)
			)
		)
		(property "MPN" "CR0402-FX-1003GLF"
			(at 0 0 90)
			(unlocked yes)
			(layer "F.Fab")
			(hide yes)
			(effects
				(font
					(size 1 1)
					(thickness 0.15)
				)
			)
		)
		(property "Manufacturer" "Bourns"
			(at 0 0 90)
			(unlocked yes)
			(layer "F.Fab")
			(hide yes)
			(effects
				(font
					(size 1 1)
					(thickness 0.15)
				)
			)
		)
		(property "License" "Apache-2.0"
			(at 0 0 90)
			(unlocked yes)
			(layer "F.Fab")
			(hide yes)
			(effects
				(font
					(size 1 1)
					(thickness 0.15)
				)
			)
		)
		(property "Author" "Antmicro"
			(at 0 0 90)
			(unlocked yes)
			(layer "F.Fab")
			(hide yes)
			(effects
				(font
					(size 1 1)
					(thickness 0.15)
				)
			)
		)
		(property "Val" "100k"
			(at 0 0 90)
			(unlocked yes)
			(layer "F.Fab")
			(hide yes)
			(effects
				(font
					(size 1 1)
					(thickness 0.15)
				)
			)
		)
		(property "Tolerance" "1%"
			(at 0 0 90)
			(unlocked yes)
			(layer "F.Fab")
			(hide yes)
			(effects
				(font
					(size 1 1)
					(thickness 0.15)
				)
			)
		)
		(sheetname "/Power/")
		(sheetfile "power.kicad_sch")
		(attr smd)
		(fp_rect
			(start -0.925 -0.47)
			(end 0.925 0.47)
			(stroke
				(width 0.05)
				(type default)
			)
			(fill no)
			(layer "F.CrtYd")
		)
		(fp_rect
			(start -0.5 -0.25)
			(end 0.5 0.25)
			(stroke
				(width 0.15)
				(type solid)
			)
			(fill no)
			(layer "F.Fab")
		)
		(pad "1" smd roundrect
			(at -0.48 0 90)
			(size 0.59 0.64)
			(layers "F.Cu" "F.Mask" "F.Paste")
			(roundrect_rratio 0.25)
			(net 341 "/Power/1V0_PG")
			(pintype "passive")
		)
		(pad "2" smd roundrect
			(at 0.48 0 90)
			(size 0.59 0.64)
			(layers "F.Cu" "F.Mask" "F.Paste")
			(roundrect_rratio 0.25)
			(net 328 "/Power/1V0_VCC")
			(pintype "passive")
		)
	)
	(footprint "antmicro-footprints:R_0402_1005Metric"
		(layer "F.Cu")
		(at 81.95 57.771999 180)
		(descr "Resistor SMD 0402")
		(tags "resistor SMD 0402")
		(property "Reference" "R22"
			(at -1.2 -0.560001 0)
			(layer "F.SilkS")
			(effects
				(font
					(size 0.7 0.7)
					(thickness 0.15)
				)
				(justify right top)
			)
		)
		(property "Value" "R_5k1_0402"
			(at -1.011843 1.772046 0)
			(layer "F.Fab")
			(hide yes)
			(effects
				(font
					(size 0.7 0.7)
					(thickness 0.15)
				)
				(justify right top)
			)
		)
		(property "Datasheet" "https://www.bourns.com/docs/product-datasheets/cr.pdf"
			(at 0 0 0)
			(layer "F.Fab")
			(hide yes)
			(effects
				(font
					(size 1.27 1.27)
					(thickness 0.15)
				)
			)
		)
		(property "Description" "SMD Chip Resistor, 5.1 kohm, ± 1%, 63 mW, 0402 [1005 Metric], Thick Film, General Purpose"
			(at 0 0 0)
			(layer "F.Fab")
			(hide yes)
			(effects
				(font
					(size 1.27 1.27)
					(thickness 0.15)
				)
			)
		)
		(property "MPN" "CR0402-FX-5101GLF"
			(at 0 0 180)
			(unlocked yes)
			(layer "F.Fab")
			(hide yes)
			(effects
				(font
					(size 1 1)
					(thickness 0.15)
				)
			)
		)
		(property "Manufacturer" "Bourns"
			(at 0 0 180)
			(unlocked yes)
			(layer "F.Fab")
			(hide yes)
			(effects
				(font
					(size 1 1)
					(thickness 0.15)
				)
			)
		)
		(property "License" "Apache-2.0"
			(at 0 0 180)
			(unlocked yes)
			(layer "F.Fab")
			(hide yes)
			(effects
				(font
					(size 1 1)
					(thickness 0.15)
				)
			)
		)
		(property "Author" "Antmicro"
			(at 0 0 180)
			(unlocked yes)
			(layer "F.Fab")
			(hide yes)
			(effects
				(font
					(size 1 1)
					(thickness 0.15)
				)
			)
		)
		(property "Val" "5k1"
			(at 0 0 180)
			(unlocked yes)
			(layer "F.Fab")
			(hide yes)
			(effects
				(font
					(size 1 1)
					(thickness 0.15)
				)
			)
		)
		(property "Tolerance" "1%"
			(at 0 0 180)
			(unlocked yes)
			(layer "F.Fab")
			(hide yes)
			(effects
				(font
					(size 1 1)
					(thickness 0.15)
				)
			)
		)
		(sheetname "/Power/")
		(sheetfile "power.kicad_sch")
		(attr smd)
		(fp_rect
			(start -0.925 -0.47)
			(end 0.925 0.47)
			(stroke
				(width 0.05)
				(type default)
			)
			(fill no)
			(layer "F.CrtYd")
		)
		(fp_rect
			(start -0.5 -0.25)
			(end 0.5 0.25)
			(stroke
				(width 0.15)
				(type solid)
			)
			(fill no)
			(layer "F.Fab")
		)
		(pad "1" smd roundrect
			(at -0.48 0 180)
			(size 0.59 0.64)
			(layers "F.Cu" "F.Mask" "F.Paste")
			(roundrect_rratio 0.25)
			(net 28 "GND")
			(pintype "passive")
		)
		(pad "2" smd roundrect
			(at 0.48 0 180)
			(size 0.59 0.64)
			(layers "F.Cu" "F.Mask" "F.Paste")
			(roundrect_rratio 0.25)
			(net 356 "/Power/CC2")
			(pintype "passive")
		)
	)
	(footprint "antmicro-footprints:C_0402_1005Metric"
		(layer "F.Cu")
		(at 56.399998 105.500002)
		(descr "Capacitor SMD 0402")
		(tags "capacitor SMD 0402")
		(property "Reference" "C19"
			(at -2.959998 0.369998 0)
			(layer "F.SilkS")
			(effects
				(font
					(size 0.7 0.7)
					(thickness 0.15)
				)
				(justify left bottom)
			)
		)
		(property "Value" "C_100n_0402"
			(at -1.022927 2.155213 0)
			(layer "F.Fab")
			(hide yes)
			(effects
				(font
					(size 0.7 0.7)
					(thickness 0.15)
				)
				(justify left bottom)
			)
		)
		(property "Datasheet" "https://www.murata.com/products/productdetail?partno=GRM155R61H104KE14%23"
			(at 0 0 0)
			(layer "F.Fab")
			(hide yes)
			(effects
				(font
					(size 1.27 1.27)
					(thickness 0.15)
				)
			)
		)
		(property "Description" "SMD Multilayer Ceramic Capacitor, 0.1 µF, 50 V, 0402 [1005 Metric], ± 10%, X5R, GRM Series"
			(at 0 0 0)
			(layer "F.Fab")
			(hide yes)
			(effects
				(font
					(size 1.27 1.27)
					(thickness 0.15)
				)
			)
		)
		(property "MPN" "GRM155R61H104KE14D"
			(at 0 0 0)
			(unlocked yes)
			(layer "F.Fab")
			(hide yes)
			(effects
				(font
					(size 1 1)
					(thickness 0.15)
				)
			)
		)
		(property "Manufacturer" "Murata"
			(at 0 0 0)
			(unlocked yes)
			(layer "F.Fab")
			(hide yes)
			(effects
				(font
					(size 1 1)
					(thickness 0.15)
				)
			)
		)
		(property "License" "Apache-2.0"
			(at 0 0 0)
			(unlocked yes)
			(layer "F.Fab")
			(hide yes)
			(effects
				(font
					(size 1 1)
					(thickness 0.15)
				)
			)
		)
		(property "Author" "Antmicro"
			(at 0 0 0)
			(unlocked yes)
			(layer "F.Fab")
			(hide yes)
			(effects
				(font
					(size 1 1)
					(thickness 0.15)
				)
			)
		)
		(property "Val" "100n"
			(at 0 0 0)
			(unlocked yes)
			(layer "F.Fab")
			(hide yes)
			(effects
				(font
					(size 1 1)
					(thickness 0.15)
				)
			)
		)
		(property "Voltage" "50V"
			(at 0 0 0)
			(unlocked yes)
			(layer "F.Fab")
			(hide yes)
			(effects
				(font
					(size 1 1)
					(thickness 0.15)
				)
			)
		)
		(property "Dielectric" "X5R"
			(at 0 0 0)
			(unlocked yes)
			(layer "F.Fab")
			(hide yes)
			(effects
				(font
					(size 1 1)
					(thickness 0.15)
				)
			)
		)
		(sheetname "/Power/")
		(sheetfile "power.kicad_sch")
		(attr smd)
		(fp_rect
			(start -0.925 -0.47)
			(end 0.925 0.47)
			(stroke
				(width 0.05)
				(type default)
			)
			(fill no)
			(layer "F.CrtYd")
		)
		(fp_line
			(start -0.494 -0.25)
			(end 0.504 -0.25)
			(stroke
				(width 0.15)
				(type solid)
			)
			(layer "F.Fab")
		)
		(fp_line
			(start -0.494 0.248)
			(end -0.494 -0.25)
			(stroke
				(width 0.15)
				(type solid)
			)
			(layer "F.Fab")
		)
		(fp_line
			(start 0.504 -0.25)
			(end 0.504 0.248)
			(stroke
				(width 0.15)
				(type solid)
			)
			(layer "F.Fab")
		)
		(fp_line
			(start 0.504 0.248)
			(end -0.494 0.248)
			(stroke
				(width 0.15)
				(type solid)
			)
			(layer "F.Fab")
		)
		(pad "1" smd roundrect
			(at -0.48 0)
			(size 0.59 0.64)
			(layers "F.Cu" "F.Mask" "F.Paste")
			(roundrect_rratio 0.25)
			(net 323 "/Power/1V88_BST")
			(pintype "passive")
		)
		(pad "2" smd roundrect
			(at 0.48 0)
			(size 0.59 0.64)
			(layers "F.Cu" "F.Mask" "F.Paste")
			(roundrect_rratio 0.25)
			(net 335 "/Power/1V88_SW")
			(pintype "passive")
		)
	)
	(footprint "antmicro-footprints:C_0402_1005Metric"
		(layer "F.Cu")
		(at 57.099999 85.15 -90)
		(descr "Capacitor SMD 0402")
		(tags "capacitor SMD 0402")
		(property "Reference" "C15"
			(at -2.93 -0.330001 90)
			(layer "F.SilkS")
			(effects
				(font
					(size 0.7 0.7)
					(thickness 0.15)
				)
				(justify right top)
			)
		)
		(property "Value" "C_1u_25V_0402"
			(at -1.022927 2.155213 90)
			(layer "F.Fab")
			(hide yes)
			(effects
				(font
					(size 0.7 0.7)
					(thickness 0.15)
				)
				(justify right top)
			)
		)
		(property "Datasheet" "https://www.murata.com/products/productdetail?partno=GRM155R61E105KE11%23"
			(at 0 0 90)
			(layer "F.Fab")
			(hide yes)
			(effects
				(font
					(size 1.27 1.27)
					(thickness 0.15)
				)
			)
		)
		(property "Description" "SMD Multilayer Ceramic Capacitor, 1 µF, 25 V, 0402 [1005 Metric], ± 10%, X5R, GRM Series"
			(at 0 0 90)
			(layer "F.Fab")
			(hide yes)
			(effects
				(font
					(size 1.27 1.27)
					(thickness 0.15)
				)
			)
		)
		(property "MPN" "GRM155R61E105KE11J"
			(at 0 0 270)
			(unlocked yes)
			(layer "F.Fab")
			(hide yes)
			(effects
				(font
					(size 1 1)
					(thickness 0.15)
				)
			)
		)
		(property "Manufacturer" "Murata"
			(at 0 0 270)
			(unlocked yes)
			(layer "F.Fab")
			(hide yes)
			(effects
				(font
					(size 1 1)
					(thickness 0.15)
				)
			)
		)
		(property "License" "Apache-2.0"
			(at 0 0 270)
			(unlocked yes)
			(layer "F.Fab")
			(hide yes)
			(effects
				(font
					(size 1 1)
					(thickness 0.15)
				)
			)
		)
		(property "Author" "Antmicro"
			(at 0 0 270)
			(unlocked yes)
			(layer "F.Fab")
			(hide yes)
			(effects
				(font
					(size 1 1)
					(thickness 0.15)
				)
			)
		)
		(property "Val" "1u"
			(at 0 0 270)
			(unlocked yes)
			(layer "F.Fab")
			(hide yes)
			(effects
				(font
					(size 1 1)
					(thickness 0.15)
				)
			)
		)
		(property "Voltage" "25V"
			(at 0 0 270)
			(unlocked yes)
			(layer "F.Fab")
			(hide yes)
			(effects
				(font
					(size 1 1)
					(thickness 0.15)
				)
			)
		)
		(property "Dielectric" "X5R"
			(at 0 0 270)
			(unlocked yes)
			(layer "F.Fab")
			(hide yes)
			(effects
				(font
					(size 1 1)
					(thickness 0.15)
				)
			)
		)
		(sheetname "/Power/")
		(sheetfile "power.kicad_sch")
		(attr smd)
		(fp_rect
			(start -0.925 -0.47)
			(end 0.925 0.47)
			(stroke
				(width 0.05)
				(type default)
			)
			(fill no)
			(layer "F.CrtYd")
		)
		(fp_line
			(start -0.494 0.248)
			(end -0.494 -0.25)
			(stroke
				(width 0.15)
				(type solid)
			)
			(layer "F.Fab")
		)
		(fp_line
			(start 0.504 0.248)
			(end -0.494 0.248)
			(stroke
				(width 0.15)
				(type solid)
			)
			(layer "F.Fab")
		)
		(fp_line
			(start -0.494 -0.25)
			(end 0.504 -0.25)
			(stroke
				(width 0.15)
				(type solid)
			)
			(layer "F.Fab")
		)
		(fp_line
			(start 0.504 -0.25)
			(end 0.504 0.248)
			(stroke
				(width 0.15)
				(type solid)
			)
			(layer "F.Fab")
		)
		(pad "1" smd roundrect
			(at -0.48 0 270)
			(size 0.59 0.64)
			(layers "F.Cu" "F.Mask" "F.Paste")
			(roundrect_rratio 0.25)
			(net 28 "GND")
			(pintype "passive")
		)
		(pad "2" smd roundrect
			(at 0.48 0 270)
			(size 0.59 0.64)
			(layers "F.Cu" "F.Mask" "F.Paste")
			(roundrect_rratio 0.25)
			(net 322 "/Power/VCCD_VCC")
			(pintype "passive")
		)
	)
	(footprint "antmicro-footprints:C_0603_1608Metric"
		(layer "F.Cu")
		(at 100.450001 101.999998)
		(descr "Capacitor SMD 0603")
		(tags "capacitor 0603")
		(property "Reference" "C159"
			(at 4.249999 0.450002 0)
			(layer "F.SilkS")
			(effects
				(font
					(size 0.7 0.7)
					(thickness 0.15)
				)
				(justify left bottom)
			)
		)
		(property "Value" "C_10u_10V_X7R_0603"
			(at -1.42757 1.770288 0)
			(layer "F.Fab")
			(hide yes)
			(effects
				(font
					(size 0.7 0.7)
					(thickness 0.15)
				)
				(justify left bottom)
			)
		)
		(property "Datasheet" "https://www.murata.com/products/productdetail?partno=GRM188Z71A106KA73%23"
			(at 0 0 0)
			(layer "F.Fab")
			(hide yes)
			(effects
				(font
					(size 1.27 1.27)
					(thickness 0.15)
				)
			)
		)
		(property "Description" "SMD Multilayer Ceramic Capacitor,  10µF, 10V, 0603, ±10%, X7R"
			(at 0 0 0)
			(layer "F.Fab")
			(hide yes)
			(effects
				(font
					(size 1.27 1.27)
					(thickness 0.15)
				)
			)
		)
		(property "MPN" "GRM188Z71A106KA73D"
			(at 0 0 0)
			(unlocked yes)
			(layer "F.Fab")
			(hide yes)
			(effects
				(font
					(size 1 1)
					(thickness 0.15)
				)
			)
		)
		(property "Val" "10u"
			(at 0 0 0)
			(unlocked yes)
			(layer "F.Fab")
			(hide yes)
			(effects
				(font
					(size 1 1)
					(thickness 0.15)
				)
			)
		)
		(property "Voltage" "10V"
			(at 0 0 0)
			(unlocked yes)
			(layer "F.Fab")
			(hide yes)
			(effects
				(font
					(size 1 1)
					(thickness 0.15)
				)
			)
		)
		(property "Dielectric" "X7R"
			(at 0 0 0)
			(unlocked yes)
			(layer "F.Fab")
			(hide yes)
			(effects
				(font
					(size 1 1)
					(thickness 0.15)
				)
			)
		)
		(property "Manufacturer" "Murata"
			(at 0 0 0)
			(unlocked yes)
			(layer "F.Fab")
			(hide yes)
			(effects
				(font
					(size 1 1)
					(thickness 0.15)
				)
			)
		)
		(property "License" "Apache-2.0"
			(at 0 0 0)
			(unlocked yes)
			(layer "F.Fab")
			(hide yes)
			(effects
				(font
					(size 1 1)
					(thickness 0.15)
				)
			)
		)
		(property "Author" "Antmicro"
			(at 0 0 0)
			(unlocked yes)
			(layer "F.Fab")
			(hide yes)
			(effects
				(font
					(size 1 1)
					(thickness 0.15)
				)
			)
		)
		(sheetname "/X710-AT2 power/")
		(sheetfile "x710-at2-power.kicad_sch")
		(attr smd)
		(fp_line
			(start -0.15 -0.4)
			(end 0.15 -0.4)
			(stroke
				(width 0.15)
				(type solid)
			)
			(layer "F.SilkS")
		)
		(fp_line
			(start -0.15 0.4)
			(end 0.15 0.4)
			(stroke
				(width 0.15)
				(type solid)
			)
			(layer "F.SilkS")
		)
		(fp_rect
			(start -1.25 -0.65)
			(end 1.25 0.65)
			(stroke
				(width 0.05)
				(type solid)
			)
			(fill no)
			(layer "F.CrtYd")
		)
		(fp_rect
			(start -0.8 -0.4)
			(end 0.8 0.4)
			(stroke
				(width 0.15)
				(type solid)
			)
			(fill no)
			(layer "F.Fab")
		)
		(pad "1" smd roundrect
			(at -0.7 0)
			(size 0.8 1)
			(layers "F.Cu" "F.Mask" "F.Paste")
			(roundrect_rratio 0.2)
			(net 28 "GND")
			(pintype "passive")
		)
		(pad "2" smd roundrect
			(at 0.7 0)
			(size 0.8 1)
			(layers "F.Cu" "F.Mask" "F.Paste")
			(roundrect_rratio 0.2)
			(net 1 "VCCA")
			(pintype "passive")
		)
	)
	(footprint "antmicro-footprints:L_Bourns-SRP4021HMT"
		(layer "F.Cu")
		(at 60.249999 88.450001 180)
		(property "Reference" "L2"
			(at -3.950001 2.250001 0)
			(layer "F.SilkS")
			(effects
				(font
					(size 0.7 0.7)
					(thickness 0.15)
				)
				(justify right top)
			)
		)
		(property "Value" "L_1u_10A_Bourns-SRP4021HMT"
			(at -2.85 3.4 0)
			(layer "F.Fab")
			(hide yes)
			(effects
				(font
					(size 0.7 0.7)
					(thickness 0.15)
				)
				(justify right top)
			)
		)
		(property "Datasheet" "https://www.mouser.com/datasheet/2/54/Bourns_04_01_2025_SRP4021HMT_Datasheet-3580094.pdf"
			(at 0 0 0)
			(layer "F.Fab")
			(hide yes)
			(effects
				(font
					(size 0.7 0.7)
					(thickness 0.15)
				)
				(justify right top)
			)
		)
		(property "Description" "Power Inductors - SMD Ind,4.1x4.2x1.9mm,1uH+/-20%,10A, Shielded"
			(at 0 0 0)
			(layer "F.Fab")
			(hide yes)
			(effects
				(font
					(size 0.7 0.7)
					(thickness 0.15)
				)
				(justify right top)
			)
		)
		(property "Val" "1u/10A"
			(at 0 0 180)
			(unlocked yes)
			(layer "F.Fab")
			(hide yes)
			(effects
				(font
					(size 1 1)
					(thickness 0.15)
				)
			)
		)
		(property "Manufacturer" "Bourns"
			(at 0 0 180)
			(unlocked yes)
			(layer "F.Fab")
			(hide yes)
			(effects
				(font
					(size 1 1)
					(thickness 0.15)
				)
			)
		)
		(property "MPN" "SRP4021HMT-1R0M"
			(at 0 0 180)
			(unlocked yes)
			(layer "F.Fab")
			(hide yes)
			(effects
				(font
					(size 1 1)
					(thickness 0.15)
				)
			)
		)
		(property "ISat" ""
			(at 0 0 180)
			(unlocked yes)
			(layer "F.Fab")
			(hide yes)
			(effects
				(font
					(size 1 1)
					(thickness 0.15)
				)
			)
		)
		(property "Isat" "8A"
			(at 0 0 180)
			(unlocked yes)
			(layer "F.Fab")
			(hide yes)
			(effects
				(font
					(size 1 1)
					(thickness 0.15)
				)
			)
		)
		(property "IMax" ""
			(at 0 0 180)
			(unlocked yes)
			(layer "F.Fab")
			(hide yes)
			(effects
				(font
					(size 1 1)
					(thickness 0.15)
				)
			)
		)
		(property "Imax" "10A"
			(at 0 0 180)
			(unlocked yes)
			(layer "F.Fab")
			(hide yes)
			(effects
				(font
					(size 1 1)
					(thickness 0.15)
				)
			)
		)
		(property "Size" "4.2x4.1"
			(at 0 0 180)
			(unlocked yes)
			(layer "F.Fab")
			(hide yes)
			(effects
				(font
					(size 1 1)
					(thickness 0.15)
				)
			)
		)
		(property "Author" "Antmicro"
			(at 0 0 180)
			(unlocked yes)
			(layer "F.Fab")
			(hide yes)
			(effects
				(font
					(size 1 1)
					(thickness 0.15)
				)
			)
		)
		(property "License" "Apache-2.0"
			(at 0 0 180)
			(unlocked yes)
			(layer "F.Fab")
			(hide yes)
			(effects
				(font
					(size 1 1)
					(thickness 0.15)
				)
			)
		)
		(sheetname "/Power/")
		(sheetfile "power.kicad_sch")
		(attr smd)
		(fp_line
			(start -0.8 2.05)
			(end 0.8 2.05)
			(stroke
				(width 0.15)
				(type solid)
			)
			(layer "F.SilkS")
		)
		(fp_line
			(start -0.8 -2.05)
			(end 0.8 -2.05)
			(stroke
				(width 0.15)
				(type solid)
			)
			(layer "F.SilkS")
		)
		(fp_rect
			(start -2.85 -2.3)
			(end 2.85 2.3)
			(stroke
				(width 0.05)
				(type solid)
			)
			(fill no)
			(layer "F.CrtYd")
		)
		(fp_rect
			(start -2 -2.05)
			(end 2 2.05)
			(stroke
				(width 0.15)
				(type solid)
			)
			(fill no)
			(layer "F.Fab")
		)
		(pad "1" smd rect
			(at 1.85 0)
			(size 1.5 3.5)
			(layers "F.Cu" "F.Mask" "F.Paste")
			(net 334 "/Power/VCCD_SW")
			(pintype "passive")
		)
		(pad "2" smd rect
			(at -1.85 0)
			(size 1.5 3.5)
			(layers "F.Cu" "F.Mask" "F.Paste")
			(net 303 "/Power/+VCCD_OUT")
			(pintype "passive")
		)
	)
	(footprint "antmicro-footprints:C_0402_1005Metric"
		(layer "F.Cu")
		(at 69.1 96.55 180)
		(descr "Capacitor SMD 0402")
		(tags "capacitor SMD 0402")
		(property "Reference" "C128"
			(at 0.69 0.29 0)
			(layer "F.SilkS")
			(effects
				(font
					(size 0.7 0.7)
					(thickness 0.15)
				)
				(justify right top)
			)
		)
		(property "Value" "C_100n_0402"
			(at -1.022927 2.155213 0)
			(layer "F.Fab")
			(hide yes)
			(effects
				(font
					(size 0.7 0.7)
					(thickness 0.15)
				)
				(justify right top)
			)
		)
		(property "Datasheet" "https://www.murata.com/products/productdetail?partno=GRM155R61H104KE14%23"
			(at 0 0 0)
			(layer "F.Fab")
			(hide yes)
			(effects
				(font
					(size 1.27 1.27)
					(thickness 0.15)
				)
			)
		)
		(property "Description" "SMD Multilayer Ceramic Capacitor, 0.1 µF, 50 V, 0402 [1005 Metric], ± 10%, X5R, GRM Series"
			(at 0 0 0)
			(layer "F.Fab")
			(hide yes)
			(effects
				(font
					(size 1.27 1.27)
					(thickness 0.15)
				)
			)
		)
		(property "MPN" "GRM155R61H104KE14D"
			(at 0 0 180)
			(unlocked yes)
			(layer "F.Fab")
			(hide yes)
			(effects
				(font
					(size 1 1)
					(thickness 0.15)
				)
			)
		)
		(property "Val" "100n"
			(at 0 0 180)
			(unlocked yes)
			(layer "F.Fab")
			(hide yes)
			(effects
				(font
					(size 1 1)
					(thickness 0.15)
				)
			)
		)
		(property "Voltage" "50V"
			(at 0 0 180)
			(unlocked yes)
			(layer "F.Fab")
			(hide yes)
			(effects
				(font
					(size 1 1)
					(thickness 0.15)
				)
			)
		)
		(property "Dielectric" "X5R"
			(at 0 0 180)
			(unlocked yes)
			(layer "F.Fab")
			(hide yes)
			(effects
				(font
					(size 1 1)
					(thickness 0.15)
				)
			)
		)
		(property "Manufacturer" "Murata"
			(at 0 0 180)
			(unlocked yes)
			(layer "F.Fab")
			(hide yes)
			(effects
				(font
					(size 1 1)
					(thickness 0.15)
				)
			)
		)
		(property "License" "Apache-2.0"
			(at 0 0 180)
			(unlocked yes)
			(layer "F.Fab")
			(hide yes)
			(effects
				(font
					(size 1 1)
					(thickness 0.15)
				)
			)
		)
		(property "Author" "Antmicro"
			(at 0 0 180)
			(unlocked yes)
			(layer "F.Fab")
			(hide yes)
			(effects
				(font
					(size 1 1)
					(thickness 0.15)
				)
			)
		)
		(sheetname "/X710-AT2 power/")
		(sheetfile "x710-at2-power.kicad_sch")
		(attr smd)
		(fp_rect
			(start -0.925 -0.47)
			(end 0.925 0.47)
			(stroke
				(width 0.05)
				(type default)
			)
			(fill no)
			(layer "F.CrtYd")
		)
		(fp_line
			(start 0.504 0.248)
			(end -0.494 0.248)
			(stroke
				(width 0.15)
				(type solid)
			)
			(layer "F.Fab")
		)
		(fp_line
			(start 0.504 -0.25)
			(end 0.504 0.248)
			(stroke
				(width 0.15)
				(type solid)
			)
			(layer "F.Fab")
		)
		(fp_line
			(start -0.494 0.248)
			(end -0.494 -0.25)
			(stroke
				(width 0.15)
				(type solid)
			)
			(layer "F.Fab")
		)
		(fp_line
			(start -0.494 -0.25)
			(end 0.504 -0.25)
			(stroke
				(width 0.15)
				(type solid)
			)
			(layer "F.Fab")
		)
		(pad "1" smd roundrect
			(at -0.48 0 180)
			(size 0.59 0.64)
			(layers "F.Cu" "F.Mask" "F.Paste")
			(roundrect_rratio 0.25)
			(net 28 "GND")
			(pintype "passive")
		)
		(pad "2" smd roundrect
			(at 0.48 0 180)
			(size 0.59 0.64)
			(layers "F.Cu" "F.Mask" "F.Paste")
			(roundrect_rratio 0.25)
			(net 18 "+1V88")
			(pintype "passive")
		)
	)
	(footprint "antmicro-footprints:R_0402_1005Metric"
		(layer "F.Cu")
		(at 55.7 80.7 90)
		(descr "Resistor SMD 0402")
		(tags "resistor SMD 0402")
		(property "Reference" "R52"
			(at -1.06 -0.37 90)
			(layer "F.SilkS")
			(effects
				(font
					(size 0.7 0.7)
					(thickness 0.15)
				)
				(justify left bottom)
			)
		)
		(property "Value" "R_8k2_0402"
			(at -1.011843 1.772046 90)
			(layer "F.Fab")
			(hide yes)
			(effects
				(font
					(size 0.7 0.7)
					(thickness 0.15)
				)
				(justify left bottom)
			)
		)
		(property "Datasheet" "https://www.bourns.com/docs/product-datasheets/cr.pdf"
			(at 0 0 90)
			(layer "F.Fab")
			(hide yes)
			(effects
				(font
					(size 1.27 1.27)
					(thickness 0.15)
				)
			)
		)
		(property "Description" "SMD Chip Resistor"
			(at 0 0 90)
			(layer "F.Fab")
			(hide yes)
			(effects
				(font
					(size 1.27 1.27)
					(thickness 0.15)
				)
			)
		)
		(property "MPN" "CR0402-FX-8201GLF"
			(at 0 0 90)
			(unlocked yes)
			(layer "F.Fab")
			(hide yes)
			(effects
				(font
					(size 1 1)
					(thickness 0.15)
				)
			)
		)
		(property "Manufacturer" "Bourns"
			(at 0 0 90)
			(unlocked yes)
			(layer "F.Fab")
			(hide yes)
			(effects
				(font
					(size 1 1)
					(thickness 0.15)
				)
			)
		)
		(property "License" "Apache-2.0"
			(at 0 0 90)
			(unlocked yes)
			(layer "F.Fab")
			(hide yes)
			(effects
				(font
					(size 1 1)
					(thickness 0.15)
				)
			)
		)
		(property "Author" "Antmicro"
			(at 0 0 90)
			(unlocked yes)
			(layer "F.Fab")
			(hide yes)
			(effects
				(font
					(size 1 1)
					(thickness 0.15)
				)
			)
		)
		(property "Val" "8k2"
			(at 0 0 90)
			(unlocked yes)
			(layer "F.Fab")
			(hide yes)
			(effects
				(font
					(size 1 1)
					(thickness 0.15)
				)
			)
		)
		(property "Tolerance" "1%"
			(at 0 0 90)
			(unlocked yes)
			(layer "F.Fab")
			(hide yes)
			(effects
				(font
					(size 1 1)
					(thickness 0.15)
				)
			)
		)
		(sheetname "/X710-AT2 PCIe/")
		(sheetfile "x710-at2-pcie.kicad_sch")
		(attr smd)
		(fp_rect
			(start -0.925 -0.47)
			(end 0.925 0.47)
			(stroke
				(width 0.05)
				(type default)
			)
			(fill no)
			(layer "F.CrtYd")
		)
		(fp_rect
			(start -0.5 -0.25)
			(end 0.5 0.25)
			(stroke
				(width 0.15)
				(type solid)
			)
			(fill no)
			(layer "F.Fab")
		)
		(pad "1" smd roundrect
			(at -0.48 0 90)
			(size 0.59 0.64)
			(layers "F.Cu" "F.Mask" "F.Paste")
			(roundrect_rratio 0.25)
			(net 11 "/X710-AT2 PCIe/PCIe_JTAG.JTDI")
			(pintype "passive")
		)
		(pad "2" smd roundrect
			(at 0.48 0 90)
			(size 0.59 0.64)
			(layers "F.Cu" "F.Mask" "F.Paste")
			(roundrect_rratio 0.25)
			(net 7 "+3V3")
			(pintype "passive")
		)
	)
	(footprint "antmicro-footprints:R_0402_1005Metric"
		(layer "F.Cu")
		(at 56.1 100.55 90)
		(descr "Resistor SMD 0402")
		(tags "resistor SMD 0402")
		(property "Reference" "R15"
			(at -1.64 -2.47 180)
			(layer "F.SilkS")
			(effects
				(font
					(size 0.7 0.7)
					(thickness 0.14)
					(bold yes)
				)
				(justify left bottom)
			)
		)
		(property "Value" "R_63k4_0402"
			(at -1.011843 1.772046 90)
			(layer "F.Fab")
			(hide yes)
			(effects
				(font
					(size 0.7 0.7)
					(thickness 0.15)
				)
				(justify left bottom)
			)
		)
		(property "Datasheet" "https://industrial.panasonic.com/cdbs/www-data/pdf/RDM0000/AOA0000C307.pdf"
			(at 0 0 90)
			(layer "F.Fab")
			(hide yes)
			(effects
				(font
					(size 1.27 1.27)
					(thickness 0.15)
				)
			)
		)
		(property "Description" "SMD Chip Resistor, 63.4 kohm, ± 0.1%, 63 mW, 0402 [1005 Metric], Thin Film,  Precision"
			(at 0 0 90)
			(layer "F.Fab")
			(hide yes)
			(effects
				(font
					(size 1.27 1.27)
					(thickness 0.15)
				)
			)
		)
		(property "MPN" "ERA-2AEB6342X"
			(at 0 0 90)
			(unlocked yes)
			(layer "F.Fab")
			(hide yes)
			(effects
				(font
					(size 1 1)
					(thickness 0.15)
				)
			)
		)
		(property "Manufacturer" "Panasonic"
			(at 0 0 90)
			(unlocked yes)
			(layer "F.Fab")
			(hide yes)
			(effects
				(font
					(size 1 1)
					(thickness 0.15)
				)
			)
		)
		(property "License" "Apache-2.0"
			(at 0 0 90)
			(unlocked yes)
			(layer "F.Fab")
			(hide yes)
			(effects
				(font
					(size 1 1)
					(thickness 0.15)
				)
			)
		)
		(property "Author" "Antmicro"
			(at 0 0 90)
			(unlocked yes)
			(layer "F.Fab")
			(hide yes)
			(effects
				(font
					(size 1 1)
					(thickness 0.15)
				)
			)
		)
		(property "Val" "63k4"
			(at 0 0 90)
			(unlocked yes)
			(layer "F.Fab")
			(hide yes)
			(effects
				(font
					(size 1 1)
					(thickness 0.15)
				)
			)
		)
		(property "Tolerance" "0.1%"
			(at 0 0 90)
			(unlocked yes)
			(layer "F.Fab")
			(hide yes)
			(effects
				(font
					(size 1 1)
					(thickness 0.15)
				)
			)
		)
		(sheetname "/Power/")
		(sheetfile "power.kicad_sch")
		(attr smd)
		(fp_rect
			(start -0.925 -0.47)
			(end 0.925 0.47)
			(stroke
				(width 0.05)
				(type default)
			)
			(fill no)
			(layer "F.CrtYd")
		)
		(fp_rect
			(start -0.5 -0.25)
			(end 0.5 0.25)
			(stroke
				(width 0.15)
				(type solid)
			)
			(fill no)
			(layer "F.Fab")
		)
		(pad "1" smd roundrect
			(at -0.48 0 90)
			(size 0.59 0.64)
			(layers "F.Cu" "F.Mask" "F.Paste")
			(roundrect_rratio 0.25)
			(net 330 "/Power/1V88_FB")
			(pintype "passive")
		)
		(pad "2" smd roundrect
			(at 0.48 0 90)
			(size 0.59 0.64)
			(layers "F.Cu" "F.Mask" "F.Paste")
			(roundrect_rratio 0.25)
			(net 310 "/Power/+1V88_OUT")
			(pintype "passive")
		)
	)
	(footprint "antmicro-footprints:TP_SMD_0.75mm"
		(layer "F.Cu")
		(at 52.050001 121.500001)
		(property "Reference" "TP18"
			(at -2.93 0.5 0)
			(layer "F.SilkS")
			(hide yes)
			(effects
				(font
					(size 0.7 0.7)
					(thickness 0.15)
				)
				(justify left bottom)
			)
		)
		(property "Value" "TP_0.75mm_SMD"
			(at 0 1.2 0)
			(layer "F.Fab")
			(hide yes)
			(effects
				(font
					(size 0.7 0.7)
					(thickness 0.15)
				)
				(justify left bottom)
			)
		)
		(property "Description" "SMT test point"
			(at 0 0 0)
			(layer "F.Fab")
			(hide yes)
			(effects
				(font
					(size 1.27 1.27)
					(thickness 0.15)
				)
			)
		)
		(property "MPN" ""
			(at 0 0 0)
			(unlocked yes)
			(layer "F.Fab")
			(hide yes)
			(effects
				(font
					(size 1 1)
					(thickness 0.15)
				)
			)
		)
		(property "Manufacturer" ""
			(at 0 0 0)
			(unlocked yes)
			(layer "F.Fab")
			(hide yes)
			(effects
				(font
					(size 1 1)
					(thickness 0.15)
				)
			)
		)
		(property "Author" "Antmicro"
			(at 0 0 0)
			(unlocked yes)
			(layer "F.Fab")
			(hide yes)
			(effects
				(font
					(size 1 1)
					(thickness 0.15)
				)
			)
		)
		(property "License" "Apache-2.0"
			(at 0 0 0)
			(unlocked yes)
			(layer "F.Fab")
			(hide yes)
			(effects
				(font
					(size 1 1)
					(thickness 0.15)
				)
			)
		)
		(sheetname "/Power/")
		(sheetfile "power.kicad_sch")
		(attr exclude_from_pos_files exclude_from_bom)
		(fp_circle
			(center 0 0)
			(end 0.475 0)
			(stroke
				(width 0.05)
				(type default)
			)
			(fill no)
			(layer "F.CrtYd")
		)
		(pad "1" smd circle
			(at 0 0)
			(size 0.75 0.75)
			(layers "F.Cu" "F.Mask")
			(net 312 "/Power/+1V0_OUT")
			(pinfunction "1")
			(pintype "passive")
		)
	)
	(footprint "antmicro-footprints:SOT-23-3"
		(layer "F.Cu")
		(at 55.65 72.615 90)
		(property "Reference" "Q1"
			(at -1.8 -1.8 90)
			(layer "F.SilkS")
			(effects
				(font
					(size 0.7 0.7)
					(thickness 0.15)
				)
				(justify left bottom)
			)
		)
		(property "Value" "2N7002_SOT-23-3"
			(at -1.9 2.7 90)
			(layer "F.Fab")
			(hide yes)
			(effects
				(font
					(size 0.7 0.7)
					(thickness 0.15)
				)
				(justify left bottom)
			)
		)
		(property "Datasheet" "https://www.onsemi.com/pub/Collateral/NDS7002A-D.PDF"
			(at 0 0 90)
			(layer "F.Fab")
			(hide yes)
			(effects
				(font
					(size 1.27 1.27)
					(thickness 0.15)
				)
			)
		)
		(property "Description" "Power MOSFET, N Channel, 60 V, 115 mA, 1.2 ohm, SOT-23, Surface Mount"
			(at 0 0 90)
			(layer "F.Fab")
			(hide yes)
			(effects
				(font
					(size 1.27 1.27)
					(thickness 0.15)
				)
			)
		)
		(property "MPN" "2N7002"
			(at 0 0 90)
			(unlocked yes)
			(layer "F.Fab")
			(hide yes)
			(effects
				(font
					(size 1 1)
					(thickness 0.15)
				)
			)
		)
		(property "Manufacturer" "ON Semiconductor"
			(at 0 0 90)
			(unlocked yes)
			(layer "F.Fab")
			(hide yes)
			(effects
				(font
					(size 1 1)
					(thickness 0.15)
				)
			)
		)
		(property "Author" "Antmicro"
			(at 0 0 90)
			(unlocked yes)
			(layer "F.Fab")
			(hide yes)
			(effects
				(font
					(size 1 1)
					(thickness 0.15)
				)
			)
		)
		(property "License" "Apache-2.0"
			(at 0 0 90)
			(unlocked yes)
			(layer "F.Fab")
			(hide yes)
			(effects
				(font
					(size 1 1)
					(thickness 0.15)
				)
			)
		)
		(sheetname "/Power/")
		(sheetfile "power.kicad_sch")
		(attr smd)
		(fp_line
			(start 0.7 -1.5)
			(end -0.7 -1.5)
			(stroke
				(width 0.15)
				(type solid)
			)
			(layer "F.SilkS")
		)
		(fp_line
			(start -0.85 -1.35)
			(end -0.7 -1.5)
			(stroke
				(width 0.15)
				(type solid)
			)
			(layer "F.SilkS")
		)
		(fp_line
			(start -1.45 -1.35)
			(end -0.85 -1.35)
			(stroke
				(width 0.15)
				(type solid)
			)
			(layer "F.SilkS")
		)
		(fp_line
			(start 0.7 -0.4)
			(end 0.7 -1.5)
			(stroke
				(width 0.15)
				(type solid)
			)
			(layer "F.SilkS")
		)
		(fp_line
			(start 0.7 0.4)
			(end 0.7 1.5)
			(stroke
				(width 0.15)
				(type solid)
			)
			(layer "F.SilkS")
		)
		(fp_line
			(start 0.7 1.5)
			(end -0.7 1.5)
			(stroke
				(width 0.15)
				(type solid)
			)
			(layer "F.SilkS")
		)
		(fp_line
			(start -0.7 1.5)
			(end -0.7 1.35)
			(stroke
				(width 0.15)
				(type solid)
			)
			(layer "F.SilkS")
		)
		(fp_line
			(start 0.825 -1.6)
			(end 0.825 -0.45)
			(stroke
				(width 0.05)
				(type solid)
			)
			(layer "F.CrtYd")
		)
		(fp_line
			(start -0.9 -1.6)
			(end 0.825 -1.6)
			(stroke
				(width 0.05)
				(type solid)
			)
			(layer "F.CrtYd")
		)
		(fp_line
			(start -0.9 -1.6)
			(end -0.9 -1.4)
			(stroke
				(width 0.05)
				(type solid)
			)
			(layer "F.CrtYd")
		)
		(fp_line
			(start -0.9 -1.4)
			(end -1.75 -1.4)
			(stroke
				(width 0.05)
				(type solid)
			)
			(layer "F.CrtYd")
		)
		(fp_line
			(start -0.85 -0.5)
			(end -1.75 -0.5)
			(stroke
				(width 0.05)
				(type solid)
			)
			(layer "F.CrtYd")
		)
		(fp_line
			(start -1.75 -0.5)
			(end -1.75 -1.4)
			(stroke
				(width 0.05)
				(type solid)
			)
			(layer "F.CrtYd")
		)
		(fp_line
			(start 1.75 -0.45)
			(end 1.75 0.45)
			(stroke
				(width 0.05)
				(type solid)
			)
			(layer "F.CrtYd")
		)
		(fp_line
			(start 0.825 -0.45)
			(end 1.75 -0.45)
			(stroke
				(width 0.05)
				(type solid)
			)
			(layer "F.CrtYd")
		)
		(fp_line
			(start 1.75 0.45)
			(end 0.85 0.45)
			(stroke
				(width 0.05)
				(type solid)
			)
			(layer "F.CrtYd")
		)
		(fp_line
			(start 0.85 0.45)
			(end 0.85 1.65)
			(stroke
				(width 0.05)
				(type solid)
			)
			(layer "F.CrtYd")
		)
		(fp_line
			(start -0.85 0.5)
			(end -0.85 -0.5)
			(stroke
				(width 0.05)
				(type solid)
			)
			(layer "F.CrtYd")
		)
		(fp_line
			(start -1.75 0.5)
			(end -0.85 0.5)
			(stroke
				(width 0.05)
				(type solid)
			)
			(layer "F.CrtYd")
		)
		(fp_line
			(start -0.85 1.4)
			(end -1.75 1.4)
			(stroke
				(width 0.05)
				(type solid)
			)
			(layer "F.CrtYd")
		)
		(fp_line
			(start -1.75 1.4)
			(end -1.75 0.5)
			(stroke
				(width 0.05)
				(type solid)
			)
			(layer "F.CrtYd")
		)
		(fp_line
			(start 0.85 1.65)
			(end -0.85 1.65)
			(stroke
				(width 0.05)
				(type solid)
			)
			(layer "F.CrtYd")
		)
		(fp_line
			(start -0.85 1.65)
			(end -0.85 1.4)
			(stroke
				(width 0.05)
				(type solid)
			)
			(layer "F.CrtYd")
		)
		(fp_line
			(start -0.437 -1.526)
			(end 0.688 -1.526)
			(stroke
				(width 0.15)
				(type solid)
			)
			(layer "F.Fab")
		)
		(fp_line
			(start -0.437 -1.526)
			(end -0.712 -1.325)
			(stroke
				(width 0.15)
				(type solid)
			)
			(layer "F.Fab")
		)
		(fp_line
			(start -0.712 -1.325)
			(end -0.712 1.523)
			(stroke
				(width 0.15)
				(type solid)
			)
			(layer "F.Fab")
		)
		(fp_line
			(start 0.688 1.519)
			(end 0.688 -1.52)
			(stroke
				(width 0.15)
				(type solid)
			)
			(layer "F.Fab")
		)
		(fp_line
			(start -0.712 1.519)
			(end 0.688 1.519)
			(stroke
				(width 0.15)
				(type solid)
			)
			(layer "F.Fab")
		)
		(pad "1" smd roundrect
			(at -1.1 -0.951 90)
			(size 1 0.6)
			(layers "F.Cu" "F.Mask" "F.Paste")
			(roundrect_rratio 0.15)
			(net 392 "/Power/ALL_RAILS_OK")
			(pinfunction "G")
			(pintype "input")
		)
		(pad "2" smd roundrect
			(at -1.1 0.949 90)
			(size 1 0.6)
			(layers "F.Cu" "F.Mask" "F.Paste")
			(roundrect_rratio 0.15)
			(net 28 "GND")
			(pinfunction "S")
			(pintype "passive")
		)
		(pad "3" smd roundrect
			(at 1.1 -0.0005 90)
			(size 1 0.6)
			(layers "F.Cu" "F.Mask" "F.Paste")
			(roundrect_rratio 0.15)
			(net 393 "/OCuLink/~{CPRSNT}")
			(pinfunction "D")
			(pintype "passive")
		)
	)
	(footprint "antmicro-footprints:SOT-23-6"
		(layer "F.Cu")
		(at 86.35 66 180)
		(property "Reference" "U12"
			(at -1.61 0.21 90)
			(layer "F.SilkS")
			(effects
				(font
					(size 0.7 0.7)
					(thickness 0.15)
				)
				(justify right top)
			)
		)
		(property "Value" "LTC4412IS6"
			(at -1.749999 2.693 0)
			(layer "F.Fab")
			(hide yes)
			(effects
				(font
					(size 0.7 0.7)
					(thickness 0.15)
				)
				(justify right top)
			)
		)
		(property "Datasheet" "https://www.analog.com/media/en/technical-documentation/data-sheets/4412fb.pdf"
			(at 0 -0.057 0)
			(layer "F.Fab")
			(hide yes)
			(effects
				(font
					(size 1.27 1.27)
					(thickness 0.15)
				)
			)
		)
		(property "Description" "Ideal diode controller"
			(at 0 -0.057 0)
			(layer "F.Fab")
			(hide yes)
			(effects
				(font
					(size 1.27 1.27)
					(thickness 0.15)
				)
			)
		)
		(property "MPN" "LTC4412IS6#TRMPBF"
			(at 0 0 180)
			(unlocked yes)
			(layer "F.Fab")
			(hide yes)
			(effects
				(font
					(size 1 1)
					(thickness 0.15)
				)
			)
		)
		(property "Manufacturer" "Analog Devices"
			(at 0 0 180)
			(unlocked yes)
			(layer "F.Fab")
			(hide yes)
			(effects
				(font
					(size 1 1)
					(thickness 0.15)
				)
			)
		)
		(property "Author" "Antmicro"
			(at 0 0 180)
			(unlocked yes)
			(layer "F.Fab")
			(hide yes)
			(effects
				(font
					(size 1 1)
					(thickness 0.15)
				)
			)
		)
		(property "License" "Apache-2.0"
			(at 0 0 180)
			(unlocked yes)
			(layer "F.Fab")
			(hide yes)
			(effects
				(font
					(size 1 1)
					(thickness 0.15)
				)
			)
		)
		(sheetname "/Power/Ideal diode 2/")
		(sheetfile "ideal-diode.kicad_sch")
		(attr smd)
		(fp_line
			(start 1.45 0.643)
			(end 1.45 0.343)
			(stroke
				(width 0.12)
				(type solid)
			)
			(layer "F.SilkS")
		)
		(fp_line
			(start 1.45 -0.757)
			(end 1.45 -0.457)
			(stroke
				(width 0.12)
				(type solid)
			)
			(layer "F.SilkS")
		)
		(fp_line
			(start 1.3 0.643)
			(end 1.45 0.643)
			(stroke
				(width 0.12)
				(type solid)
			)
			(layer "F.SilkS")
		)
		(fp_line
			(start 1.3 -0.757)
			(end 1.45 -0.757)
			(stroke
				(width 0.12)
				(type solid)
			)
			(layer "F.SilkS")
		)
		(fp_line
			(start -1.3 -0.757)
			(end -1.45 -0.757)
			(stroke
				(width 0.12)
				(type solid)
			)
			(layer "F.SilkS")
		)
		(fp_line
			(start -1.45 0.643)
			(end -1.45 0.343)
			(stroke
				(width 0.12)
				(type solid)
			)
			(layer "F.SilkS")
		)
		(fp_line
			(start -1.45 -0.757)
			(end -1.45 -0.457)
			(stroke
				(width 0.12)
				(type solid)
			)
			(layer "F.SilkS")
		)
		(fp_rect
			(start -1.55 -1.85)
			(end 1.55 1.75)
			(stroke
				(width 0.05)
				(type solid)
			)
			(fill no)
			(layer "F.CrtYd")
		)
		(fp_line
			(start 1.5 0.643)
			(end -1.5 0.643)
			(stroke
				(width 0.1)
				(type solid)
			)
			(layer "F.Fab")
		)
		(fp_line
			(start 1.5 -0.757)
			(end 1.5 0.643)
			(stroke
				(width 0.1)
				(type solid)
			)
			(layer "F.Fab")
		)
		(fp_line
			(start -1.5 0.643)
			(end -1.5 -0.757)
			(stroke
				(width 0.1)
				(type solid)
			)
			(layer "F.Fab")
		)
		(fp_line
			(start -1.5 -0.757)
			(end 1.5 -0.757)
			(stroke
				(width 0.1)
				(type solid)
			)
			(layer "F.Fab")
		)
		(fp_text user "."
			(at -1.4 1.46 0)
			(layer "F.SilkS")
			(effects
				(font
					(size 1 1)
					(thickness 0.15)
				)
			)
		)
		(pad "1" smd roundrect
			(at -0.954 1.1 180)
			(size 0.55 1)
			(layers "F.Cu" "F.Mask" "F.Paste")
			(roundrect_rratio 0.15)
			(net 351 "/Power/+5V_USB")
			(pinfunction "IN")
			(pintype "power_in")
		)
		(pad "2" smd roundrect
			(at -0.003 1.1 180)
			(size 0.55 1)
			(layers "F.Cu" "F.Mask" "F.Paste")
			(roundrect_rratio 0.15)
			(net 28 "GND")
			(pinfunction "GND")
			(pintype "power_in")
		)
		(pad "3" smd roundrect
			(at 0.947 1.1 180)
			(size 0.55 1)
			(layers "F.Cu" "F.Mask" "F.Paste")
			(roundrect_rratio 0.15)
			(net 28 "GND")
			(pinfunction "CTL")
			(pintype "input")
		)
		(pad "4" smd roundrect
			(at 0.947 -1.214 180)
			(size 0.55 1)
			(layers "F.Cu" "F.Mask" "F.Paste")
			(roundrect_rratio 0.15)
			(net 375 "unconnected-(U12-STAT-Pad4)")
			(pinfunction "STAT")
			(pintype "output+no_connect")
		)
		(pad "5" smd roundrect
			(at -0.003 -1.214 180)
			(size 0.55 1)
			(layers "F.Cu" "F.Mask" "F.Paste")
			(roundrect_rratio 0.15)
			(net 156 "Net-(Q3-G)")
			(pinfunction "GATE")
			(pintype "output")
		)
		(pad "6" smd roundrect
			(at -0.954 -1.214 180)
			(size 0.55 1)
			(layers "F.Cu" "F.Mask" "F.Paste")
			(roundrect_rratio 0.15)
			(net 314 "VCC")
			(pinfunction "SENSE")
			(pintype "input")
		)
	)
	(footprint "antmicro-footprints:C_0402_1005Metric"
		(layer "F.Cu")
		(at 105.7 112.5)
		(descr "Capacitor SMD 0402")
		(tags "capacitor SMD 0402")
		(property "Reference" "C70"
			(at 0.83 1.45 0)
			(layer "F.SilkS")
			(effects
				(font
					(size 0.7 0.7)
					(thickness 0.15)
				)
				(justify left bottom)
			)
		)
		(property "Value" "C_100n_0402"
			(at -1.022927 2.155213 0)
			(layer "F.Fab")
			(hide yes)
			(effects
				(font
					(size 0.7 0.7)
					(thickness 0.15)
				)
				(justify left bottom)
			)
		)
		(property "Datasheet" "https://www.murata.com/products/productdetail?partno=GRM155R61H104KE14%23"
			(at 0 0 0)
			(layer "F.Fab")
			(hide yes)
			(effects
				(font
					(size 1.27 1.27)
					(thickness 0.15)
				)
			)
		)
		(property "Description" "SMD Multilayer Ceramic Capacitor, 0.1 µF, 50 V, 0402 [1005 Metric], ± 10%, X5R, GRM Series"
			(at 0 0 0)
			(layer "F.Fab")
			(hide yes)
			(effects
				(font
					(size 1.27 1.27)
					(thickness 0.15)
				)
			)
		)
		(property "MPN" "GRM155R61H104KE14D"
			(at 0 0 0)
			(unlocked yes)
			(layer "F.Fab")
			(hide yes)
			(effects
				(font
					(size 1 1)
					(thickness 0.15)
				)
			)
		)
		(property "Val" "100n"
			(at 0 0 0)
			(unlocked yes)
			(layer "F.Fab")
			(hide yes)
			(effects
				(font
					(size 1 1)
					(thickness 0.15)
				)
			)
		)
		(property "Voltage" "50V"
			(at 0 0 0)
			(unlocked yes)
			(layer "F.Fab")
			(hide yes)
			(effects
				(font
					(size 1 1)
					(thickness 0.15)
				)
			)
		)
		(property "Dielectric" "X5R"
			(at 0 0 0)
			(unlocked yes)
			(layer "F.Fab")
			(hide yes)
			(effects
				(font
					(size 1 1)
					(thickness 0.15)
				)
			)
		)
		(property "Manufacturer" "Murata"
			(at 0 0 0)
			(unlocked yes)
			(layer "F.Fab")
			(hide yes)
			(effects
				(font
					(size 1 1)
					(thickness 0.15)
				)
			)
		)
		(property "License" "Apache-2.0"
			(at 0 0 0)
			(unlocked yes)
			(layer "F.Fab")
			(hide yes)
			(effects
				(font
					(size 1 1)
					(thickness 0.15)
				)
			)
		)
		(property "Author" "Antmicro"
			(at 0 0 0)
			(unlocked yes)
			(layer "F.Fab")
			(hide yes)
			(effects
				(font
					(size 1 1)
					(thickness 0.15)
				)
			)
		)
		(sheetname "/X710-AT2 10GbE/")
		(sheetfile "x710-at2-10gbe.kicad_sch")
		(attr smd)
		(fp_rect
			(start -0.925 -0.47)
			(end 0.925 0.47)
			(stroke
				(width 0.05)
				(type default)
			)
			(fill no)
			(layer "F.CrtYd")
		)
		(fp_line
			(start -0.494 -0.25)
			(end 0.504 -0.25)
			(stroke
				(width 0.15)
				(type solid)
			)
			(layer "F.Fab")
		)
		(fp_line
			(start -0.494 0.248)
			(end -0.494 -0.25)
			(stroke
				(width 0.15)
				(type solid)
			)
			(layer "F.Fab")
		)
		(fp_line
			(start 0.504 -0.25)
			(end 0.504 0.248)
			(stroke
				(width 0.15)
				(type solid)
			)
			(layer "F.Fab")
		)
		(fp_line
			(start 0.504 0.248)
			(end -0.494 0.248)
			(stroke
				(width 0.15)
				(type solid)
			)
			(layer "F.Fab")
		)
		(pad "1" smd roundrect
			(at -0.48 0)
			(size 0.59 0.64)
			(layers "F.Cu" "F.Mask" "F.Paste")
			(roundrect_rratio 0.25)
			(net 28 "GND")
			(pintype "passive")
		)
		(pad "2" smd roundrect
			(at 0.48 0)
			(size 0.59 0.64)
			(layers "F.Cu" "F.Mask" "F.Paste")
			(roundrect_rratio 0.25)
			(net 7 "+3V3")
			(pintype "passive")
		)
	)
	(footprint "antmicro-footprints:C_0603_1608Metric_EIA"
		(layer "F.Cu")
		(at 60.649999 85.450002)
		(descr "Capacitor SMD 0603, IPC-7351 Density Level A")
		(tags "Capacitor 0603")
		(property "Reference" "C204"
			(at -1.429999 -1.990002 0)
			(layer "F.SilkS")
			(effects
				(font
					(size 0.7 0.7)
					(thickness 0.15)
				)
				(justify left bottom)
			)
		)
		(property "Value" "C_22u_16V_0603"
			(at -1.42757 1.770288 0)
			(layer "F.Fab")
			(hide yes)
			(effects
				(font
					(size 0.7 0.7)
					(thickness 0.15)
				)
				(justify left bottom)
			)
		)
		(property "Datasheet" "https://product.samsungsem.com/mlcc/CL10A226MO7JZN.do"
			(at 0 0 0)
			(layer "F.Fab")
			(hide yes)
			(effects
				(font
					(size 1.27 1.27)
					(thickness 0.15)
				)
			)
		)
		(property "Description" "SMD Multilayer Ceramic Capacitor"
			(at 0 0 0)
			(layer "F.Fab")
			(hide yes)
			(effects
				(font
					(size 1.27 1.27)
					(thickness 0.15)
				)
			)
		)
		(property "MPN" "CL10A226MO7JZNC"
			(at 0 0 0)
			(unlocked yes)
			(layer "F.Fab")
			(hide yes)
			(effects
				(font
					(size 1 1)
					(thickness 0.15)
				)
			)
		)
		(property "Manufacturer" "Samsung Electro-Mechanics"
			(at 0 0 0)
			(unlocked yes)
			(layer "F.Fab")
			(hide yes)
			(effects
				(font
					(size 1 1)
					(thickness 0.15)
				)
			)
		)
		(property "License" "Apache-2.0"
			(at 0 0 0)
			(unlocked yes)
			(layer "F.Fab")
			(hide yes)
			(effects
				(font
					(size 1 1)
					(thickness 0.15)
				)
			)
		)
		(property "Author" "Antmicro"
			(at 0 0 0)
			(unlocked yes)
			(layer "F.Fab")
			(hide yes)
			(effects
				(font
					(size 1 1)
					(thickness 0.15)
				)
			)
		)
		(property "Val" "22u"
			(at 0 0 0)
			(unlocked yes)
			(layer "F.Fab")
			(hide yes)
			(effects
				(font
					(size 1 1)
					(thickness 0.15)
				)
			)
		)
		(property "Voltage" "16V"
			(at 0 0 0)
			(unlocked yes)
			(layer "F.Fab")
			(hide yes)
			(effects
				(font
					(size 1 1)
					(thickness 0.15)
				)
			)
		)
		(property "Dielectric" ""
			(at 0 0 0)
			(unlocked yes)
			(layer "F.Fab")
			(hide yes)
			(effects
				(font
					(size 1 1)
					(thickness 0.15)
				)
			)
		)
		(property "Public" "False"
			(at 0 0 0)
			(unlocked yes)
			(layer "F.Fab")
			(hide yes)
			(effects
				(font
					(size 1 1)
					(thickness 0.15)
				)
			)
		)
		(sheetname "/Power/")
		(sheetfile "power.kicad_sch")
		(attr smd)
		(fp_line
			(start -0.15 -0.55)
			(end 0.15 -0.55)
			(stroke
				(width 0.15)
				(type solid)
			)
			(layer "F.SilkS")
		)
		(fp_line
			(start -0.15 0.55)
			(end 0.15 0.55)
			(stroke
				(width 0.15)
				(type solid)
			)
			(layer "F.SilkS")
		)
		(fp_rect
			(start -1.25 -0.65)
			(end 1.25 0.65)
			(stroke
				(width 0.05)
				(type solid)
			)
			(fill no)
			(layer "F.CrtYd")
		)
		(fp_rect
			(start -0.8 -0.45)
			(end 0.8 0.45)
			(stroke
				(width 0.15)
				(type solid)
			)
			(fill no)
			(layer "F.Fab")
		)
		(pad "1" smd roundrect
			(at -0.7 0)
			(size 0.8 1.1)
			(layers "F.Cu" "F.Mask" "F.Paste")
			(roundrect_rratio 0.2)
			(net 28 "GND")
			(pintype "passive")
		)
		(pad "2" smd roundrect
			(at 0.7 0)
			(size 0.8 1.1)
			(layers "F.Cu" "F.Mask" "F.Paste")
			(roundrect_rratio 0.2)
			(net 303 "/Power/+VCCD_OUT")
			(pintype "passive")
		)
	)
	(footprint "antmicro-footprints:R_0402_1005Metric"
		(layer "F.Cu")
		(at 109.15 100.1 -90)
		(descr "Resistor SMD 0402")
		(tags "resistor SMD 0402")
		(property "Reference" "R182"
			(at -0.8 -0.45 90)
			(layer "F.SilkS")
			(effects
				(font
					(size 0.7 0.7)
					(thickness 0.15)
				)
				(justify left bottom)
			)
		)
		(property "Value" "R_6k04_0.1%_0402"
			(at -1.011843 1.772046 90)
			(layer "F.Fab")
			(hide yes)
			(effects
				(font
					(size 0.7 0.7)
					(thickness 0.15)
				)
				(justify right top)
			)
		)
		(property "Datasheet" "https://www.vishay.com/docs/28758/tnpw_e3.pdf"
			(at 0 0 90)
			(layer "F.Fab")
			(hide yes)
			(effects
				(font
					(size 1.27 1.27)
					(thickness 0.15)
				)
			)
		)
		(property "Description" "SMD Chip Resistor, 6.49 kohm, ± 1%, 62.5 mW, 0402 [1005 Metric], Thick Film, General Purpose"
			(at 0 0 90)
			(layer "F.Fab")
			(hide yes)
			(effects
				(font
					(size 1.27 1.27)
					(thickness 0.15)
				)
			)
		)
		(property "MPN" "TNPW04026K04BEED"
			(at 0 0 270)
			(unlocked yes)
			(layer "F.Fab")
			(hide yes)
			(effects
				(font
					(size 1 1)
					(thickness 0.15)
				)
			)
		)
		(property "Manufacturer" "Vishay"
			(at 0 0 270)
			(unlocked yes)
			(layer "F.Fab")
			(hide yes)
			(effects
				(font
					(size 1 1)
					(thickness 0.15)
				)
			)
		)
		(property "License" "Apache-2.0"
			(at 0 0 270)
			(unlocked yes)
			(layer "F.Fab")
			(hide yes)
			(effects
				(font
					(size 1 1)
					(thickness 0.15)
				)
			)
		)
		(property "Author" "Antmicro"
			(at 0 0 270)
			(unlocked yes)
			(layer "F.Fab")
			(hide yes)
			(effects
				(font
					(size 1 1)
					(thickness 0.15)
				)
			)
		)
		(property "Val" "6k04"
			(at 0 0 270)
			(unlocked yes)
			(layer "F.Fab")
			(hide yes)
			(effects
				(font
					(size 1 1)
					(thickness 0.15)
				)
			)
		)
		(property "Tolerance" "0.1%"
			(at 0 0 270)
			(unlocked yes)
			(layer "F.Fab")
			(hide yes)
			(effects
				(font
					(size 1 1)
					(thickness 0.15)
				)
			)
		)
		(sheetname "/Fan controller/")
		(sheetfile "fan-controller.kicad_sch")
		(attr smd exclude_from_pos_files exclude_from_bom dnp)
		(fp_rect
			(start -0.925 -0.47)
			(end 0.925 0.47)
			(stroke
				(width 0.05)
				(type default)
			)
			(fill no)
			(layer "F.CrtYd")
		)
		(fp_rect
			(start -0.5 -0.25)
			(end 0.5 0.25)
			(stroke
				(width 0.15)
				(type solid)
			)
			(fill no)
			(layer "F.Fab")
		)
		(pad "1" smd roundrect
			(at -0.48 0 270)
			(size 0.59 0.64)
			(layers "F.Cu" "F.Mask" "F.Paste")
			(roundrect_rratio 0.25)
			(net 397 "Net-(R175-Pad1)")
			(pintype "passive")
		)
		(pad "2" smd roundrect
			(at 0.48 0 270)
			(size 0.59 0.64)
			(layers "F.Cu" "F.Mask" "F.Paste")
			(roundrect_rratio 0.25)
			(net 388 "/Fan controller/+5V")
			(pintype "passive")
		)
	)
	(footprint "antmicro-footprints:C_0402_1005Metric"
		(layer "F.Cu")
		(at 82.25 84.15)
		(descr "Capacitor SMD 0402")
		(tags "capacitor SMD 0402")
		(property "Reference" "C198"
			(at 0.8 0.5 0)
			(layer "F.SilkS")
			(effects
				(font
					(size 0.7 0.7)
					(thickness 0.15)
				)
				(justify left bottom)
			)
		)
		(property "Value" "C_100n_0402"
			(at -1.022927 2.155213 0)
			(layer "F.Fab")
			(hide yes)
			(effects
				(font
					(size 0.7 0.7)
					(thickness 0.15)
				)
				(justify left bottom)
			)
		)
		(property "Datasheet" "https://www.murata.com/products/productdetail?partno=GRM155R61H104KE14%23"
			(at 0 0 0)
			(layer "F.Fab")
			(hide yes)
			(effects
				(font
					(size 1.27 1.27)
					(thickness 0.15)
				)
			)
		)
		(property "Description" "SMD Multilayer Ceramic Capacitor, 0.1 µF, 50 V, 0402 [1005 Metric], ± 10%, X5R, GRM Series"
			(at 0 0 0)
			(layer "F.Fab")
			(hide yes)
			(effects
				(font
					(size 1.27 1.27)
					(thickness 0.15)
				)
			)
		)
		(property "MPN" "GRM155R61H104KE14D"
			(at 0 0 0)
			(unlocked yes)
			(layer "F.Fab")
			(hide yes)
			(effects
				(font
					(size 1 1)
					(thickness 0.15)
				)
			)
		)
		(property "Val" "100n"
			(at 0 0 0)
			(unlocked yes)
			(layer "F.Fab")
			(hide yes)
			(effects
				(font
					(size 1 1)
					(thickness 0.15)
				)
			)
		)
		(property "Voltage" "50V"
			(at 0 0 0)
			(unlocked yes)
			(layer "F.Fab")
			(hide yes)
			(effects
				(font
					(size 1 1)
					(thickness 0.15)
				)
			)
		)
		(property "Dielectric" "X5R"
			(at 0 0 0)
			(unlocked yes)
			(layer "F.Fab")
			(hide yes)
			(effects
				(font
					(size 1 1)
					(thickness 0.15)
				)
			)
		)
		(property "Manufacturer" "Murata"
			(at 0 0 0)
			(unlocked yes)
			(layer "F.Fab")
			(hide yes)
			(effects
				(font
					(size 1 1)
					(thickness 0.15)
				)
			)
		)
		(property "License" "Apache-2.0"
			(at 0 0 0)
			(unlocked yes)
			(layer "F.Fab")
			(hide yes)
			(effects
				(font
					(size 1 1)
					(thickness 0.15)
				)
			)
		)
		(property "Author" "Antmicro"
			(at 0 0 0)
			(unlocked yes)
			(layer "F.Fab")
			(hide yes)
			(effects
				(font
					(size 1 1)
					(thickness 0.15)
				)
			)
		)
		(sheetname "/X710-AT2 Misc/")
		(sheetfile "x710-at2-mics.kicad_sch")
		(attr smd)
		(fp_rect
			(start -0.925 -0.47)
			(end 0.925 0.47)
			(stroke
				(width 0.05)
				(type default)
			)
			(fill no)
			(layer "F.CrtYd")
		)
		(fp_line
			(start -0.494 -0.25)
			(end 0.504 -0.25)
			(stroke
				(width 0.15)
				(type solid)
			)
			(layer "F.Fab")
		)
		(fp_line
			(start -0.494 0.248)
			(end -0.494 -0.25)
			(stroke
				(width 0.15)
				(type solid)
			)
			(layer "F.Fab")
		)
		(fp_line
			(start 0.504 -0.25)
			(end 0.504 0.248)
			(stroke
				(width 0.15)
				(type solid)
			)
			(layer "F.Fab")
		)
		(fp_line
			(start 0.504 0.248)
			(end -0.494 0.248)
			(stroke
				(width 0.15)
				(type solid)
			)
			(layer "F.Fab")
		)
		(pad "1" smd roundrect
			(at -0.48 0)
			(size 0.59 0.64)
			(layers "F.Cu" "F.Mask" "F.Paste")
			(roundrect_rratio 0.25)
			(net 28 "GND")
			(pintype "passive")
		)
		(pad "2" smd roundrect
			(at 0.48 0)
			(size 0.59 0.64)
			(layers "F.Cu" "F.Mask" "F.Paste")
			(roundrect_rratio 0.25)
			(net 78 "Net-(U10-VCC)")
			(pintype "passive")
		)
	)
	(footprint "antmicro-footprints:C_0402_1005Metric"
		(layer "F.Cu")
		(at 70.499998 78.339995 180)
		(descr "Capacitor SMD 0402")
		(tags "capacitor SMD 0402")
		(property "Reference" "C5"
			(at -2.230002 0.309995 0)
			(layer "F.SilkS")
			(effects
				(font
					(size 0.7 0.7)
					(thickness 0.15)
				)
				(justify right top)
			)
		)
		(property "Value" "C_100n_0402"
			(at -1.022927 2.155213 0)
			(layer "F.Fab")
			(hide yes)
			(effects
				(font
					(size 0.7 0.7)
					(thickness 0.15)
				)
				(justify right top)
			)
		)
		(property "Datasheet" "https://www.murata.com/products/productdetail?partno=GRM155R61H104KE14%23"
			(at 0 0 0)
			(layer "F.Fab")
			(hide yes)
			(effects
				(font
					(size 1.27 1.27)
					(thickness 0.15)
				)
			)
		)
		(property "Description" "SMD Multilayer Ceramic Capacitor, 0.1 µF, 50 V, 0402 [1005 Metric], ± 10%, X5R, GRM Series"
			(at 0 0 0)
			(layer "F.Fab")
			(hide yes)
			(effects
				(font
					(size 1.27 1.27)
					(thickness 0.15)
				)
			)
		)
		(property "MPN" "GRM155R61H104KE14D"
			(at 0 0 180)
			(unlocked yes)
			(layer "F.Fab")
			(hide yes)
			(effects
				(font
					(size 1 1)
					(thickness 0.15)
				)
			)
		)
		(property "Manufacturer" "Murata"
			(at 0 0 180)
			(unlocked yes)
			(layer "F.Fab")
			(hide yes)
			(effects
				(font
					(size 1 1)
					(thickness 0.15)
				)
			)
		)
		(property "License" "Apache-2.0"
			(at 0 0 180)
			(unlocked yes)
			(layer "F.Fab")
			(hide yes)
			(effects
				(font
					(size 1 1)
					(thickness 0.15)
				)
			)
		)
		(property "Author" "Antmicro"
			(at 0 0 180)
			(unlocked yes)
			(layer "F.Fab")
			(hide yes)
			(effects
				(font
					(size 1 1)
					(thickness 0.15)
				)
			)
		)
		(property "Val" "100n"
			(at 0 0 180)
			(unlocked yes)
			(layer "F.Fab")
			(hide yes)
			(effects
				(font
					(size 1 1)
					(thickness 0.15)
				)
			)
		)
		(property "Voltage" "50V"
			(at 0 0 180)
			(unlocked yes)
			(layer "F.Fab")
			(hide yes)
			(effects
				(font
					(size 1 1)
					(thickness 0.15)
				)
			)
		)
		(property "Dielectric" "X5R"
			(at 0 0 180)
			(unlocked yes)
			(layer "F.Fab")
			(hide yes)
			(effects
				(font
					(size 1 1)
					(thickness 0.15)
				)
			)
		)
		(sheetname "/Power/")
		(sheetfile "power.kicad_sch")
		(attr smd)
		(fp_rect
			(start -0.925 -0.47)
			(end 0.925 0.47)
			(stroke
				(width 0.05)
				(type default)
			)
			(fill no)
			(layer "F.CrtYd")
		)
		(fp_line
			(start 0.504 0.248)
			(end -0.494 0.248)
			(stroke
				(width 0.15)
				(type solid)
			)
			(layer "F.Fab")
		)
		(fp_line
			(start 0.504 -0.25)
			(end 0.504 0.248)
			(stroke
				(width 0.15)
				(type solid)
			)
			(layer "F.Fab")
		)
		(fp_line
			(start -0.494 0.248)
			(end -0.494 -0.25)
			(stroke
				(width 0.15)
				(type solid)
			)
			(layer "F.Fab")
		)
		(fp_line
			(start -0.494 -0.25)
			(end 0.504 -0.25)
			(stroke
				(width 0.15)
				(type solid)
			)
			(layer "F.Fab")
		)
		(pad "1" smd roundrect
			(at -0.48 0 180)
			(size 0.59 0.64)
			(layers "F.Cu" "F.Mask" "F.Paste")
			(roundrect_rratio 0.25)
			(net 28 "GND")
			(pintype "passive")
		)
		(pad "2" smd roundrect
			(at 0.48 0 180)
			(size 0.59 0.64)
			(layers "F.Cu" "F.Mask" "F.Paste")
			(roundrect_rratio 0.25)
			(net 314 "VCC")
			(pintype "passive")
		)
	)
	(footprint "antmicro-footprints:C_0603_1608Metric_EIA"
		(layer "F.Cu")
		(at 66.7 84.900001 180)
		(descr "Capacitor SMD 0603, IPC-7351 Density Level A")
		(tags "Capacitor 0603")
		(property "Reference" "C122"
			(at -1.98 5.110001 0)
			(layer "F.SilkS")
			(effects
				(font
					(size 0.7 0.7)
					(thickness 0.15)
				)
				(justify right top)
			)
		)
		(property "Value" "C_22u_16V_0603"
			(at -1.42757 1.770288 0)
			(layer "F.Fab")
			(hide yes)
			(effects
				(font
					(size 0.7 0.7)
					(thickness 0.15)
				)
				(justify right top)
			)
		)
		(property "Datasheet" "https://product.samsungsem.com/mlcc/CL10A226MO7JZN.do"
			(at 0 0 0)
			(layer "F.Fab")
			(hide yes)
			(effects
				(font
					(size 1.27 1.27)
					(thickness 0.15)
				)
			)
		)
		(property "Description" "SMD Multilayer Ceramic Capacitor"
			(at 0 0 0)
			(layer "F.Fab")
			(hide yes)
			(effects
				(font
					(size 1.27 1.27)
					(thickness 0.15)
				)
			)
		)
		(property "MPN" "CL10A226MO7JZNC"
			(at 0 0 180)
			(unlocked yes)
			(layer "F.Fab")
			(hide yes)
			(effects
				(font
					(size 1 1)
					(thickness 0.15)
				)
			)
		)
		(property "Manufacturer" "Samsung Electro-Mechanics"
			(at 0 0 180)
			(unlocked yes)
			(layer "F.Fab")
			(hide yes)
			(effects
				(font
					(size 1 1)
					(thickness 0.15)
				)
			)
		)
		(property "License" "Apache-2.0"
			(at 0 0 180)
			(unlocked yes)
			(layer "F.Fab")
			(hide yes)
			(effects
				(font
					(size 1 1)
					(thickness 0.15)
				)
			)
		)
		(property "Author" "Antmicro"
			(at 0 0 180)
			(unlocked yes)
			(layer "F.Fab")
			(hide yes)
			(effects
				(font
					(size 1 1)
					(thickness 0.15)
				)
			)
		)
		(property "Val" "22u"
			(at 0 0 180)
			(unlocked yes)
			(layer "F.Fab")
			(hide yes)
			(effects
				(font
					(size 1 1)
					(thickness 0.15)
				)
			)
		)
		(property "Voltage" "16V"
			(at 0 0 180)
			(unlocked yes)
			(layer "F.Fab")
			(hide yes)
			(effects
				(font
					(size 1 1)
					(thickness 0.15)
				)
			)
		)
		(property "Dielectric" ""
			(at 0 0 180)
			(unlocked yes)
			(layer "F.Fab")
			(hide yes)
			(effects
				(font
					(size 1 1)
					(thickness 0.15)
				)
			)
		)
		(sheetname "/X710-AT2 power/")
		(sheetfile "x710-at2-power.kicad_sch")
		(attr smd)
		(fp_line
			(start -0.15 0.55)
			(end 0.15 0.55)
			(stroke
				(width 0.15)
				(type solid)
			)
			(layer "F.SilkS")
		)
		(fp_line
			(start -0.15 -0.55)
			(end 0.15 -0.55)
			(stroke
				(width 0.15)
				(type solid)
			)
			(layer "F.SilkS")
		)
		(fp_rect
			(start -1.25 -0.65)
			(end 1.25 0.65)
			(stroke
				(width 0.05)
				(type solid)
			)
			(fill no)
			(layer "F.CrtYd")
		)
		(fp_rect
			(start -0.8 -0.45)
			(end 0.8 0.45)
			(stroke
				(width 0.15)
				(type solid)
			)
			(fill no)
			(layer "F.Fab")
		)
		(pad "1" smd roundrect
			(at -0.7 0 180)
			(size 0.8 1.1)
			(layers "F.Cu" "F.Mask" "F.Paste")
			(roundrect_rratio 0.2)
			(net 28 "GND")
			(pintype "passive")
		)
		(pad "2" smd roundrect
			(at 0.7 0 180)
			(size 0.8 1.1)
			(layers "F.Cu" "F.Mask" "F.Paste")
			(roundrect_rratio 0.2)
			(net 9 "VCCD")
			(pintype "passive")
		)
	)
	(footprint "antmicro-footprints:Heatsink_ATS-61500R-C2-R0"
		(locked yes)
		(layer "F.Cu")
		(at 84.975 100 90)
		(property "Reference" "H1"
			(at -23.081282 26.535 90)
			(unlocked yes)
			(layer "F.SilkS")
			(effects
				(font
					(size 0.7 0.7)
					(thickness 0.15)
				)
				(justify left bottom)
			)
		)
		(property "Value" "Heatsink_ATS-61500R-C2-R0"
			(at -22.27 -17.825 90)
			(unlocked yes)
			(layer "F.Fab")
			(hide yes)
			(effects
				(font
					(size 0.7 0.7)
					(thickness 0.15)
				)
				(justify left bottom)
			)
		)
		(property "Datasheet" "https://www.qats.com/DataSheet/ATS-61500-Series-C2-R0"
			(at 0 0 90)
			(layer "F.Fab")
			(hide yes)
			(effects
				(font
					(size 1.27 1.27)
					(thickness 0.15)
				)
			)
		)
		(property "Description" "Heat Sinks fanSINK Assembly with Mounting Hardware"
			(at 0 0 90)
			(layer "F.Fab")
			(hide yes)
			(effects
				(font
					(size 1.27 1.27)
					(thickness 0.15)
				)
			)
		)
		(property "MPN" "ATS-61500R-C2-R0"
			(at 0 0 90)
			(unlocked yes)
			(layer "F.Fab")
			(hide yes)
			(effects
				(font
					(size 1 1)
					(thickness 0.15)
				)
			)
		)
		(property "Manufacturer" "Advanced Thermal Solutions"
			(at 0 0 90)
			(unlocked yes)
			(layer "F.Fab")
			(hide yes)
			(effects
				(font
					(size 1 1)
					(thickness 0.15)
				)
			)
		)
		(property "Author" "Antmicro"
			(at 0 0 90)
			(unlocked yes)
			(layer "F.Fab")
			(hide yes)
			(effects
				(font
					(size 1 1)
					(thickness 0.15)
				)
			)
		)
		(property "License" "Apache-2.0"
			(at 0 0 90)
			(unlocked yes)
			(layer "F.Fab")
			(hide yes)
			(effects
				(font
					(size 1 1)
					(thickness 0.15)
				)
			)
		)
		(property ki_fp_filters "Heatsink_*")
		(sheetname "/")
		(sheetfile "oculink-to-10gbe-adapter.kicad_sch")
		(attr exclude_from_pos_files exclude_from_bom dnp)
		(fp_circle
			(center 22 -22)
			(end 26.22 -22)
			(stroke
				(width 0.05)
				(type solid)
			)
			(fill no)
			(layer "F.CrtYd")
		)
		(fp_circle
			(center -22 -22)
			(end -17.78 -22)
			(stroke
				(width 0.05)
				(type solid)
			)
			(fill no)
			(layer "F.CrtYd")
		)
		(fp_circle
			(center 22 22)
			(end 26.22 22)
			(stroke
				(width 0.05)
				(type solid)
			)
			(fill no)
			(layer "F.CrtYd")
		)
		(fp_circle
			(center -22 22)
			(end -17.78 22)
			(stroke
				(width 0.05)
				(type solid)
			)
			(fill no)
			(layer "F.CrtYd")
		)
		(zone
			(net 0)
			(net_name "")
			(layers "F.Cu" "B.Cu" "In1.Cu" "In2.Cu" "In3.Cu" "In4.Cu" "In5.Cu" "In6.Cu")
			(hatch edge 0.5)
			(connect_pads
				(clearance 0)
			)
			(min_thickness 0.25)
			(filled_areas_thickness no)
			(keepout
				(tracks not_allowed)
				(vias not_allowed)
				(pads allowed)
				(copperpour not_allowed)
				(footprints allowed)
			)
			(placement
				(enabled no)
				(sheetname "")
			)
			(fill
				(thermal_gap 0.5)
				(thermal_bridge_width 0.5)
			)
			(polygon
				(pts
					(xy 62.95963 75.979643) (xy 62.675 76) (xy 62.396165 76.060657) (xy 62.1288 76.160379) (xy 61.878348 76.297136)
					(xy 61.649909 76.468144) (xy 61.448131 76.669922) (xy 61.277123 76.898361) (xy 61.140366 77.148813)
					(xy 61.040644 77.416178) (xy 60.979987 77.695013) (xy 60.95963 77.979643) (xy 60.979987 78.264273)
					(xy 61.040644 78.543108) (xy 61.140366 78.810473) (xy 61.277123 79.060925) (xy 61.448131 79.289364)
					(xy 61.649909 79.491142) (xy 61.878348 79.66215) (xy 62.1288 79.798907) (xy 62.396165 79.898629)
					(xy 62.675 79.959286) (xy 62.95963 79.979643) (xy 63.24426 79.959286) (xy 63.523095 79.898629)
					(xy 63.79046 79.798907) (xy 64.040912 79.66215) (xy 64.269351 79.491142) (xy 64.471129 79.289364)
					(xy 64.642137 79.060925) (xy 64.778894 78.810473) (xy 64.878616 78.543108) (xy 64.939273 78.264273)
					(xy 64.95963 77.979643) (xy 64.939273 77.695013) (xy 64.878616 77.416178) (xy 64.778894 77.148813)
					(xy 64.642137 76.898361) (xy 64.471129 76.669922) (xy 64.269351 76.468144) (xy 64.040912 76.297136)
					(xy 63.79046 76.160379) (xy 63.523095 76.060657) (xy 63.24426 76)
				)
			)
		)
		(zone
			(net 0)
			(net_name "")
			(layers "F.Cu" "B.Cu" "In1.Cu" "In2.Cu" "In3.Cu" "In4.Cu" "In5.Cu" "In6.Cu")
			(hatch edge 0.5)
			(connect_pads
				(clearance 0)
			)
			(min_thickness 0.25)
			(filled_areas_thickness no)
			(keepout
				(tracks not_allowed)
				(vias not_allowed)
				(pads allowed)
				(copperpour not_allowed)
				(footprints allowed)
			)
			(placement
				(enabled no)
				(sheetname "")
			)
			(fill
				(thermal_gap 0.5)
				(thermal_bridge_width 0.5)
			)
			(polygon
				(pts
					(xy 62.975 120) (xy 62.69037 120.020357) (xy 62.411535 120.081014) (xy 62.14417 120.180736) (xy 61.893718 120.317493)
					(xy 61.665279 120.488501) (xy 61.463501 120.690279) (xy 61.292493 120.918718) (xy 61.155736 121.16917)
					(xy 61.056014 121.436535) (xy 60.995357 121.71537) (xy 60.975 122) (xy 60.995357 122.28463) (xy 61.056014 122.563465)
					(xy 61.155736 122.83083) (xy 61.292493 123.081282) (xy 61.463501 123.309721) (xy 61.665279 123.511499)
					(xy 61.893718 123.682507) (xy 62.14417 123.819264) (xy 62.411535 123.918986) (xy 62.69037 123.979643)
					(xy 62.975 124) (xy 63.25963 123.979643) (xy 63.538465 123.918986) (xy 63.80583 123.819264) (xy 64.056282 123.682507)
					(xy 64.284721 123.511499) (xy 64.486499 123.309721) (xy 64.657507 123.081282) (xy 64.794264 122.83083)
					(xy 64.893986 122.563465) (xy 64.954643 122.28463) (xy 64.975 122) (xy 64.954643 121.71537) (xy 64.893986 121.436535)
					(xy 64.794264 121.16917) (xy 64.657507 120.918718) (xy 64.486499 120.690279) (xy 64.284721 120.488501)
					(xy 64.056282 120.317493) (xy 63.80583 120.180736) (xy 63.538465 120.081014) (xy 63.25963 120.020357)
				)
			)
		)
		(zone
			(net 0)
			(net_name "")
			(layers "F.Cu" "B.Cu" "In1.Cu" "In2.Cu" "In3.Cu" "In4.Cu" "In5.Cu" "In6.Cu")
			(hatch edge 0.5)
			(connect_pads
				(clearance 0)
			)
			(min_thickness 0.25)
			(filled_areas_thickness no)
			(keepout
				(tracks not_allowed)
				(vias not_allowed)
				(pads allowed)
				(copperpour not_allowed)
				(footprints allowed)
			)
			(placement
				(enabled no)
				(sheetname "")
			)
			(fill
				(thermal_gap 0.5)
				(thermal_bridge_width 0.5)
			)
			(polygon
				(pts
					(xy 106.956014 75.982507) (xy 106.671384 76.002864) (xy 106.392549 76.063521) (xy 106.125184 76.163243)
					(xy 105.874732 76.3) (xy 105.646293 76.471008) (xy 105.444515 76.672786) (xy 105.273507 76.901225)
					(xy 105.13675 77.151677) (xy 105.037028 77.419042) (xy 104.976371 77.697877) (xy 104.956014 77.982507)
					(xy 104.976371 78.267137) (xy 105.037028 78.545972) (xy 105.13675 78.813337) (xy 105.273507 79.063789)
					(xy 105.444515 79.292228) (xy 105.646293 79.494006) (xy 105.874732 79.665014) (xy 106.125184 79.801771)
					(xy 106.392549 79.901493) (xy 106.671384 79.96215) (xy 106.956014 79.982507) (xy 107.240644 79.96215)
					(xy 107.519479 79.901493) (xy 107.786844 79.801771) (xy 108.037296 79.665014) (xy 108.265735 79.494006)
					(xy 108.467513 79.292228) (xy 108.638521 79.063789) (xy 108.775278 78.813337) (xy 108.875 78.545972)
					(xy 108.935657 78.267137) (xy 108.956014 77.982507) (xy 108.935657 77.697877) (xy 108.875 77.419042)
					(xy 108.775278 77.151677) (xy 108.638521 76.901225) (xy 108.467513 76.672786) (xy 108.265735 76.471008)
					(xy 108.037296 76.3) (xy 107.786844 76.163243) (xy 107.519479 76.063521) (xy 107.240644 76.002864)
				)
			)
		)
		(zone
			(net 0)
			(net_name "")
			(layers "F.Cu" "B.Cu" "In1.Cu" "In2.Cu" "In3.Cu" "In4.Cu" "In5.Cu" "In6.Cu")
			(hatch edge 0.5)
			(connect_pads
				(clearance 0)
			)
			(min_thickness 0.25)
			(filled_areas_thickness no)
			(keepout
				(tracks not_allowed)
				(vias not_allowed)
				(pads allowed)
				(copperpour not_allowed)
				(footprints allowed)
			)
			(placement
				(enabled no)
				(sheetname "")
			)
			(fill
				(thermal_gap 0.5)
				(thermal_bridge_width 0.5)
			)
			(polygon
				(pts
					(xy 106.956014 120) (xy 106.671384 120.020357) (xy 106.392549 120.081014) (xy 106.125184 120.180736)
					(xy 105.874732 120.317493) (xy 105.646293 120.488501) (xy 105.444515 120.690279) (xy 105.273507 120.918718)
					(xy 105.13675 121.16917) (xy 105.037028 121.436535) (xy 104.976371 121.71537) (xy 104.956014 122)
					(xy 104.976371 122.28463) (xy 105.037028 122.563465) (xy 105.13675 122.83083) (xy 105.273507 123.081282)
					(xy 105.444515 123.309721) (xy 105.646293 123.511499) (xy 105.874732 123.682507) (xy 106.125184 123.819264)
					(xy 106.392549 123.918986) (xy 106.671384 123.979643) (xy 106.956014 124) (xy 107.240644 123.979643)
					(xy 107.519479 123.918986) (xy 107.786844 123.819264) (xy 108.037296 123.682507) (xy 108.265735 123.511499)
					(xy 108.467513 123.309721) (xy 108.638521 123.081282) (xy 108.775278 122.83083) (xy 108.875 122.563465)
					(xy 108.935657 122.28463) (xy 108.956014 122) (xy 108.935657 121.71537) (xy 108.875 121.436535)
					(xy 108.775278 121.16917) (xy 108.638521 120.918718) (xy 108.467513 120.690279) (xy 108.265735 120.488501)
					(xy 108.037296 120.317493) (xy 107.786844 120.180736) (xy 107.519479 120.081014) (xy 107.240644 120.020357)
				)
			)
		)
	)
	(footprint "antmicro-footprints:R_0402_1005Metric"
		(layer "F.Cu")
		(at 111.15 100.100001 -90)
		(descr "Resistor SMD 0402")
		(tags "resistor SMD 0402")
		(property "Reference" "R180"
			(at -0.800001 -1.45 90)
			(layer "F.SilkS")
			(effects
				(font
					(size 0.7 0.7)
					(thickness 0.15)
				)
				(justify left bottom)
			)
		)
		(property "Value" "R_10k_0402"
			(at -1.011843 1.772046 90)
			(layer "F.Fab")
			(hide yes)
			(effects
				(font
					(size 0.7 0.7)
					(thickness 0.15)
				)
				(justify right top)
			)
		)
		(property "Datasheet" "https://www.bourns.com/docs/product-datasheets/cr.pdf"
			(at 0 0 90)
			(layer "F.Fab")
			(hide yes)
			(effects
				(font
					(size 1.27 1.27)
					(thickness 0.15)
				)
			)
		)
		(property "Description" "SMD Chip Resistor, 10 kohm, ± 1%, 62.5 mW, 0402 [1005 Metric], Thick Film, General Purpose"
			(at 0 0 90)
			(layer "F.Fab")
			(hide yes)
			(effects
				(font
					(size 1.27 1.27)
					(thickness 0.15)
				)
			)
		)
		(property "MPN" "CR0402-FX-1002GLF"
			(at 0 0 270)
			(unlocked yes)
			(layer "F.Fab")
			(hide yes)
			(effects
				(font
					(size 1 1)
					(thickness 0.15)
				)
			)
		)
		(property "Manufacturer" "Bourns"
			(at 0 0 270)
			(unlocked yes)
			(layer "F.Fab")
			(hide yes)
			(effects
				(font
					(size 1 1)
					(thickness 0.15)
				)
			)
		)
		(property "License" "Apache-2.0"
			(at 0 0 270)
			(unlocked yes)
			(layer "F.Fab")
			(hide yes)
			(effects
				(font
					(size 1 1)
					(thickness 0.15)
				)
			)
		)
		(property "Author" "Antmicro"
			(at 0 0 270)
			(unlocked yes)
			(layer "F.Fab")
			(hide yes)
			(effects
				(font
					(size 1 1)
					(thickness 0.15)
				)
			)
		)
		(property "Val" "10k"
			(at 0 0 270)
			(unlocked yes)
			(layer "F.Fab")
			(hide yes)
			(effects
				(font
					(size 1 1)
					(thickness 0.15)
				)
			)
		)
		(property "Tolerance" "1%"
			(at 0 0 270)
			(unlocked yes)
			(layer "F.Fab")
			(hide yes)
			(effects
				(font
					(size 1 1)
					(thickness 0.15)
				)
			)
		)
		(sheetname "/Fan controller/")
		(sheetfile "fan-controller.kicad_sch")
		(attr smd exclude_from_pos_files exclude_from_bom dnp)
		(fp_rect
			(start -0.925 -0.47)
			(end 0.925 0.47)
			(stroke
				(width 0.05)
				(type default)
			)
			(fill no)
			(layer "F.CrtYd")
		)
		(fp_rect
			(start -0.5 -0.25)
			(end 0.5 0.25)
			(stroke
				(width 0.15)
				(type solid)
			)
			(fill no)
			(layer "F.Fab")
		)
		(pad "1" smd roundrect
			(at -0.48 0 270)
			(size 0.59 0.64)
			(layers "F.Cu" "F.Mask" "F.Paste")
			(roundrect_rratio 0.25)
			(net 28 "GND")
			(pintype "passive")
		)
		(pad "2" smd roundrect
			(at 0.48 0 270)
			(size 0.59 0.64)
			(layers "F.Cu" "F.Mask" "F.Paste")
			(roundrect_rratio 0.25)
			(net 400 "/Fan controller/SLOPE")
			(pintype "passive")
		)
	)
	(footprint "antmicro-footprints:R_0402_1005Metric"
		(layer "F.Cu")
		(at 83.85 57.771999)
		(descr "Resistor SMD 0402")
		(tags "resistor SMD 0402")
		(property "Reference" "R23"
			(at -0.67 1.330001 0)
			(layer "F.SilkS")
			(effects
				(font
					(size 0.7 0.7)
					(thickness 0.15)
				)
				(justify left bottom)
			)
		)
		(property "Value" "R_5k1_0402"
			(at -1.011843 1.772046 0)
			(layer "F.Fab")
			(hide yes)
			(effects
				(font
					(size 0.7 0.7)
					(thickness 0.15)
				)
				(justify left bottom)
			)
		)
		(property "Datasheet" "https://www.bourns.com/docs/product-datasheets/cr.pdf"
			(at 0 0 0)
			(layer "F.Fab")
			(hide yes)
			(effects
				(font
					(size 1.27 1.27)
					(thickness 0.15)
				)
			)
		)
		(property "Description" "SMD Chip Resistor, 5.1 kohm, ± 1%, 63 mW, 0402 [1005 Metric], Thick Film, General Purpose"
			(at 0 0 0)
			(layer "F.Fab")
			(hide yes)
			(effects
				(font
					(size 1.27 1.27)
					(thickness 0.15)
				)
			)
		)
		(property "MPN" "CR0402-FX-5101GLF"
			(at 0 0 0)
			(unlocked yes)
			(layer "F.Fab")
			(hide yes)
			(effects
				(font
					(size 1 1)
					(thickness 0.15)
				)
			)
		)
		(property "Manufacturer" "Bourns"
			(at 0 0 0)
			(unlocked yes)
			(layer "F.Fab")
			(hide yes)
			(effects
				(font
					(size 1 1)
					(thickness 0.15)
				)
			)
		)
		(property "License" "Apache-2.0"
			(at 0 0 0)
			(unlocked yes)
			(layer "F.Fab")
			(hide yes)
			(effects
				(font
					(size 1 1)
					(thickness 0.15)
				)
			)
		)
		(property "Author" "Antmicro"
			(at 0 0 0)
			(unlocked yes)
			(layer "F.Fab")
			(hide yes)
			(effects
				(font
					(size 1 1)
					(thickness 0.15)
				)
			)
		)
		(property "Val" "5k1"
			(at 0 0 0)
			(unlocked yes)
			(layer "F.Fab")
			(hide yes)
			(effects
				(font
					(size 1 1)
					(thickness 0.15)
				)
			)
		)
		(property "Tolerance" "1%"
			(at 0 0 0)
			(unlocked yes)
			(layer "F.Fab")
			(hide yes)
			(effects
				(font
					(size 1 1)
					(thickness 0.15)
				)
			)
		)
		(sheetname "/Power/")
		(sheetfile "power.kicad_sch")
		(attr smd)
		(fp_rect
			(start -0.925 -0.47)
			(end 0.925 0.47)
			(stroke
				(width 0.05)
				(type default)
			)
			(fill no)
			(layer "F.CrtYd")
		)
		(fp_rect
			(start -0.5 -0.25)
			(end 0.5 0.25)
			(stroke
				(width 0.15)
				(type solid)
			)
			(fill no)
			(layer "F.Fab")
		)
		(pad "1" smd roundrect
			(at -0.48 0)
			(size 0.59 0.64)
			(layers "F.Cu" "F.Mask" "F.Paste")
			(roundrect_rratio 0.25)
			(net 28 "GND")
			(pintype "passive")
		)
		(pad "2" smd roundrect
			(at 0.48 0)
			(size 0.59 0.64)
			(layers "F.Cu" "F.Mask" "F.Paste")
			(roundrect_rratio 0.25)
			(net 357 "/Power/CC1")
			(pintype "passive")
		)
	)
	(footprint "antmicro-footprints:C_0402_1005Metric"
		(layer "F.Cu")
		(at 97.399999 108.1)
		(descr "Capacitor SMD 0402")
		(tags "capacitor SMD 0402")
		(property "Reference" "C68"
			(at -2.249999 15.625 0)
			(layer "F.SilkS")
			(effects
				(font
					(size 0.7 0.7)
					(thickness 0.15)
				)
				(justify left bottom)
			)
		)
		(property "Value" "C_100n_0402"
			(at -1.022927 2.155213 0)
			(layer "F.Fab")
			(hide yes)
			(effects
				(font
					(size 0.7 0.7)
					(thickness 0.15)
				)
				(justify left bottom)
			)
		)
		(property "Datasheet" "https://www.murata.com/products/productdetail?partno=GRM155R61H104KE14%23"
			(at 0 0 0)
			(layer "F.Fab")
			(hide yes)
			(effects
				(font
					(size 1.27 1.27)
					(thickness 0.15)
				)
			)
		)
		(property "Description" "SMD Multilayer Ceramic Capacitor, 0.1 µF, 50 V, 0402 [1005 Metric], ± 10%, X5R, GRM Series"
			(at 0 0 0)
			(layer "F.Fab")
			(hide yes)
			(effects
				(font
					(size 1.27 1.27)
					(thickness 0.15)
				)
			)
		)
		(property "MPN" "GRM155R61H104KE14D"
			(at 0 0 0)
			(unlocked yes)
			(layer "F.Fab")
			(hide yes)
			(effects
				(font
					(size 1 1)
					(thickness 0.15)
				)
			)
		)
		(property "Val" "100n"
			(at 0 0 0)
			(unlocked yes)
			(layer "F.Fab")
			(hide yes)
			(effects
				(font
					(size 1 1)
					(thickness 0.15)
				)
			)
		)
		(property "Voltage" "50V"
			(at 0 0 0)
			(unlocked yes)
			(layer "F.Fab")
			(hide yes)
			(effects
				(font
					(size 1 1)
					(thickness 0.15)
				)
			)
		)
		(property "Dielectric" "X5R"
			(at 0 0 0)
			(unlocked yes)
			(layer "F.Fab")
			(hide yes)
			(effects
				(font
					(size 1 1)
					(thickness 0.15)
				)
			)
		)
		(property "Manufacturer" "Murata"
			(at 0 0 0)
			(unlocked yes)
			(layer "F.Fab")
			(hide yes)
			(effects
				(font
					(size 1 1)
					(thickness 0.15)
				)
			)
		)
		(property "License" "Apache-2.0"
			(at 0 0 0)
			(unlocked yes)
			(layer "F.Fab")
			(hide yes)
			(effects
				(font
					(size 1 1)
					(thickness 0.15)
				)
			)
		)
		(property "Author" "Antmicro"
			(at 0 0 0)
			(unlocked yes)
			(layer "F.Fab")
			(hide yes)
			(effects
				(font
					(size 1 1)
					(thickness 0.15)
				)
			)
		)
		(sheetname "/X710-AT2 10GbE/")
		(sheetfile "x710-at2-10gbe.kicad_sch")
		(attr smd)
		(fp_rect
			(start -0.925 -0.47)
			(end 0.925 0.47)
			(stroke
				(width 0.05)
				(type default)
			)
			(fill no)
			(layer "F.CrtYd")
		)
		(fp_line
			(start -0.494 -0.25)
			(end 0.504 -0.25)
			(stroke
				(width 0.15)
				(type solid)
			)
			(layer "F.Fab")
		)
		(fp_line
			(start -0.494 0.248)
			(end -0.494 -0.25)
			(stroke
				(width 0.15)
				(type solid)
			)
			(layer "F.Fab")
		)
		(fp_line
			(start 0.504 -0.25)
			(end 0.504 0.248)
			(stroke
				(width 0.15)
				(type solid)
			)
			(layer "F.Fab")
		)
		(fp_line
			(start 0.504 0.248)
			(end -0.494 0.248)
			(stroke
				(width 0.15)
				(type solid)
			)
			(layer "F.Fab")
		)
		(pad "1" smd roundrect
			(at -0.48 0)
			(size 0.59 0.64)
			(layers "F.Cu" "F.Mask" "F.Paste")
			(roundrect_rratio 0.25)
			(net 29 "/X710-AT2 10GbE/25MHZ_OSC.+")
			(pintype "passive")
		)
		(pad "2" smd roundrect
			(at 0.48 0)
			(size 0.59 0.64)
			(layers "F.Cu" "F.Mask" "F.Paste")
			(roundrect_rratio 0.25)
			(net 30 "/X710-AT2 10GbE/25MHZ_OSC_AC.+")
			(pintype "passive")
		)
	)
	(footprint "antmicro-footprints:R_0603_1608Metric"
		(layer "F.Cu")
		(at 63.199998 91.8)
		(descr "Resistor SMD 0603")
		(tags "resistor SMD 0603")
		(property "Reference" "R28"
			(at -0.41795 -0.496932 0)
			(layer "F.SilkS")
			(effects
				(font
					(size 0.7 0.7)
					(thickness 0.15)
				)
				(justify left bottom)
			)
		)
		(property "Value" "R_0R_22.4A_0603"
			(at 0 1.6 0)
			(layer "F.Fab")
			(hide yes)
			(effects
				(font
					(size 0.7 0.7)
					(thickness 0.15)
				)
				(justify left bottom)
			)
		)
		(property "Datasheet" "https://fscdn.rohm.com/en/products/databook/datasheet/passive/resistor/chip_resistor/pmr-jpw-e.pdf"
			(at 0 0 0)
			(layer "F.Fab")
			(hide yes)
			(effects
				(font
					(size 1.27 1.27)
					(thickness 0.15)
				)
			)
		)
		(property "Description" "SMD Chip Resistor"
			(at 0 0 0)
			(layer "F.Fab")
			(hide yes)
			(effects
				(font
					(size 1.27 1.27)
					(thickness 0.15)
				)
			)
		)
		(property "MPN" "PMR03EZPJ000"
			(at 0 0 0)
			(unlocked yes)
			(layer "F.Fab")
			(hide yes)
			(effects
				(font
					(size 1 1)
					(thickness 0.15)
				)
			)
		)
		(property "Manufacturer" "ROHM Semiconductor"
			(at 0 0 0)
			(unlocked yes)
			(layer "F.Fab")
			(hide yes)
			(effects
				(font
					(size 1 1)
					(thickness 0.15)
				)
			)
		)
		(property "Val" "0R"
			(at 0 0 0)
			(unlocked yes)
			(layer "F.Fab")
			(hide yes)
			(effects
				(font
					(size 1 1)
					(thickness 0.15)
				)
			)
		)
		(property "Max. Curr." "22.4A"
			(at 0 0 0)
			(unlocked yes)
			(layer "F.Fab")
			(hide yes)
			(effects
				(font
					(size 1 1)
					(thickness 0.15)
				)
			)
		)
		(property "Author" "Antmicro"
			(at 0 0 0)
			(unlocked yes)
			(layer "F.Fab")
			(hide yes)
			(effects
				(font
					(size 1 1)
					(thickness 0.15)
				)
			)
		)
		(property "License" "Apache-2.0"
			(at 0 0 0)
			(unlocked yes)
			(layer "F.Fab")
			(hide yes)
			(effects
				(font
					(size 1 1)
					(thickness 0.15)
				)
			)
		)
		(property "Tolerance" "template_tolerance"
			(at 0 0 0)
			(unlocked yes)
			(layer "F.Fab")
			(hide yes)
			(effects
				(font
					(size 1 1)
					(thickness 0.15)
				)
			)
		)
		(sheetname "/Power/")
		(sheetfile "power.kicad_sch")
		(attr smd)
		(fp_line
			(start -0.15 -0.4)
			(end 0.15 -0.4)
			(stroke
				(width 0.15)
				(type solid)
			)
			(layer "F.SilkS")
		)
		(fp_line
			(start -0.15 0.4)
			(end 0.15 0.4)
			(stroke
				(width 0.15)
				(type solid)
			)
			(layer "F.SilkS")
		)
		(fp_rect
			(start -1.25 -0.65)
			(end 1.25 0.65)
			(stroke
				(width 0.05)
				(type solid)
			)
			(fill no)
			(layer "F.CrtYd")
		)
		(fp_rect
			(start -0.8 -0.4)
			(end 0.8 0.4)
			(stroke
				(width 0.15)
				(type solid)
			)
			(fill no)
			(layer "F.Fab")
		)
		(pad "1" smd roundrect
			(at -0.7 0)
			(size 0.8 1)
			(layers "F.Cu" "F.Mask" "F.Paste")
			(roundrect_rratio 0.2)
			(net 311 "/Power/+DVDD_OUT")
			(pintype "passive")
		)
		(pad "2" smd roundrect
			(at 0.7 0)
			(size 0.8 1)
			(layers "F.Cu" "F.Mask" "F.Paste")
			(roundrect_rratio 0.2)
			(net 6 "DVDD")
			(pintype "passive")
		)
	)
	(footprint "antmicro-footprints:R_0402_1005Metric"
		(layer "F.Cu")
		(at 107.6 112.5 180)
		(descr "Resistor SMD 0402")
		(tags "resistor SMD 0402")
		(property "Reference" "R43"
			(at -3.21 -0.63 0)
			(layer "F.SilkS")
			(effects
				(font
					(size 0.7 0.7)
					(thickness 0.15)
				)
				(justify right top)
			)
		)
		(property "Value" "R_10k_0402"
			(at -1.011843 1.772046 0)
			(layer "F.Fab")
			(hide yes)
			(effects
				(font
					(size 0.7 0.7)
					(thickness 0.15)
				)
				(justify right top)
			)
		)
		(property "Datasheet" "https://www.bourns.com/docs/product-datasheets/cr.pdf"
			(at 0 0 0)
			(layer "F.Fab")
			(hide yes)
			(effects
				(font
					(size 1.27 1.27)
					(thickness 0.15)
				)
			)
		)
		(property "Description" "SMD Chip Resistor, 10 kohm, ± 1%, 62.5 mW, 0402 [1005 Metric], Thick Film, General Purpose"
			(at 0 0 0)
			(layer "F.Fab")
			(hide yes)
			(effects
				(font
					(size 1.27 1.27)
					(thickness 0.15)
				)
			)
		)
		(property "MPN" "CR0402-FX-1002GLF"
			(at 0 0 180)
			(unlocked yes)
			(layer "F.Fab")
			(hide yes)
			(effects
				(font
					(size 1 1)
					(thickness 0.15)
				)
			)
		)
		(property "Manufacturer" "Bourns"
			(at 0 0 180)
			(unlocked yes)
			(layer "F.Fab")
			(hide yes)
			(effects
				(font
					(size 1 1)
					(thickness 0.15)
				)
			)
		)
		(property "License" "Apache-2.0"
			(at 0 0 180)
			(unlocked yes)
			(layer "F.Fab")
			(hide yes)
			(effects
				(font
					(size 1 1)
					(thickness 0.15)
				)
			)
		)
		(property "Author" "Antmicro"
			(at 0 0 180)
			(unlocked yes)
			(layer "F.Fab")
			(hide yes)
			(effects
				(font
					(size 1 1)
					(thickness 0.15)
				)
			)
		)
		(property "Val" "10k"
			(at 0 0 180)
			(unlocked yes)
			(layer "F.Fab")
			(hide yes)
			(effects
				(font
					(size 1 1)
					(thickness 0.15)
				)
			)
		)
		(property "Tolerance" "1%"
			(at 0 0 180)
			(unlocked yes)
			(layer "F.Fab")
			(hide yes)
			(effects
				(font
					(size 1 1)
					(thickness 0.15)
				)
			)
		)
		(sheetname "/X710-AT2 10GbE/")
		(sheetfile "x710-at2-10gbe.kicad_sch")
		(attr smd)
		(fp_rect
			(start -0.925 -0.47)
			(end 0.925 0.47)
			(stroke
				(width 0.05)
				(type default)
			)
			(fill no)
			(layer "F.CrtYd")
		)
		(fp_rect
			(start -0.5 -0.25)
			(end 0.5 0.25)
			(stroke
				(width 0.15)
				(type solid)
			)
			(fill no)
			(layer "F.Fab")
		)
		(pad "1" smd roundrect
			(at -0.48 0 180)
			(size 0.59 0.64)
			(layers "F.Cu" "F.Mask" "F.Paste")
			(roundrect_rratio 0.25)
			(net 74 "/X710-AT2 10GbE/3V3_OSC")
			(pintype "passive")
		)
		(pad "2" smd roundrect
			(at 0.48 0 180)
			(size 0.59 0.64)
			(layers "F.Cu" "F.Mask" "F.Paste")
			(roundrect_rratio 0.25)
			(net 149 "/X710-AT2 10GbE/EN_OSC")
			(pintype "passive")
		)
	)
	(footprint "antmicro-footprints:R_0402_1005Metric"
		(layer "F.Cu")
		(at 99.16 90.1645 180)
		(descr "Resistor SMD 0402")
		(tags "resistor SMD 0402")
		(property "Reference" "R95"
			(at -1.04 -0.5355 0)
			(layer "F.SilkS")
			(effects
				(font
					(size 0.7 0.7)
					(thickness 0.15)
				)
				(justify right top)
			)
		)
		(property "Value" "R_0R_0402"
			(at -1.011843 1.772047 0)
			(layer "F.Fab")
			(hide yes)
			(effects
				(font
					(size 0.7 0.7)
					(thickness 0.15)
				)
				(justify right top)
			)
		)
		(property "Datasheet" "https://industrial.panasonic.com/cdbs/www-data/pdf/RDA0000/AOA0000C301.pdf"
			(at 0 0 0)
			(layer "F.Fab")
			(hide yes)
			(effects
				(font
					(size 1.27 1.27)
					(thickness 0.15)
				)
			)
		)
		(property "Description" "SMD Chip Resistor, Jumper, 0 ohm, 100 mW, 0402 [1005 Metric], Thick Film, General Purpose"
			(at 0 0 0)
			(layer "F.Fab")
			(hide yes)
			(effects
				(font
					(size 1.27 1.27)
					(thickness 0.15)
				)
			)
		)
		(property "MPN" "ERJ2GE0R00X"
			(at 0 0 180)
			(unlocked yes)
			(layer "F.Fab")
			(hide yes)
			(effects
				(font
					(size 1 1)
					(thickness 0.15)
				)
			)
		)
		(property "Manufacturer" "Panasonic"
			(at 0 0 180)
			(unlocked yes)
			(layer "F.Fab")
			(hide yes)
			(effects
				(font
					(size 1 1)
					(thickness 0.15)
				)
			)
		)
		(property "License" "Apache-2.0"
			(at 0 0 180)
			(unlocked yes)
			(layer "F.Fab")
			(hide yes)
			(effects
				(font
					(size 1 1)
					(thickness 0.15)
				)
			)
		)
		(property "Author" "Antmicro"
			(at 0 0 180)
			(unlocked yes)
			(layer "F.Fab")
			(hide yes)
			(effects
				(font
					(size 1 1)
					(thickness 0.15)
				)
			)
		)
		(property "Val" "0R"
			(at 0 0 180)
			(unlocked yes)
			(layer "F.Fab")
			(hide yes)
			(effects
				(font
					(size 1 1)
					(thickness 0.15)
				)
			)
		)
		(property "Tolerance" "~"
			(at 0 0 180)
			(unlocked yes)
			(layer "F.Fab")
			(hide yes)
			(effects
				(font
					(size 1 1)
					(thickness 0.15)
				)
			)
		)
		(property "Current" "1A"
			(at 0 0 180)
			(unlocked yes)
			(layer "F.Fab")
			(hide yes)
			(effects
				(font
					(size 1 1)
					(thickness 0.15)
				)
			)
		)
		(sheetname "/X710-AT2 PCIe/")
		(sheetfile "x710-at2-pcie.kicad_sch")
		(attr smd)
		(fp_rect
			(start -0.925 -0.47)
			(end 0.925 0.47)
			(stroke
				(width 0.05)
				(type default)
			)
			(fill no)
			(layer "F.CrtYd")
		)
		(fp_rect
			(start -0.5 -0.25)
			(end 0.5 0.25)
			(stroke
				(width 0.15)
				(type solid)
			)
			(fill no)
			(layer "F.Fab")
		)
		(pad "1" smd roundrect
			(at -0.48 0 180)
			(size 0.59 0.64)
			(layers "F.Cu" "F.Mask" "F.Paste")
			(roundrect_rratio 0.25)
			(net 42 "/OCuLink/REFCLK.+")
			(pintype "passive")
		)
		(pad "2" smd roundrect
			(at 0.48 0 180)
			(size 0.59 0.64)
			(layers "F.Cu" "F.Mask" "F.Paste")
			(roundrect_rratio 0.25)
			(net 402 "/X710-AT2 PCIe/CLK+")
			(pintype "passive")
		)
	)
	(footprint "antmicro-footprints:R_0402_1005Metric"
		(layer "F.Cu")
		(at 58.099999 92.849999 90)
		(descr "Resistor SMD 0402")
		(tags "resistor SMD 0402")
		(property "Reference" "R31"
			(at -1.240001 1.220001 90)
			(layer "F.SilkS")
			(effects
				(font
					(size 0.7 0.7)
					(thickness 0.15)
				)
				(justify left bottom)
			)
		)
		(property "Value" "R_100k_0402"
			(at -1.011843 1.772046 90)
			(layer "F.Fab")
			(hide yes)
			(effects
				(font
					(size 0.7 0.7)
					(thickness 0.15)
				)
				(justify left bottom)
			)
		)
		(property "Datasheet" "https://www.bourns.com/docs/product-datasheets/cr.pdf"
			(at 0 0 90)
			(layer "F.Fab")
			(hide yes)
			(effects
				(font
					(size 1.27 1.27)
					(thickness 0.15)
				)
			)
		)
		(property "Description" "SMD Chip Resistor, 100 kohm, ± 1%, 62.5 mW, 0402 [1005 Metric], Thick Film, General Purpose"
			(at 0 0 90)
			(layer "F.Fab")
			(hide yes)
			(effects
				(font
					(size 1.27 1.27)
					(thickness 0.15)
				)
			)
		)
		(property "MPN" "CR0402-FX-1003GLF"
			(at 0 0 90)
			(unlocked yes)
			(layer "F.Fab")
			(hide yes)
			(effects
				(font
					(size 1 1)
					(thickness 0.15)
				)
			)
		)
		(property "Manufacturer" "Bourns"
			(at 0 0 90)
			(unlocked yes)
			(layer "F.Fab")
			(hide yes)
			(effects
				(font
					(size 1 1)
					(thickness 0.15)
				)
			)
		)
		(property "License" "Apache-2.0"
			(at 0 0 90)
			(unlocked yes)
			(layer "F.Fab")
			(hide yes)
			(effects
				(font
					(size 1 1)
					(thickness 0.15)
				)
			)
		)
		(property "Author" "Antmicro"
			(at 0 0 90)
			(unlocked yes)
			(layer "F.Fab")
			(hide yes)
			(effects
				(font
					(size 1 1)
					(thickness 0.15)
				)
			)
		)
		(property "Val" "100k"
			(at 0 0 90)
			(unlocked yes)
			(layer "F.Fab")
			(hide yes)
			(effects
				(font
					(size 1 1)
					(thickness 0.15)
				)
			)
		)
		(property "Tolerance" "1%"
			(at 0 0 90)
			(unlocked yes)
			(layer "F.Fab")
			(hide yes)
			(effects
				(font
					(size 1 1)
					(thickness 0.15)
				)
			)
		)
		(sheetname "/Power/")
		(sheetfile "power.kicad_sch")
		(attr smd)
		(fp_rect
			(start -0.925 -0.47)
			(end 0.925 0.47)
			(stroke
				(width 0.05)
				(type default)
			)
			(fill no)
			(layer "F.CrtYd")
		)
		(fp_rect
			(start -0.5 -0.25)
			(end 0.5 0.25)
			(stroke
				(width 0.15)
				(type solid)
			)
			(fill no)
			(layer "F.Fab")
		)
		(pad "1" smd roundrect
			(at -0.48 0 90)
			(size 0.59 0.64)
			(layers "F.Cu" "F.Mask" "F.Paste")
			(roundrect_rratio 0.25)
			(net 378 "/Power/DVDD_PG")
			(pintype "passive")
		)
		(pad "2" smd roundrect
			(at 0.48 0 90)
			(size 0.59 0.64)
			(layers "F.Cu" "F.Mask" "F.Paste")
			(roundrect_rratio 0.25)
			(net 326 "/Power/DVDD_VCC")
			(pintype "passive")
		)
	)
	(footprint "antmicro-footprints:R_0402_1005Metric"
		(layer "F.Cu")
		(at 101.3 106.15 180)
		(descr "Resistor SMD 0402")
		(tags "resistor SMD 0402")
		(property "Reference" "R79"
			(at 0.8 -15.425 0)
			(layer "F.SilkS")
			(effects
				(font
					(size 0.7 0.7)
					(thickness 0.15)
				)
				(justify left bottom)
			)
		)
		(property "Value" "R_100k_0402"
			(at -1.011843 1.772046 0)
			(layer "F.Fab")
			(hide yes)
			(effects
				(font
					(size 0.7 0.7)
					(thickness 0.15)
				)
				(justify right top)
			)
		)
		(property "Datasheet" "https://www.bourns.com/docs/product-datasheets/cr.pdf"
			(at 0 0 0)
			(layer "F.Fab")
			(hide yes)
			(effects
				(font
					(size 1.27 1.27)
					(thickness 0.15)
				)
			)
		)
		(property "Description" "SMD Chip Resistor, 100 kohm, ± 1%, 62.5 mW, 0402 [1005 Metric], Thick Film, General Purpose"
			(at 0 0 0)
			(layer "F.Fab")
			(hide yes)
			(effects
				(font
					(size 1.27 1.27)
					(thickness 0.15)
				)
			)
		)
		(property "MPN" "CR0402-FX-1003GLF"
			(at 0 0 180)
			(unlocked yes)
			(layer "F.Fab")
			(hide yes)
			(effects
				(font
					(size 1 1)
					(thickness 0.15)
				)
			)
		)
		(property "Manufacturer" "Bourns"
			(at 0 0 180)
			(unlocked yes)
			(layer "F.Fab")
			(hide yes)
			(effects
				(font
					(size 1 1)
					(thickness 0.15)
				)
			)
		)
		(property "License" "Apache-2.0"
			(at 0 0 180)
			(unlocked yes)
			(layer "F.Fab")
			(hide yes)
			(effects
				(font
					(size 1 1)
					(thickness 0.15)
				)
			)
		)
		(property "Author" "Antmicro"
			(at 0 0 180)
			(unlocked yes)
			(layer "F.Fab")
			(hide yes)
			(effects
				(font
					(size 1 1)
					(thickness 0.15)
				)
			)
		)
		(property "Val" "100k"
			(at 0 0 180)
			(unlocked yes)
			(layer "F.Fab")
			(hide yes)
			(effects
				(font
					(size 1 1)
					(thickness 0.15)
				)
			)
		)
		(property "Tolerance" "1%"
			(at 0 0 180)
			(unlocked yes)
			(layer "F.Fab")
			(hide yes)
			(effects
				(font
					(size 1 1)
					(thickness 0.15)
				)
			)
		)
		(sheetname "/X710-AT2 Misc/")
		(sheetfile "x710-at2-mics.kicad_sch")
		(attr smd)
		(fp_rect
			(start -0.925 -0.47)
			(end 0.925 0.47)
			(stroke
				(width 0.05)
				(type default)
			)
			(fill no)
			(layer "F.CrtYd")
		)
		(fp_rect
			(start -0.5 -0.25)
			(end 0.5 0.25)
			(stroke
				(width 0.15)
				(type solid)
			)
			(fill no)
			(layer "F.Fab")
		)
		(pad "1" smd roundrect
			(at -0.48 0 180)
			(size 0.59 0.64)
			(layers "F.Cu" "F.Mask" "F.Paste")
			(roundrect_rratio 0.25)
			(net 361 "/X710-AT2 Misc/NCSI.TXD_1")
			(pintype "passive")
		)
		(pad "2" smd roundrect
			(at 0.48 0 180)
			(size 0.59 0.64)
			(layers "F.Cu" "F.Mask" "F.Paste")
			(roundrect_rratio 0.25)
			(net 7 "+3V3")
			(pintype "passive")
		)
	)
	(footprint "antmicro-footprints:C_0603_1608Metric_EIA"
		(layer "F.Cu")
		(at 77.2 82.3 180)
		(descr "Capacitor SMD 0603, IPC-7351 Density Level A")
		(tags "Capacitor 0603")
		(property "Reference" "C154"
			(at -1.4 7.586 0)
			(layer "F.SilkS")
			(effects
				(font
					(size 0.7 0.7)
					(thickness 0.15)
				)
				(justify right top)
			)
		)
		(property "Value" "C_22u_16V_0603"
			(at -1.42757 1.770288 0)
			(layer "F.Fab")
			(hide yes)
			(effects
				(font
					(size 0.7 0.7)
					(thickness 0.15)
				)
				(justify right top)
			)
		)
		(property "Datasheet" "https://product.samsungsem.com/mlcc/CL10A226MO7JZN.do"
			(at 0 0 0)
			(layer "F.Fab")
			(hide yes)
			(effects
				(font
					(size 1.27 1.27)
					(thickness 0.15)
				)
			)
		)
		(property "Description" "SMD Multilayer Ceramic Capacitor"
			(at 0 0 0)
			(layer "F.Fab")
			(hide yes)
			(effects
				(font
					(size 1.27 1.27)
					(thickness 0.15)
				)
			)
		)
		(property "MPN" "CL10A226MO7JZNC"
			(at 0 0 180)
			(unlocked yes)
			(layer "F.Fab")
			(hide yes)
			(effects
				(font
					(size 1 1)
					(thickness 0.15)
				)
			)
		)
		(property "Manufacturer" "Samsung Electro-Mechanics"
			(at 0 0 180)
			(unlocked yes)
			(layer "F.Fab")
			(hide yes)
			(effects
				(font
					(size 1 1)
					(thickness 0.15)
				)
			)
		)
		(property "License" "Apache-2.0"
			(at 0 0 180)
			(unlocked yes)
			(layer "F.Fab")
			(hide yes)
			(effects
				(font
					(size 1 1)
					(thickness 0.15)
				)
			)
		)
		(property "Author" "Antmicro"
			(at 0 0 180)
			(unlocked yes)
			(layer "F.Fab")
			(hide yes)
			(effects
				(font
					(size 1 1)
					(thickness 0.15)
				)
			)
		)
		(property "Val" "22u"
			(at 0 0 180)
			(unlocked yes)
			(layer "F.Fab")
			(hide yes)
			(effects
				(font
					(size 1 1)
					(thickness 0.15)
				)
			)
		)
		(property "Voltage" "16V"
			(at 0 0 180)
			(unlocked yes)
			(layer "F.Fab")
			(hide yes)
			(effects
				(font
					(size 1 1)
					(thickness 0.15)
				)
			)
		)
		(property "Dielectric" ""
			(at 0 0 180)
			(unlocked yes)
			(layer "F.Fab")
			(hide yes)
			(effects
				(font
					(size 1 1)
					(thickness 0.15)
				)
			)
		)
		(sheetname "/X710-AT2 power/")
		(sheetfile "x710-at2-power.kicad_sch")
		(attr smd)
		(fp_line
			(start -0.15 0.55)
			(end 0.15 0.55)
			(stroke
				(width 0.15)
				(type solid)
			)
			(layer "F.SilkS")
		)
		(fp_line
			(start -0.15 -0.55)
			(end 0.15 -0.55)
			(stroke
				(width 0.15)
				(type solid)
			)
			(layer "F.SilkS")
		)
		(fp_rect
			(start -1.25 -0.65)
			(end 1.25 0.65)
			(stroke
				(width 0.05)
				(type solid)
			)
			(fill no)
			(layer "F.CrtYd")
		)
		(fp_rect
			(start -0.8 -0.45)
			(end 0.8 0.45)
			(stroke
				(width 0.15)
				(type solid)
			)
			(fill no)
			(layer "F.Fab")
		)
		(pad "1" smd roundrect
			(at -0.7 0 180)
			(size 0.8 1.1)
			(layers "F.Cu" "F.Mask" "F.Paste")
			(roundrect_rratio 0.2)
			(net 28 "GND")
			(pintype "passive")
		)
		(pad "2" smd roundrect
			(at 0.7 0 180)
			(size 0.8 1.1)
			(layers "F.Cu" "F.Mask" "F.Paste")
			(roundrect_rratio 0.2)
			(net 7 "+3V3")
			(pintype "passive")
		)
	)
	(footprint "antmicro-footprints:C_0402_1005Metric"
		(layer "F.Cu")
		(at 104.498001 62.778655 -90)
		(descr "Capacitor SMD 0402")
		(tags "capacitor SMD 0402")
		(property "Reference" "C190"
			(at 1.406345 -2.501999 270)
			(layer "F.SilkS")
			(effects
				(font
					(size 0.7 0.7)
					(thickness 0.15)
				)
				(justify left bottom)
			)
		)
		(property "Value" "C_220n_16V_0402"
			(at -1.022927 2.155213 270)
			(layer "F.Fab")
			(hide yes)
			(effects
				(font
					(size 0.7 0.7)
					(thickness 0.15)
				)
				(justify left bottom)
			)
		)
		(property "Datasheet" "https://www.murata.com/products/productdetail?partno=GRM155R71C224KA12%23"
			(at 0 0 270)
			(layer "F.Fab")
			(hide yes)
			(effects
				(font
					(size 1.27 1.27)
					(thickness 0.15)
				)
			)
		)
		(property "Description" "SMD Multilayer Ceramic Capacitor, 0.22 µF, 16 V, 0402 [1005 Metric], ± 10%, X7R, GRM Series"
			(at 0 0 270)
			(layer "F.Fab")
			(hide yes)
			(effects
				(font
					(size 1.27 1.27)
					(thickness 0.15)
				)
			)
		)
		(property "MPN" "GRM155R71C224KA12D"
			(at 0 0 270)
			(unlocked yes)
			(layer "F.Fab")
			(hide yes)
			(effects
				(font
					(size 1 1)
					(thickness 0.15)
				)
			)
		)
		(property "Manufacturer" "Murata"
			(at 0 0 270)
			(unlocked yes)
			(layer "F.Fab")
			(hide yes)
			(effects
				(font
					(size 1 1)
					(thickness 0.15)
				)
			)
		)
		(property "License" "Apache-2.0"
			(at 0 0 270)
			(unlocked yes)
			(layer "F.Fab")
			(hide yes)
			(effects
				(font
					(size 1 1)
					(thickness 0.15)
				)
			)
		)
		(property "Author" "Antmicro"
			(at 0 0 270)
			(unlocked yes)
			(layer "F.Fab")
			(hide yes)
			(effects
				(font
					(size 1 1)
					(thickness 0.15)
				)
			)
		)
		(property "Val" "220n"
			(at 0 0 270)
			(unlocked yes)
			(layer "F.Fab")
			(hide yes)
			(effects
				(font
					(size 1 1)
					(thickness 0.15)
				)
			)
		)
		(property "Voltage" "16V"
			(at 0 0 270)
			(unlocked yes)
			(layer "F.Fab")
			(hide yes)
			(effects
				(font
					(size 1 1)
					(thickness 0.15)
				)
			)
		)
		(property "Dielectric" "X7R"
			(at 0 0 270)
			(unlocked yes)
			(layer "F.Fab")
			(hide yes)
			(effects
				(font
					(size 1 1)
					(thickness 0.15)
				)
			)
		)
		(sheetname "/X710-AT2 PCIe/")
		(sheetfile "x710-at2-pcie.kicad_sch")
		(attr smd)
		(fp_rect
			(start -0.925 -0.47)
			(end 0.925 0.47)
			(stroke
				(width 0.05)
				(type default)
			)
			(fill no)
			(layer "F.CrtYd")
		)
		(fp_line
			(start -0.494 0.248)
			(end -0.494 -0.25)
			(stroke
				(width 0.15)
				(type solid)
			)
			(layer "F.Fab")
		)
		(fp_line
			(start 0.504 0.248)
			(end -0.494 0.248)
			(stroke
				(width 0.15)
				(type solid)
			)
			(layer "F.Fab")
		)
		(fp_line
			(start -0.494 -0.25)
			(end 0.504 -0.25)
			(stroke
				(width 0.15)
				(type solid)
			)
			(layer "F.Fab")
		)
		(fp_line
			(start 0.504 -0.25)
			(end 0.504 0.248)
			(stroke
				(width 0.15)
				(type solid)
			)
			(layer "F.Fab")
		)
		(pad "1" smd roundrect
			(at -0.48 0 270)
			(size 0.59 0.64)
			(layers "F.Cu" "F.Mask" "F.Paste")
			(roundrect_rratio 0.25)
			(net 13 "/OCuLink/PCIe_{x4}.TX0+")
			(pintype "passive")
		)
		(pad "2" smd roundrect
			(at 0.48 0 270)
			(size 0.59 0.64)
			(layers "F.Cu" "F.Mask" "F.Paste")
			(roundrect_rratio 0.25)
			(net 32 "/X710-AT2 PCIe/PCIe_{x4}_AC.TX0+")
			(pintype "passive")
		)
	)
	(footprint "antmicro-footprints:SOT-23-3"
		(layer "F.Cu")
		(at 55.65 78 90)
		(property "Reference" "Q4"
			(at 0.85 1.44 90)
			(layer "F.SilkS")
			(effects
				(font
					(size 0.7 0.7)
					(thickness 0.15)
				)
				(justify left bottom)
			)
		)
		(property "Value" "2N7002_SOT-23-3"
			(at -1.9 2.7 90)
			(layer "F.Fab")
			(hide yes)
			(effects
				(font
					(size 0.7 0.7)
					(thickness 0.15)
				)
				(justify left bottom)
			)
		)
		(property "Datasheet" "https://www.onsemi.com/pub/Collateral/NDS7002A-D.PDF"
			(at 0 0 90)
			(layer "F.Fab")
			(hide yes)
			(effects
				(font
					(size 1.27 1.27)
					(thickness 0.15)
				)
			)
		)
		(property "Description" "Power MOSFET, N Channel, 60 V, 115 mA, 1.2 ohm, SOT-23, Surface Mount"
			(at 0 0 90)
			(layer "F.Fab")
			(hide yes)
			(effects
				(font
					(size 1.27 1.27)
					(thickness 0.15)
				)
			)
		)
		(property "MPN" "2N7002"
			(at 0 0 90)
			(unlocked yes)
			(layer "F.Fab")
			(hide yes)
			(effects
				(font
					(size 1 1)
					(thickness 0.15)
				)
			)
		)
		(property "Manufacturer" "ON Semiconductor"
			(at 0 0 90)
			(unlocked yes)
			(layer "F.Fab")
			(hide yes)
			(effects
				(font
					(size 1 1)
					(thickness 0.15)
				)
			)
		)
		(property "Author" "Antmicro"
			(at 0 0 90)
			(unlocked yes)
			(layer "F.Fab")
			(hide yes)
			(effects
				(font
					(size 1 1)
					(thickness 0.15)
				)
			)
		)
		(property "License" "Apache-2.0"
			(at 0 0 90)
			(unlocked yes)
			(layer "F.Fab")
			(hide yes)
			(effects
				(font
					(size 1 1)
					(thickness 0.15)
				)
			)
		)
		(sheetname "/Power/")
		(sheetfile "power.kicad_sch")
		(attr smd)
		(fp_line
			(start 0.7 -1.5)
			(end -0.7 -1.5)
			(stroke
				(width 0.15)
				(type solid)
			)
			(layer "F.SilkS")
		)
		(fp_line
			(start -0.85 -1.35)
			(end -0.7 -1.5)
			(stroke
				(width 0.15)
				(type solid)
			)
			(layer "F.SilkS")
		)
		(fp_line
			(start -1.45 -1.35)
			(end -0.85 -1.35)
			(stroke
				(width 0.15)
				(type solid)
			)
			(layer "F.SilkS")
		)
		(fp_line
			(start 0.7 -0.4)
			(end 0.7 -1.5)
			(stroke
				(width 0.15)
				(type solid)
			)
			(layer "F.SilkS")
		)
		(fp_line
			(start 0.7 0.4)
			(end 0.7 1.5)
			(stroke
				(width 0.15)
				(type solid)
			)
			(layer "F.SilkS")
		)
		(fp_line
			(start 0.7 1.5)
			(end -0.7 1.5)
			(stroke
				(width 0.15)
				(type solid)
			)
			(layer "F.SilkS")
		)
		(fp_line
			(start -0.7 1.5)
			(end -0.7 1.35)
			(stroke
				(width 0.15)
				(type solid)
			)
			(layer "F.SilkS")
		)
		(fp_line
			(start 0.825 -1.6)
			(end 0.825 -0.45)
			(stroke
				(width 0.05)
				(type solid)
			)
			(layer "F.CrtYd")
		)
		(fp_line
			(start -0.9 -1.6)
			(end 0.825 -1.6)
			(stroke
				(width 0.05)
				(type solid)
			)
			(layer "F.CrtYd")
		)
		(fp_line
			(start -0.9 -1.6)
			(end -0.9 -1.4)
			(stroke
				(width 0.05)
				(type solid)
			)
			(layer "F.CrtYd")
		)
		(fp_line
			(start -0.9 -1.4)
			(end -1.75 -1.4)
			(stroke
				(width 0.05)
				(type solid)
			)
			(layer "F.CrtYd")
		)
		(fp_line
			(start -0.85 -0.5)
			(end -1.75 -0.5)
			(stroke
				(width 0.05)
				(type solid)
			)
			(layer "F.CrtYd")
		)
		(fp_line
			(start -1.75 -0.5)
			(end -1.75 -1.4)
			(stroke
				(width 0.05)
				(type solid)
			)
			(layer "F.CrtYd")
		)
		(fp_line
			(start 1.75 -0.45)
			(end 1.75 0.45)
			(stroke
				(width 0.05)
				(type solid)
			)
			(layer "F.CrtYd")
		)
		(fp_line
			(start 0.825 -0.45)
			(end 1.75 -0.45)
			(stroke
				(width 0.05)
				(type solid)
			)
			(layer "F.CrtYd")
		)
		(fp_line
			(start 1.75 0.45)
			(end 0.85 0.45)
			(stroke
				(width 0.05)
				(type solid)
			)
			(layer "F.CrtYd")
		)
		(fp_line
			(start 0.85 0.45)
			(end 0.85 1.65)
			(stroke
				(width 0.05)
				(type solid)
			)
			(layer "F.CrtYd")
		)
		(fp_line
			(start -0.85 0.5)
			(end -0.85 -0.5)
			(stroke
				(width 0.05)
				(type solid)
			)
			(layer "F.CrtYd")
		)
		(fp_line
			(start -1.75 0.5)
			(end -0.85 0.5)
			(stroke
				(width 0.05)
				(type solid)
			)
			(layer "F.CrtYd")
		)
		(fp_line
			(start -0.85 1.4)
			(end -1.75 1.4)
			(stroke
				(width 0.05)
				(type solid)
			)
			(layer "F.CrtYd")
		)
		(fp_line
			(start -1.75 1.4)
			(end -1.75 0.5)
			(stroke
				(width 0.05)
				(type solid)
			)
			(layer "F.CrtYd")
		)
		(fp_line
			(start 0.85 1.65)
			(end -0.85 1.65)
			(stroke
				(width 0.05)
				(type solid)
			)
			(layer "F.CrtYd")
		)
		(fp_line
			(start -0.85 1.65)
			(end -0.85 1.4)
			(stroke
				(width 0.05)
				(type solid)
			)
			(layer "F.CrtYd")
		)
		(fp_line
			(start -0.437 -1.526)
			(end 0.688 -1.526)
			(stroke
				(width 0.15)
				(type solid)
			)
			(layer "F.Fab")
		)
		(fp_line
			(start -0.437 -1.526)
			(end -0.712 -1.325)
			(stroke
				(width 0.15)
				(type solid)
			)
			(layer "F.Fab")
		)
		(fp_line
			(start -0.712 -1.325)
			(end -0.712 1.523)
			(stroke
				(width 0.15)
				(type solid)
			)
			(layer "F.Fab")
		)
		(fp_line
			(start 0.688 1.519)
			(end 0.688 -1.52)
			(stroke
				(width 0.15)
				(type solid)
			)
			(layer "F.Fab")
		)
		(fp_line
			(start -0.712 1.519)
			(end 0.688 1.519)
			(stroke
				(width 0.15)
				(type solid)
			)
			(layer "F.Fab")
		)
		(pad "1" smd roundrect
			(at -1.1 -0.951 90)
			(size 1 0.6)
			(layers "F.Cu" "F.Mask" "F.Paste")
			(roundrect_rratio 0.15)
			(net 378 "/Power/DVDD_PG")
			(pinfunction "G")
			(pintype "input")
		)
		(pad "2" smd roundrect
			(at -1.1 0.949 90)
			(size 1 0.6)
			(layers "F.Cu" "F.Mask" "F.Paste")
			(roundrect_rratio 0.15)
			(net 28 "GND")
			(pinfunction "S")
			(pintype "passive")
		)
		(pad "3" smd roundrect
			(at 1.1 -0.0005 90)
			(size 1 0.6)
			(layers "F.Cu" "F.Mask" "F.Paste")
			(roundrect_rratio 0.15)
			(net 89 "Net-(D11-C)")
			(pinfunction "D")
			(pintype "passive")
		)
	)
	(footprint "antmicro-footprints:C_0603_1608Metric_EIA"
		(layer "F.Cu")
		(at 77.2 83.65 180)
		(descr "Capacitor SMD 0603, IPC-7351 Density Level A")
		(tags "Capacitor 0603")
		(property "Reference" "C153"
			(at -1.4 7.772 0)
			(layer "F.SilkS")
			(effects
				(font
					(size 0.7 0.7)
					(thickness 0.15)
				)
				(justify right top)
			)
		)
		(property "Value" "C_22u_16V_0603"
			(at -1.42757 1.770288 0)
			(layer "F.Fab")
			(hide yes)
			(effects
				(font
					(size 0.7 0.7)
					(thickness 0.15)
				)
				(justify right top)
			)
		)
		(property "Datasheet" "https://product.samsungsem.com/mlcc/CL10A226MO7JZN.do"
			(at 0 0 0)
			(layer "F.Fab")
			(hide yes)
			(effects
				(font
					(size 1.27 1.27)
					(thickness 0.15)
				)
			)
		)
		(property "Description" "SMD Multilayer Ceramic Capacitor"
			(at 0 0 0)
			(layer "F.Fab")
			(hide yes)
			(effects
				(font
					(size 1.27 1.27)
					(thickness 0.15)
				)
			)
		)
		(property "MPN" "CL10A226MO7JZNC"
			(at 0 0 180)
			(unlocked yes)
			(layer "F.Fab")
			(hide yes)
			(effects
				(font
					(size 1 1)
					(thickness 0.15)
				)
			)
		)
		(property "Manufacturer" "Samsung Electro-Mechanics"
			(at 0 0 180)
			(unlocked yes)
			(layer "F.Fab")
			(hide yes)
			(effects
				(font
					(size 1 1)
					(thickness 0.15)
				)
			)
		)
		(property "License" "Apache-2.0"
			(at 0 0 180)
			(unlocked yes)
			(layer "F.Fab")
			(hide yes)
			(effects
				(font
					(size 1 1)
					(thickness 0.15)
				)
			)
		)
		(property "Author" "Antmicro"
			(at 0 0 180)
			(unlocked yes)
			(layer "F.Fab")
			(hide yes)
			(effects
				(font
					(size 1 1)
					(thickness 0.15)
				)
			)
		)
		(property "Val" "22u"
			(at 0 0 180)
			(unlocked yes)
			(layer "F.Fab")
			(hide yes)
			(effects
				(font
					(size 1 1)
					(thickness 0.15)
				)
			)
		)
		(property "Voltage" "16V"
			(at 0 0 180)
			(unlocked yes)
			(layer "F.Fab")
			(hide yes)
			(effects
				(font
					(size 1 1)
					(thickness 0.15)
				)
			)
		)
		(property "Dielectric" ""
			(at 0 0 180)
			(unlocked yes)
			(layer "F.Fab")
			(hide yes)
			(effects
				(font
					(size 1 1)
					(thickness 0.15)
				)
			)
		)
		(sheetname "/X710-AT2 power/")
		(sheetfile "x710-at2-power.kicad_sch")
		(attr smd)
		(fp_line
			(start -0.15 0.55)
			(end 0.15 0.55)
			(stroke
				(width 0.15)
				(type solid)
			)
			(layer "F.SilkS")
		)
		(fp_line
			(start -0.15 -0.55)
			(end 0.15 -0.55)
			(stroke
				(width 0.15)
				(type solid)
			)
			(layer "F.SilkS")
		)
		(fp_rect
			(start -1.25 -0.65)
			(end 1.25 0.65)
			(stroke
				(width 0.05)
				(type solid)
			)
			(fill no)
			(layer "F.CrtYd")
		)
		(fp_rect
			(start -0.8 -0.45)
			(end 0.8 0.45)
			(stroke
				(width 0.15)
				(type solid)
			)
			(fill no)
			(layer "F.Fab")
		)
		(pad "1" smd roundrect
			(at -0.7 0 180)
			(size 0.8 1.1)
			(layers "F.Cu" "F.Mask" "F.Paste")
			(roundrect_rratio 0.2)
			(net 28 "GND")
			(pintype "passive")
		)
		(pad "2" smd roundrect
			(at 0.7 0 180)
			(size 0.8 1.1)
			(layers "F.Cu" "F.Mask" "F.Paste")
			(roundrect_rratio 0.2)
			(net 7 "+3V3")
			(pintype "passive")
		)
	)
	(footprint "antmicro-footprints:C_0603_1608Metric_EIA"
		(layer "F.Cu")
		(at 60.649999 107.2)
		(descr "Capacitor SMD 0603, IPC-7351 Density Level A")
		(tags "Capacitor 0603")
		(property "Reference" "C34"
			(at -3.219999 -0.61 0)
			(layer "F.SilkS")
			(effects
				(font
					(size 0.7 0.7)
					(thickness 0.15)
				)
				(justify left bottom)
			)
		)
		(property "Value" "C_22u_16V_0603"
			(at -1.42757 1.770288 0)
			(layer "F.Fab")
			(hide yes)
			(effects
				(font
					(size 0.7 0.7)
					(thickness 0.15)
				)
				(justify left bottom)
			)
		)
		(property "Datasheet" "https://product.samsungsem.com/mlcc/CL10A226MO7JZN.do"
			(at 0 0 0)
			(layer "F.Fab")
			(hide yes)
			(effects
				(font
					(size 1.27 1.27)
					(thickness 0.15)
				)
			)
		)
		(property "Description" "SMD Multilayer Ceramic Capacitor"
			(at 0 0 0)
			(layer "F.Fab")
			(hide yes)
			(effects
				(font
					(size 1.27 1.27)
					(thickness 0.15)
				)
			)
		)
		(property "MPN" "CL10A226MO7JZNC"
			(at 0 0 0)
			(unlocked yes)
			(layer "F.Fab")
			(hide yes)
			(effects
				(font
					(size 1 1)
					(thickness 0.15)
				)
			)
		)
		(property "Manufacturer" "Samsung Electro-Mechanics"
			(at 0 0 0)
			(unlocked yes)
			(layer "F.Fab")
			(hide yes)
			(effects
				(font
					(size 1 1)
					(thickness 0.15)
				)
			)
		)
		(property "License" "Apache-2.0"
			(at 0 0 0)
			(unlocked yes)
			(layer "F.Fab")
			(hide yes)
			(effects
				(font
					(size 1 1)
					(thickness 0.15)
				)
			)
		)
		(property "Author" "Antmicro"
			(at 0 0 0)
			(unlocked yes)
			(layer "F.Fab")
			(hide yes)
			(effects
				(font
					(size 1 1)
					(thickness 0.15)
				)
			)
		)
		(property "Val" "22u"
			(at 0 0 0)
			(unlocked yes)
			(layer "F.Fab")
			(hide yes)
			(effects
				(font
					(size 1 1)
					(thickness 0.15)
				)
			)
		)
		(property "Voltage" "16V"
			(at 0 0 0)
			(unlocked yes)
			(layer "F.Fab")
			(hide yes)
			(effects
				(font
					(size 1 1)
					(thickness 0.15)
				)
			)
		)
		(property "Dielectric" ""
			(at 0 0 0)
			(unlocked yes)
			(layer "F.Fab")
			(hide yes)
			(effects
				(font
					(size 1 1)
					(thickness 0.15)
				)
			)
		)
		(property "Public" "False"
			(at 0 0 0)
			(unlocked yes)
			(layer "F.Fab")
			(hide yes)
			(effects
				(font
					(size 1 1)
					(thickness 0.15)
				)
			)
		)
		(sheetname "/Power/")
		(sheetfile "power.kicad_sch")
		(attr smd)
		(fp_line
			(start -0.15 -0.55)
			(end 0.15 -0.55)
			(stroke
				(width 0.15)
				(type solid)
			)
			(layer "F.SilkS")
		)
		(fp_line
			(start -0.15 0.55)
			(end 0.15 0.55)
			(stroke
				(width 0.15)
				(type solid)
			)
			(layer "F.SilkS")
		)
		(fp_rect
			(start -1.25 -0.65)
			(end 1.25 0.65)
			(stroke
				(width 0.05)
				(type solid)
			)
			(fill no)
			(layer "F.CrtYd")
		)
		(fp_rect
			(start -0.8 -0.45)
			(end 0.8 0.45)
			(stroke
				(width 0.15)
				(type solid)
			)
			(fill no)
			(layer "F.Fab")
		)
		(pad "1" smd roundrect
			(at -0.7 0)
			(size 0.8 1.1)
			(layers "F.Cu" "F.Mask" "F.Paste")
			(roundrect_rratio 0.2)
			(net 28 "GND")
			(pintype "passive")
		)
		(pad "2" smd roundrect
			(at 0.7 0)
			(size 0.8 1.1)
			(layers "F.Cu" "F.Mask" "F.Paste")
			(roundrect_rratio 0.2)
			(net 312 "/Power/+1V0_OUT")
			(pintype "passive")
		)
	)
	(footprint "antmicro-footprints:R_0402_1005Metric"
		(layer "F.Cu")
		(at 99.349999 107.099999 180)
		(descr "Resistor SMD 0402")
		(tags "resistor SMD 0402")
		(property "Reference" "R45"
			(at 1.249999 -15.550001 0)
			(layer "F.SilkS")
			(effects
				(font
					(size 0.7 0.7)
					(thickness 0.15)
				)
				(justify left bottom)
			)
		)
		(property "Value" "R_150R_0402"
			(at -1.011843 1.772046 0)
			(layer "F.Fab")
			(hide yes)
			(effects
				(font
					(size 0.7 0.7)
					(thickness 0.15)
				)
				(justify right top)
			)
		)
		(property "Datasheet" "https://www.bourns.com/docs/product-datasheets/cr.pdf"
			(at 0 0 0)
			(layer "F.Fab")
			(hide yes)
			(effects
				(font
					(size 1.27 1.27)
					(thickness 0.15)
				)
			)
		)
		(property "Description" "SMD Chip Resistor, 150 ohm, ± 1%, 62.5 mW, 0402 [1005 Metric], Thick Film, General Purpose"
			(at 0 0 0)
			(layer "F.Fab")
			(hide yes)
			(effects
				(font
					(size 1.27 1.27)
					(thickness 0.15)
				)
			)
		)
		(property "MPN" "CR0402-FX-1500GLF"
			(at 0 0 180)
			(unlocked yes)
			(layer "F.Fab")
			(hide yes)
			(effects
				(font
					(size 1 1)
					(thickness 0.15)
				)
			)
		)
		(property "Manufacturer" "Bourns"
			(at 0 0 180)
			(unlocked yes)
			(layer "F.Fab")
			(hide yes)
			(effects
				(font
					(size 1 1)
					(thickness 0.15)
				)
			)
		)
		(property "License" "Apache-2.0"
			(at 0 0 180)
			(unlocked yes)
			(layer "F.Fab")
			(hide yes)
			(effects
				(font
					(size 1 1)
					(thickness 0.15)
				)
			)
		)
		(property "Author" "Antmicro"
			(at 0 0 180)
			(unlocked yes)
			(layer "F.Fab")
			(hide yes)
			(effects
				(font
					(size 1 1)
					(thickness 0.15)
				)
			)
		)
		(property "Val" "150R"
			(at 0 0 180)
			(unlocked yes)
			(layer "F.Fab")
			(hide yes)
			(effects
				(font
					(size 1 1)
					(thickness 0.15)
				)
			)
		)
		(property "Tolerance" "1%"
			(at 0 0 180)
			(unlocked yes)
			(layer "F.Fab")
			(hide yes)
			(effects
				(font
					(size 1 1)
					(thickness 0.15)
				)
			)
		)
		(sheetname "/X710-AT2 10GbE/")
		(sheetfile "x710-at2-10gbe.kicad_sch")
		(attr smd)
		(fp_rect
			(start -0.925 -0.47)
			(end 0.925 0.47)
			(stroke
				(width 0.05)
				(type default)
			)
			(fill no)
			(layer "F.CrtYd")
		)
		(fp_rect
			(start -0.5 -0.25)
			(end 0.5 0.25)
			(stroke
				(width 0.15)
				(type solid)
			)
			(fill no)
			(layer "F.Fab")
		)
		(pad "1" smd roundrect
			(at -0.48 0 180)
			(size 0.59 0.64)
			(layers "F.Cu" "F.Mask" "F.Paste")
			(roundrect_rratio 0.25)
			(net 28 "GND")
			(pintype "passive")
		)
		(pad "2" smd roundrect
			(at 0.48 0 180)
			(size 0.59 0.64)
			(layers "F.Cu" "F.Mask" "F.Paste")
			(roundrect_rratio 0.25)
			(net 30 "/X710-AT2 10GbE/25MHZ_OSC_AC.+")
			(pintype "passive")
		)
	)
	(footprint "antmicro-footprints:MP_Pad6mm_Drill3.2mm"
		(layer "F.Cu")
		(at 106.975 77.995)
		(property "Reference" "MP6"
			(at 0 -3.2 0)
			(layer "F.SilkS")
			(hide yes)
			(effects
				(font
					(size 0.7 0.7)
					(thickness 0.15)
				)
				(justify left bottom)
			)
		)
		(property "Value" "MP_Pad6mm_Drill3.2mm"
			(at 0 3.9 0)
			(layer "F.Fab")
			(hide yes)
			(effects
				(font
					(size 0.7 0.7)
					(thickness 0.15)
				)
				(justify left bottom)
			)
		)
		(property "Description" "Mechanical part"
			(at 0 0 0)
			(layer "F.Fab")
			(hide yes)
			(effects
				(font
					(size 1.27 1.27)
					(thickness 0.15)
				)
			)
		)
		(property "Author" "Antmicro"
			(at 0 0 0)
			(unlocked yes)
			(layer "F.Fab")
			(hide yes)
			(effects
				(font
					(size 1 1)
					(thickness 0.15)
				)
			)
		)
		(property "License" "Apache-2.0"
			(at 0 0 0)
			(unlocked yes)
			(layer "F.Fab")
			(hide yes)
			(effects
				(font
					(size 1 1)
					(thickness 0.15)
				)
			)
		)
		(sheetname "/")
		(sheetfile "oculink-to-10gbe-adapter.kicad_sch")
		(attr exclude_from_pos_files exclude_from_bom)
		(fp_circle
			(center 0 0)
			(end 3.25 0)
			(stroke
				(width 0.05)
				(type default)
			)
			(fill no)
			(layer "F.CrtYd")
		)
		(fp_text user "License: Apache-2.0"
			(at -0.178 8.425 0)
			(layer "F.Fab")
			(effects
				(font
					(size 0.7 0.7)
					(thickness 0.15)
				)
				(justify left bottom)
			)
		)
		(fp_text user "${REFERENCE}"
			(at -0.178 6.025 0)
			(layer "F.Fab")
			(effects
				(font
					(size 0.7 0.7)
					(thickness 0.15)
				)
				(justify left bottom)
			)
		)
		(fp_text user "Author: Antmicro"
			(at -0.178 7.225 0)
			(layer "F.Fab")
			(effects
				(font
					(size 0.7 0.7)
					(thickness 0.15)
				)
				(justify left bottom)
			)
		)
		(pad "1" thru_hole circle
			(at 0 0)
			(size 6 6)
			(drill 3.2)
			(layers "*.Cu" "*.Mask")
			(remove_unused_layers no)
			(net 28 "GND")
			(pintype "passive")
		)
	)
	(footprint "antmicro-footprints:SOT-23-5"
		(layer "F.Cu")
		(at 115.9 103.4 180)
		(property "Reference" "U6"
			(at -2.05 -1.77 0)
			(layer "F.SilkS")
			(effects
				(font
					(size 0.7 0.7)
					(thickness 0.15)
				)
				(justify right top)
			)
		)
		(property "Value" "LP2985IM5X-5.0_SOT"
			(at 0.002 2.799 0)
			(layer "F.Fab")
			(hide yes)
			(effects
				(font
					(size 0.7 0.7)
					(thickness 0.15)
				)
				(justify right top)
			)
		)
		(property "Datasheet" "https://www.ti.com/lit/ds/symlink/lp2985-n.pdf?ts=1705246249323&ref_url=https%253A%252F%252Fwww.mouser.se%252F"
			(at 0 0 0)
			(layer "F.Fab")
			(hide yes)
			(effects
				(font
					(size 1.27 1.27)
					(thickness 0.15)
				)
			)
		)
		(property "Description" "LDO voltage regulator 150-mA, 16-V, low-dropout voltage regulator with enable 5-SOT-23"
			(at 0 0 0)
			(layer "F.Fab")
			(hide yes)
			(effects
				(font
					(size 1.27 1.27)
					(thickness 0.15)
				)
			)
		)
		(property "MPN" "LP2985IM5X-5.0/NOPB"
			(at 0 0 180)
			(unlocked yes)
			(layer "F.Fab")
			(hide yes)
			(effects
				(font
					(size 1 1)
					(thickness 0.15)
				)
			)
		)
		(property "Manufacturer" "Texas Instruments"
			(at 0 0 180)
			(unlocked yes)
			(layer "F.Fab")
			(hide yes)
			(effects
				(font
					(size 1 1)
					(thickness 0.15)
				)
			)
		)
		(property "Author" "Antmicro"
			(at 0 0 180)
			(unlocked yes)
			(layer "F.Fab")
			(hide yes)
			(effects
				(font
					(size 1 1)
					(thickness 0.15)
				)
			)
		)
		(property "License" "Apache-2.0"
			(at 0 0 180)
			(unlocked yes)
			(layer "F.Fab")
			(hide yes)
			(effects
				(font
					(size 1 1)
					(thickness 0.15)
				)
			)
		)
		(sheetname "/Fan controller/")
		(sheetfile "fan-controller.kicad_sch")
		(attr smd exclude_from_pos_files exclude_from_bom dnp)
		(fp_line
			(start 0.8 1.599)
			(end 0.549 1.599)
			(stroke
				(width 0.15)
				(type solid)
			)
			(layer "F.SilkS")
		)
		(fp_line
			(start 0.8 1.3)
			(end 0.8 1.599)
			(stroke
				(width 0.15)
				(type solid)
			)
			(layer "F.SilkS")
		)
		(fp_line
			(start 0.8 0.55)
			(end 0.8 -0.55)
			(stroke
				(width 0.15)
				(type solid)
			)
			(layer "F.SilkS")
		)
		(fp_line
			(start 0.8 -1.3)
			(end 0.8 -1.6)
			(stroke
				(width 0.15)
				(type solid)
			)
			(layer "F.SilkS")
		)
		(fp_line
			(start 0.8 -1.6)
			(end 0.5 -1.6)
			(stroke
				(width 0.15)
				(type solid)
			)
			(layer "F.SilkS")
		)
		(fp_line
			(start -0.55 1.6)
			(end -0.85 1.6)
			(stroke
				(width 0.15)
				(type solid)
			)
			(layer "F.SilkS")
		)
		(fp_line
			(start -0.8 -1.6)
			(end -0.5 -1.6)
			(stroke
				(width 0.15)
				(type solid)
			)
			(layer "F.SilkS")
		)
		(fp_line
			(start -0.8 -1.6)
			(end -0.8 -1.3)
			(stroke
				(width 0.15)
				(type solid)
			)
			(layer "F.SilkS")
		)
		(fp_line
			(start -0.85 1.6)
			(end -0.85 1.301)
			(stroke
				(width 0.15)
				(type solid)
			)
			(layer "F.SilkS")
		)
		(fp_circle
			(center -1.25 -1.5)
			(end -1.2 -1.5)
			(stroke
				(width 0.15)
				(type solid)
			)
			(fill yes)
			(layer "F.SilkS")
		)
		(fp_rect
			(start 1.9 -1.76)
			(end -1.9 1.75)
			(stroke
				(width 0.05)
				(type solid)
			)
			(fill no)
			(layer "F.CrtYd")
		)
		(fp_line
			(start -0.398 -1.526)
			(end -0.874 -1.05)
			(stroke
				(width 0.15)
				(type solid)
			)
			(layer "F.Fab")
		)
		(fp_rect
			(start 0.874 1.523)
			(end -0.873 -1.525)
			(stroke
				(width 0.15)
				(type solid)
			)
			(fill no)
			(layer "F.Fab")
		)
		(pad "1" smd rect
			(at -1.351 -0.951 90)
			(size 0.55 1)
			(layers "F.Cu" "F.Mask" "F.Paste")
			(net 314 "VCC")
			(pinfunction "IN")
			(pintype "power_in")
		)
		(pad "2" smd rect
			(at -1.351 0 90)
			(size 0.55 1)
			(layers "F.Cu" "F.Mask" "F.Paste")
			(net 28 "GND")
			(pinfunction "GND")
			(pintype "power_in")
		)
		(pad "3" smd rect
			(at -1.351 0.949 90)
			(size 0.55 1)
			(layers "F.Cu" "F.Mask" "F.Paste")
			(net 314 "VCC")
			(pinfunction "EN")
			(pintype "input")
		)
		(pad "4" smd rect
			(at 1.35 0.949 90)
			(size 0.55 1)
			(layers "F.Cu" "F.Mask" "F.Paste")
			(net 386 "Net-(U6-BYPASS)")
			(pinfunction "BYPASS")
			(pintype "passive")
		)
		(pad "5" smd rect
			(at 1.35 -0.951 90)
			(size 0.55 1)
			(layers "F.Cu" "F.Mask" "F.Paste")
			(net 388 "/Fan controller/+5V")
			(pinfunction "OUT")
			(pintype "power_out")
		)
	)
	(footprint "antmicro-footprints:R_0402_1005Metric"
		(layer "F.Cu")
		(at 70.8 91.305 90)
		(descr "Resistor SMD 0402")
		(tags "resistor SMD 0402")
		(property "Reference" "R102"
			(at 0.785 0.34 90)
			(layer "F.SilkS")
			(effects
				(font
					(size 0.7 0.7)
					(thickness 0.15)
				)
				(justify left bottom)
			)
		)
		(property "Value" "R_22R_0402"
			(at -1.011843 1.772046 90)
			(layer "F.Fab")
			(hide yes)
			(effects
				(font
					(size 0.7 0.7)
					(thickness 0.15)
				)
				(justify left bottom)
			)
		)
		(property "Datasheet" "https://www.bourns.com/docs/product-datasheets/cr.pdf"
			(at 0 0 90)
			(layer "F.Fab")
			(hide yes)
			(effects
				(font
					(size 1.27 1.27)
					(thickness 0.15)
				)
			)
		)
		(property "Description" "SMD Chip Resistor, 22 ohm, ± 1%, 62.5 mW, 0402 [1005 Metric], Thick Film, General Purpose"
			(at 0 0 90)
			(layer "F.Fab")
			(hide yes)
			(effects
				(font
					(size 1.27 1.27)
					(thickness 0.15)
				)
			)
		)
		(property "MPN" "CR0402-FX-22R0GLF"
			(at 0 0 90)
			(unlocked yes)
			(layer "F.Fab")
			(hide yes)
			(effects
				(font
					(size 1 1)
					(thickness 0.15)
				)
			)
		)
		(property "Manufacturer" "Bourns"
			(at 0 0 90)
			(unlocked yes)
			(layer "F.Fab")
			(hide yes)
			(effects
				(font
					(size 1 1)
					(thickness 0.15)
				)
			)
		)
		(property "License" "Apache-2.0"
			(at 0 0 90)
			(unlocked yes)
			(layer "F.Fab")
			(hide yes)
			(effects
				(font
					(size 1 1)
					(thickness 0.15)
				)
			)
		)
		(property "Author" "Antmicro"
			(at 0 0 90)
			(unlocked yes)
			(layer "F.Fab")
			(hide yes)
			(effects
				(font
					(size 1 1)
					(thickness 0.15)
				)
			)
		)
		(property "Val" "22R"
			(at 0 0 90)
			(unlocked yes)
			(layer "F.Fab")
			(hide yes)
			(effects
				(font
					(size 1 1)
					(thickness 0.15)
				)
			)
		)
		(property "Tolerance" "1%"
			(at 0 0 90)
			(unlocked yes)
			(layer "F.Fab")
			(hide yes)
			(effects
				(font
					(size 1 1)
					(thickness 0.15)
				)
			)
		)
		(sheetname "/X710-AT2 Misc/")
		(sheetfile "x710-at2-mics.kicad_sch")
		(attr smd)
		(fp_rect
			(start -0.925 -0.47)
			(end 0.925 0.47)
			(stroke
				(width 0.05)
				(type default)
			)
			(fill no)
			(layer "F.CrtYd")
		)
		(fp_rect
			(start -0.5 -0.25)
			(end 0.5 0.25)
			(stroke
				(width 0.15)
				(type solid)
			)
			(fill no)
			(layer "F.Fab")
		)
		(pad "1" smd roundrect
			(at -0.48 0 90)
			(size 0.59 0.64)
			(layers "F.Cu" "F.Mask" "F.Paste")
			(roundrect_rratio 0.25)
			(net 107 "/X710-AT2 Misc/FLSH_SCK")
			(pintype "passive")
		)
		(pad "2" smd roundrect
			(at 0.48 0 90)
			(size 0.59 0.64)
			(layers "F.Cu" "F.Mask" "F.Paste")
			(roundrect_rratio 0.25)
			(net 106 "/Flash memory/FLASH.CLK")
			(pintype "passive")
		)
	)
	(footprint "antmicro-footprints:C_0603_1608Metric_EIA"
		(layer "F.Cu")
		(at 67.25 115.5 180)
		(descr "Capacitor SMD 0603, IPC-7351 Density Level A")
		(tags "Capacitor 0603")
		(property "Reference" "C170"
			(at 1.22 0.22 0)
			(layer "F.SilkS")
			(effects
				(font
					(size 0.7 0.7)
					(thickness 0.15)
				)
				(justify right top)
			)
		)
		(property "Value" "C_22u_16V_0603"
			(at -1.42757 1.770288 0)
			(layer "F.Fab")
			(hide yes)
			(effects
				(font
					(size 0.7 0.7)
					(thickness 0.15)
				)
				(justify right top)
			)
		)
		(property "Datasheet" "https://product.samsungsem.com/mlcc/CL10A226MO7JZN.do"
			(at 0 0 0)
			(layer "F.Fab")
			(hide yes)
			(effects
				(font
					(size 1.27 1.27)
					(thickness 0.15)
				)
			)
		)
		(property "Description" "SMD Multilayer Ceramic Capacitor"
			(at 0 0 0)
			(layer "F.Fab")
			(hide yes)
			(effects
				(font
					(size 1.27 1.27)
					(thickness 0.15)
				)
			)
		)
		(property "MPN" "CL10A226MO7JZNC"
			(at 0 0 180)
			(unlocked yes)
			(layer "F.Fab")
			(hide yes)
			(effects
				(font
					(size 1 1)
					(thickness 0.15)
				)
			)
		)
		(property "Manufacturer" "Samsung Electro-Mechanics"
			(at 0 0 180)
			(unlocked yes)
			(layer "F.Fab")
			(hide yes)
			(effects
				(font
					(size 1 1)
					(thickness 0.15)
				)
			)
		)
		(property "License" "Apache-2.0"
			(at 0 0 180)
			(unlocked yes)
			(layer "F.Fab")
			(hide yes)
			(effects
				(font
					(size 1 1)
					(thickness 0.15)
				)
			)
		)
		(property "Author" "Antmicro"
			(at 0 0 180)
			(unlocked yes)
			(layer "F.Fab")
			(hide yes)
			(effects
				(font
					(size 1 1)
					(thickness 0.15)
				)
			)
		)
		(property "Val" "22u"
			(at 0 0 180)
			(unlocked yes)
			(layer "F.Fab")
			(hide yes)
			(effects
				(font
					(size 1 1)
					(thickness 0.15)
				)
			)
		)
		(property "Voltage" "16V"
			(at 0 0 180)
			(unlocked yes)
			(layer "F.Fab")
			(hide yes)
			(effects
				(font
					(size 1 1)
					(thickness 0.15)
				)
			)
		)
		(property "Dielectric" ""
			(at 0 0 180)
			(unlocked yes)
			(layer "F.Fab")
			(hide yes)
			(effects
				(font
					(size 1 1)
					(thickness 0.15)
				)
			)
		)
		(sheetname "/X710-AT2 power/")
		(sheetfile "x710-at2-power.kicad_sch")
		(attr smd)
		(fp_line
			(start -0.15 0.55)
			(end 0.15 0.55)
			(stroke
				(width 0.15)
				(type solid)
			)
			(layer "F.SilkS")
		)
		(fp_line
			(start -0.15 -0.55)
			(end 0.15 -0.55)
			(stroke
				(width 0.15)
				(type solid)
			)
			(layer "F.SilkS")
		)
		(fp_rect
			(start -1.25 -0.65)
			(end 1.25 0.65)
			(stroke
				(width 0.05)
				(type solid)
			)
			(fill no)
			(layer "F.CrtYd")
		)
		(fp_rect
			(start -0.8 -0.45)
			(end 0.8 0.45)
			(stroke
				(width 0.15)
				(type solid)
			)
			(fill no)
			(layer "F.Fab")
		)
		(pad "1" smd roundrect
			(at -0.7 0 180)
			(size 0.8 1.1)
			(layers "F.Cu" "F.Mask" "F.Paste")
			(roundrect_rratio 0.2)
			(net 28 "GND")
			(pintype "passive")
		)
		(pad "2" smd roundrect
			(at 0.7 0 180)
			(size 0.8 1.1)
			(layers "F.Cu" "F.Mask" "F.Paste")
			(roundrect_rratio 0.2)
			(net 302 "+1V0")
			(pintype "passive")
		)
	)
	(footprint "antmicro-footprints:R_0402_1005Metric"
		(layer "F.Cu")
		(at 56.1 92.849999 90)
		(descr "Resistor SMD 0402")
		(tags "resistor SMD 0402")
		(property "Reference" "R29"
			(at -1.670001 -1.1 180)
			(layer "F.SilkS")
			(effects
				(font
					(size 0.7 0.7)
					(thickness 0.15)
				)
				(justify left bottom)
			)
		)
		(property "Value" "R_20k_0402"
			(at -1.011843 1.772046 90)
			(layer "F.Fab")
			(hide yes)
			(effects
				(font
					(size 0.7 0.7)
					(thickness 0.15)
				)
				(justify left bottom)
			)
		)
		(property "Datasheet" "https://www.bourns.com/docs/product-datasheets/cr.pdf"
			(at 0 0 90)
			(layer "F.Fab")
			(hide yes)
			(effects
				(font
					(size 1.27 1.27)
					(thickness 0.15)
				)
			)
		)
		(property "Description" "SMD Chip Resistor, 20 kohm, ± 1%, 62.5 mW, 0402 [1005 Metric], Thick Film, General Purpose"
			(at 0 0 90)
			(layer "F.Fab")
			(hide yes)
			(effects
				(font
					(size 1.27 1.27)
					(thickness 0.15)
				)
			)
		)
		(property "MPN" "CR0402-FX-2002GLF"
			(at 0 0 90)
			(unlocked yes)
			(layer "F.Fab")
			(hide yes)
			(effects
				(font
					(size 1 1)
					(thickness 0.15)
				)
			)
		)
		(property "Manufacturer" "Bourns"
			(at 0 0 90)
			(unlocked yes)
			(layer "F.Fab")
			(hide yes)
			(effects
				(font
					(size 1 1)
					(thickness 0.15)
				)
			)
		)
		(property "License" "Apache-2.0"
			(at 0 0 90)
			(unlocked yes)
			(layer "F.Fab")
			(hide yes)
			(effects
				(font
					(size 1 1)
					(thickness 0.15)
				)
			)
		)
		(property "Author" "Antmicro"
			(at 0 0 90)
			(unlocked yes)
			(layer "F.Fab")
			(hide yes)
			(effects
				(font
					(size 1 1)
					(thickness 0.15)
				)
			)
		)
		(property "Val" "20k"
			(at 0 0 90)
			(unlocked yes)
			(layer "F.Fab")
			(hide yes)
			(effects
				(font
					(size 1 1)
					(thickness 0.15)
				)
			)
		)
		(property "Tolerance" "1%"
			(at 0 0 90)
			(unlocked yes)
			(layer "F.Fab")
			(hide yes)
			(effects
				(font
					(size 1 1)
					(thickness 0.15)
				)
			)
		)
		(sheetname "/Power/")
		(sheetfile "power.kicad_sch")
		(attr smd)
		(fp_rect
			(start -0.925 -0.47)
			(end 0.925 0.47)
			(stroke
				(width 0.05)
				(type default)
			)
			(fill no)
			(layer "F.CrtYd")
		)
		(fp_rect
			(start -0.5 -0.25)
			(end 0.5 0.25)
			(stroke
				(width 0.15)
				(type solid)
			)
			(fill no)
			(layer "F.Fab")
		)
		(pad "1" smd roundrect
			(at -0.48 0 90)
			(size 0.59 0.64)
			(layers "F.Cu" "F.Mask" "F.Paste")
			(roundrect_rratio 0.25)
			(net 331 "/Power/DVDD_FB")
			(pintype "passive")
		)
		(pad "2" smd roundrect
			(at 0.48 0 90)
			(size 0.59 0.64)
			(layers "F.Cu" "F.Mask" "F.Paste")
			(roundrect_rratio 0.25)
			(net 311 "/Power/+DVDD_OUT")
			(pintype "passive")
		)
	)
	(footprint "antmicro-footprints:C_0603_1608Metric_EIA"
		(layer "F.Cu")
		(at 51.9 96.199999 -90)
		(descr "Capacitor SMD 0603, IPC-7351 Density Level A")
		(tags "Capacitor 0603")
		(property "Reference" "C41"
			(at 1.190001 0.38 90)
			(layer "F.SilkS")
			(effects
				(font
					(size 0.7 0.7)
					(thickness 0.15)
				)
				(justify right top)
			)
		)
		(property "Value" "C_22u_16V_0603"
			(at -1.42757 1.770288 90)
			(layer "F.Fab")
			(hide yes)
			(effects
				(font
					(size 0.7 0.7)
					(thickness 0.15)
				)
				(justify right top)
			)
		)
		(property "Datasheet" "https://product.samsungsem.com/mlcc/CL10A226MO7JZN.do"
			(at 0 0 90)
			(layer "F.Fab")
			(hide yes)
			(effects
				(font
					(size 1.27 1.27)
					(thickness 0.15)
				)
			)
		)
		(property "Description" "SMD Multilayer Ceramic Capacitor"
			(at 0 0 90)
			(layer "F.Fab")
			(hide yes)
			(effects
				(font
					(size 1.27 1.27)
					(thickness 0.15)
				)
			)
		)
		(property "MPN" "CL10A226MO7JZNC"
			(at 0 0 270)
			(unlocked yes)
			(layer "F.Fab")
			(hide yes)
			(effects
				(font
					(size 1 1)
					(thickness 0.15)
				)
			)
		)
		(property "Manufacturer" "Samsung Electro-Mechanics"
			(at 0 0 270)
			(unlocked yes)
			(layer "F.Fab")
			(hide yes)
			(effects
				(font
					(size 1 1)
					(thickness 0.15)
				)
			)
		)
		(property "License" "Apache-2.0"
			(at 0 0 270)
			(unlocked yes)
			(layer "F.Fab")
			(hide yes)
			(effects
				(font
					(size 1 1)
					(thickness 0.15)
				)
			)
		)
		(property "Author" "Antmicro"
			(at 0 0 270)
			(unlocked yes)
			(layer "F.Fab")
			(hide yes)
			(effects
				(font
					(size 1 1)
					(thickness 0.15)
				)
			)
		)
		(property "Val" "22u"
			(at 0 0 270)
			(unlocked yes)
			(layer "F.Fab")
			(hide yes)
			(effects
				(font
					(size 1 1)
					(thickness 0.15)
				)
			)
		)
		(property "Voltage" "16V"
			(at 0 0 270)
			(unlocked yes)
			(layer "F.Fab")
			(hide yes)
			(effects
				(font
					(size 1 1)
					(thickness 0.15)
				)
			)
		)
		(property "Dielectric" ""
			(at 0 0 270)
			(unlocked yes)
			(layer "F.Fab")
			(hide yes)
			(effects
				(font
					(size 1 1)
					(thickness 0.15)
				)
			)
		)
		(property "Public" "False"
			(at 0 0 270)
			(unlocked yes)
			(layer "F.Fab")
			(hide yes)
			(effects
				(font
					(size 1 1)
					(thickness 0.15)
				)
			)
		)
		(sheetname "/Power/")
		(sheetfile "power.kicad_sch")
		(attr smd)
		(fp_line
			(start -0.15 0.55)
			(end 0.15 0.55)
			(stroke
				(width 0.15)
				(type solid)
			)
			(layer "F.SilkS")
		)
		(fp_line
			(start -0.15 -0.55)
			(end 0.15 -0.55)
			(stroke
				(width 0.15)
				(type solid)
			)
			(layer "F.SilkS")
		)
		(fp_rect
			(start -1.25 -0.65)
			(end 1.25 0.65)
			(stroke
				(width 0.05)
				(type solid)
			)
			(fill no)
			(layer "F.CrtYd")
		)
		(fp_rect
			(start -0.8 -0.45)
			(end 0.8 0.45)
			(stroke
				(width 0.15)
				(type solid)
			)
			(fill no)
			(layer "F.Fab")
		)
		(pad "1" smd roundrect
			(at -0.7 0 270)
			(size 0.8 1.1)
			(layers "F.Cu" "F.Mask" "F.Paste")
			(roundrect_rratio 0.2)
			(net 28 "GND")
			(pintype "passive")
		)
		(pad "2" smd roundrect
			(at 0.7 0 270)
			(size 0.8 1.1)
			(layers "F.Cu" "F.Mask" "F.Paste")
			(roundrect_rratio 0.2)
			(net 314 "VCC")
			(pintype "passive")
		)
	)
	(footprint "antmicro-footprints:C_0402_1005Metric"
		(layer "F.Cu")
		(at 86.43 58.111999 90)
		(descr "Capacitor SMD 0402")
		(tags "capacitor SMD 0402")
		(property "Reference" "C37"
			(at -1.130001 2.41 90)
			(layer "F.SilkS")
			(effects
				(font
					(size 0.7 0.7)
					(thickness 0.15)
				)
				(justify left bottom)
			)
		)
		(property "Value" "C_100n_0402"
			(at -1.022927 2.155213 90)
			(layer "F.Fab")
			(hide yes)
			(effects
				(font
					(size 0.7 0.7)
					(thickness 0.15)
				)
				(justify left bottom)
			)
		)
		(property "Datasheet" "https://www.murata.com/products/productdetail?partno=GRM155R61H104KE14%23"
			(at 0 0 90)
			(layer "F.Fab")
			(hide yes)
			(effects
				(font
					(size 1.27 1.27)
					(thickness 0.15)
				)
			)
		)
		(property "Description" "SMD Multilayer Ceramic Capacitor, 0.1 µF, 50 V, 0402 [1005 Metric], ± 10%, X5R, GRM Series"
			(at 0 0 90)
			(layer "F.Fab")
			(hide yes)
			(effects
				(font
					(size 1.27 1.27)
					(thickness 0.15)
				)
			)
		)
		(property "MPN" "GRM155R61H104KE14D"
			(at 0 0 90)
			(unlocked yes)
			(layer "F.Fab")
			(hide yes)
			(effects
				(font
					(size 1 1)
					(thickness 0.15)
				)
			)
		)
		(property "Val" "100n"
			(at 0 0 90)
			(unlocked yes)
			(layer "F.Fab")
			(hide yes)
			(effects
				(font
					(size 1 1)
					(thickness 0.15)
				)
			)
		)
		(property "Voltage" "50V"
			(at 0 0 90)
			(unlocked yes)
			(layer "F.Fab")
			(hide yes)
			(effects
				(font
					(size 1 1)
					(thickness 0.15)
				)
			)
		)
		(property "Dielectric" "X5R"
			(at 0 0 90)
			(unlocked yes)
			(layer "F.Fab")
			(hide yes)
			(effects
				(font
					(size 1 1)
					(thickness 0.15)
				)
			)
		)
		(property "Manufacturer" "Murata"
			(at 0 0 90)
			(unlocked yes)
			(layer "F.Fab")
			(hide yes)
			(effects
				(font
					(size 1 1)
					(thickness 0.15)
				)
			)
		)
		(property "License" "Apache-2.0"
			(at 0 0 90)
			(unlocked yes)
			(layer "F.Fab")
			(hide yes)
			(effects
				(font
					(size 1 1)
					(thickness 0.15)
				)
			)
		)
		(property "Author" "Antmicro"
			(at 0 0 90)
			(unlocked yes)
			(layer "F.Fab")
			(hide yes)
			(effects
				(font
					(size 1 1)
					(thickness 0.15)
				)
			)
		)
		(sheetname "/Power/")
		(sheetfile "power.kicad_sch")
		(attr smd)
		(fp_rect
			(start -0.925 -0.47)
			(end 0.925 0.47)
			(stroke
				(width 0.05)
				(type default)
			)
			(fill no)
			(layer "F.CrtYd")
		)
		(fp_line
			(start 0.504 -0.25)
			(end 0.504 0.248)
			(stroke
				(width 0.15)
				(type solid)
			)
			(layer "F.Fab")
		)
		(fp_line
			(start -0.494 -0.25)
			(end 0.504 -0.25)
			(stroke
				(width 0.15)
				(type solid)
			)
			(layer "F.Fab")
		)
		(fp_line
			(start 0.504 0.248)
			(end -0.494 0.248)
			(stroke
				(width 0.15)
				(type solid)
			)
			(layer "F.Fab")
		)
		(fp_line
			(start -0.494 0.248)
			(end -0.494 -0.25)
			(stroke
				(width 0.15)
				(type solid)
			)
			(layer "F.Fab")
		)
		(pad "1" smd roundrect
			(at -0.48 0 90)
			(size 0.59 0.64)
			(layers "F.Cu" "F.Mask" "F.Paste")
			(roundrect_rratio 0.25)
			(net 28 "GND")
			(pintype "passive")
		)
		(pad "2" smd roundrect
			(at 0.48 0 90)
			(size 0.59 0.64)
			(layers "F.Cu" "F.Mask" "F.Paste")
			(roundrect_rratio 0.25)
			(net 43 "Net-(C37-Pad2)")
			(pintype "passive")
		)
	)
	(footprint "antmicro-footprints:C_0603_1608Metric_EIA"
		(layer "F.Cu")
		(at 53.25 88.500001 -90)
		(descr "Capacitor SMD 0603, IPC-7351 Density Level A")
		(tags "Capacitor 0603")
		(property "Reference" "C13"
			(at 1.259999 1.37 270)
			(layer "F.SilkS")
			(effects
				(font
					(size 0.7 0.7)
					(thickness 0.15)
				)
				(justify right top)
			)
		)
		(property "Value" "C_22u_16V_0603"
			(at -1.42757 1.770288 90)
			(layer "F.Fab")
			(hide yes)
			(effects
				(font
					(size 0.7 0.7)
					(thickness 0.15)
				)
				(justify right top)
			)
		)
		(property "Datasheet" "https://product.samsungsem.com/mlcc/CL10A226MO7JZN.do"
			(at 0 0 90)
			(layer "F.Fab")
			(hide yes)
			(effects
				(font
					(size 1.27 1.27)
					(thickness 0.15)
				)
			)
		)
		(property "Description" "SMD Multilayer Ceramic Capacitor"
			(at 0 0 90)
			(layer "F.Fab")
			(hide yes)
			(effects
				(font
					(size 1.27 1.27)
					(thickness 0.15)
				)
			)
		)
		(property "MPN" "CL10A226MO7JZNC"
			(at 0 0 270)
			(unlocked yes)
			(layer "F.Fab")
			(hide yes)
			(effects
				(font
					(size 1 1)
					(thickness 0.15)
				)
			)
		)
		(property "Manufacturer" "Samsung Electro-Mechanics"
			(at 0 0 270)
			(unlocked yes)
			(layer "F.Fab")
			(hide yes)
			(effects
				(font
					(size 1 1)
					(thickness 0.15)
				)
			)
		)
		(property "License" "Apache-2.0"
			(at 0 0 270)
			(unlocked yes)
			(layer "F.Fab")
			(hide yes)
			(effects
				(font
					(size 1 1)
					(thickness 0.15)
				)
			)
		)
		(property "Author" "Antmicro"
			(at 0 0 270)
			(unlocked yes)
			(layer "F.Fab")
			(hide yes)
			(effects
				(font
					(size 1 1)
					(thickness 0.15)
				)
			)
		)
		(property "Val" "22u"
			(at 0 0 270)
			(unlocked yes)
			(layer "F.Fab")
			(hide yes)
			(effects
				(font
					(size 1 1)
					(thickness 0.15)
				)
			)
		)
		(property "Voltage" "16V"
			(at 0 0 270)
			(unlocked yes)
			(layer "F.Fab")
			(hide yes)
			(effects
				(font
					(size 1 1)
					(thickness 0.15)
				)
			)
		)
		(property "Dielectric" ""
			(at 0 0 270)
			(unlocked yes)
			(layer "F.Fab")
			(hide yes)
			(effects
				(font
					(size 1 1)
					(thickness 0.15)
				)
			)
		)
		(property "Public" "False"
			(at 0 0 270)
			(unlocked yes)
			(layer "F.Fab")
			(hide yes)
			(effects
				(font
					(size 1 1)
					(thickness 0.15)
				)
			)
		)
		(sheetname "/Power/")
		(sheetfile "power.kicad_sch")
		(attr smd)
		(fp_line
			(start -0.15 0.55)
			(end 0.15 0.55)
			(stroke
				(width 0.15)
				(type solid)
			)
			(layer "F.SilkS")
		)
		(fp_line
			(start -0.15 -0.55)
			(end 0.15 -0.55)
			(stroke
				(width 0.15)
				(type solid)
			)
			(layer "F.SilkS")
		)
		(fp_rect
			(start -1.25 -0.65)
			(end 1.25 0.65)
			(stroke
				(width 0.05)
				(type solid)
			)
			(fill no)
			(layer "F.CrtYd")
		)
		(fp_rect
			(start -0.8 -0.45)
			(end 0.8 0.45)
			(stroke
				(width 0.15)
				(type solid)
			)
			(fill no)
			(layer "F.Fab")
		)
		(pad "1" smd roundrect
			(at -0.7 0 270)
			(size 0.8 1.1)
			(layers "F.Cu" "F.Mask" "F.Paste")
			(roundrect_rratio 0.2)
			(net 28 "GND")
			(pintype "passive")
		)
		(pad "2" smd roundrect
			(at 0.7 0 270)
			(size 0.8 1.1)
			(layers "F.Cu" "F.Mask" "F.Paste")
			(roundrect_rratio 0.2)
			(net 314 "VCC")
			(pintype "passive")
		)
	)
	(footprint "antmicro-footprints:TP_SMD_0.75mm"
		(layer "F.Cu")
		(at 63.41 65.443001)
		(property "Reference" "TP23"
			(at -1.66 -0.813001 0)
			(layer "F.SilkS")
			(effects
				(font
					(size 0.7 0.7)
					(thickness 0.15)
				)
				(justify left bottom)
			)
		)
		(property "Value" "TP_0.75mm_SMD"
			(at 0 1.2 0)
			(layer "F.Fab")
			(hide yes)
			(effects
				(font
					(size 0.7 0.7)
					(thickness 0.15)
				)
				(justify left bottom)
			)
		)
		(property "Description" "SMT test point"
			(at 0 0 0)
			(layer "F.Fab")
			(hide yes)
			(effects
				(font
					(size 1.27 1.27)
					(thickness 0.15)
				)
			)
		)
		(property "MPN" ""
			(at 0 0 0)
			(unlocked yes)
			(layer "F.Fab")
			(hide yes)
			(effects
				(font
					(size 1 1)
					(thickness 0.15)
				)
			)
		)
		(property "Manufacturer" ""
			(at 0 0 0)
			(unlocked yes)
			(layer "F.Fab")
			(hide yes)
			(effects
				(font
					(size 1 1)
					(thickness 0.15)
				)
			)
		)
		(property "Author" "Antmicro"
			(at 0 0 0)
			(unlocked yes)
			(layer "F.Fab")
			(hide yes)
			(effects
				(font
					(size 1 1)
					(thickness 0.15)
				)
			)
		)
		(property "License" "Apache-2.0"
			(at 0 0 0)
			(unlocked yes)
			(layer "F.Fab")
			(hide yes)
			(effects
				(font
					(size 1 1)
					(thickness 0.15)
				)
			)
		)
		(sheetname "/Power/")
		(sheetfile "power.kicad_sch")
		(attr exclude_from_pos_files exclude_from_bom)
		(fp_circle
			(center 0 0)
			(end 0.475 0)
			(stroke
				(width 0.05)
				(type default)
			)
			(fill no)
			(layer "F.CrtYd")
		)
		(pad "1" smd circle
			(at 0 0)
			(size 0.75 0.75)
			(layers "F.Cu" "F.Mask")
			(net 350 "/Power/+12V_IN")
			(pinfunction "1")
			(pintype "passive")
		)
	)
	(footprint "antmicro-footprints:C_0603_1608Metric_EIA"
		(layer "F.Cu")
		(at 60.649997 91.799999)
		(descr "Capacitor SMD 0603, IPC-7351 Density Level A")
		(tags "Capacitor 0603")
		(property "Reference" "C44"
			(at -3.389997 -0.659999 0)
			(layer "F.SilkS")
			(effects
				(font
					(size 0.7 0.7)
					(thickness 0.15)
				)
				(justify left bottom)
			)
		)
		(property "Value" "C_22u_16V_0603"
			(at -1.42757 1.770288 0)
			(layer "F.Fab")
			(hide yes)
			(effects
				(font
					(size 0.7 0.7)
					(thickness 0.15)
				)
				(justify left bottom)
			)
		)
		(property "Datasheet" "https://product.samsungsem.com/mlcc/CL10A226MO7JZN.do"
			(at 0 0 0)
			(layer "F.Fab")
			(hide yes)
			(effects
				(font
					(size 1.27 1.27)
					(thickness 0.15)
				)
			)
		)
		(property "Description" "SMD Multilayer Ceramic Capacitor"
			(at 0 0 0)
			(layer "F.Fab")
			(hide yes)
			(effects
				(font
					(size 1.27 1.27)
					(thickness 0.15)
				)
			)
		)
		(property "MPN" "CL10A226MO7JZNC"
			(at 0 0 0)
			(unlocked yes)
			(layer "F.Fab")
			(hide yes)
			(effects
				(font
					(size 1 1)
					(thickness 0.15)
				)
			)
		)
		(property "Manufacturer" "Samsung Electro-Mechanics"
			(at 0 0 0)
			(unlocked yes)
			(layer "F.Fab")
			(hide yes)
			(effects
				(font
					(size 1 1)
					(thickness 0.15)
				)
			)
		)
		(property "License" "Apache-2.0"
			(at 0 0 0)
			(unlocked yes)
			(layer "F.Fab")
			(hide yes)
			(effects
				(font
					(size 1 1)
					(thickness 0.15)
				)
			)
		)
		(property "Author" "Antmicro"
			(at 0 0 0)
			(unlocked yes)
			(layer "F.Fab")
			(hide yes)
			(effects
				(font
					(size 1 1)
					(thickness 0.15)
				)
			)
		)
		(property "Val" "22u"
			(at 0 0 0)
			(unlocked yes)
			(layer "F.Fab")
			(hide yes)
			(effects
				(font
					(size 1 1)
					(thickness 0.15)
				)
			)
		)
		(property "Voltage" "16V"
			(at 0 0 0)
			(unlocked yes)
			(layer "F.Fab")
			(hide yes)
			(effects
				(font
					(size 1 1)
					(thickness 0.15)
				)
			)
		)
		(property "Dielectric" ""
			(at 0 0 0)
			(unlocked yes)
			(layer "F.Fab")
			(hide yes)
			(effects
				(font
					(size 1 1)
					(thickness 0.15)
				)
			)
		)
		(property "Public" "False"
			(at 0 0 0)
			(unlocked yes)
			(layer "F.Fab")
			(hide yes)
			(effects
				(font
					(size 1 1)
					(thickness 0.15)
				)
			)
		)
		(sheetname "/Power/")
		(sheetfile "power.kicad_sch")
		(attr smd)
		(fp_line
			(start -0.15 -0.55)
			(end 0.15 -0.55)
			(stroke
				(width 0.15)
				(type solid)
			)
			(layer "F.SilkS")
		)
		(fp_line
			(start -0.15 0.55)
			(end 0.15 0.55)
			(stroke
				(width 0.15)
				(type solid)
			)
			(layer "F.SilkS")
		)
		(fp_rect
			(start -1.25 -0.65)
			(end 1.25 0.65)
			(stroke
				(width 0.05)
				(type solid)
			)
			(fill no)
			(layer "F.CrtYd")
		)
		(fp_rect
			(start -0.8 -0.45)
			(end 0.8 0.45)
			(stroke
				(width 0.15)
				(type solid)
			)
			(fill no)
			(layer "F.Fab")
		)
		(pad "1" smd roundrect
			(at -0.7 0)
			(size 0.8 1.1)
			(layers "F.Cu" "F.Mask" "F.Paste")
			(roundrect_rratio 0.2)
			(net 28 "GND")
			(pintype "passive")
		)
		(pad "2" smd roundrect
			(at 0.7 0)
			(size 0.8 1.1)
			(layers "F.Cu" "F.Mask" "F.Paste")
			(roundrect_rratio 0.2)
			(net 311 "/Power/+DVDD_OUT")
			(pintype "passive")
		)
	)
	(footprint "antmicro-footprints:R_0402_1005Metric"
		(layer "F.Cu")
		(at 53.1 85.15 -90)
		(descr "Resistor SMD 0402")
		(tags "resistor SMD 0402")
		(property "Reference" "R10"
			(at -1.04 2.84 90)
			(layer "F.SilkS")
			(effects
				(font
					(size 0.7 0.7)
					(thickness 0.15)
				)
				(justify right top)
			)
		)
		(property "Value" "R_0R_0402"
			(at -1.011843 1.772046 90)
			(layer "F.Fab")
			(hide yes)
			(effects
				(font
					(size 0.7 0.7)
					(thickness 0.15)
				)
				(justify right top)
			)
		)
		(property "Datasheet" "https://industrial.panasonic.com/cdbs/www-data/pdf/RDA0000/AOA0000C301.pdf"
			(at 0 0 90)
			(layer "F.Fab")
			(hide yes)
			(effects
				(font
					(size 1.27 1.27)
					(thickness 0.15)
				)
			)
		)
		(property "Description" "SMD Chip Resistor, Jumper, 0 ohm, 100 mW, 0402 [1005 Metric], Thick Film, General Purpose"
			(at 0 0 90)
			(layer "F.Fab")
			(hide yes)
			(effects
				(font
					(size 1.27 1.27)
					(thickness 0.15)
				)
			)
		)
		(property "MPN" "ERJ2GE0R00X"
			(at 0 0 270)
			(unlocked yes)
			(layer "F.Fab")
			(hide yes)
			(effects
				(font
					(size 1 1)
					(thickness 0.15)
				)
			)
		)
		(property "Manufacturer" "Panasonic"
			(at 0 0 270)
			(unlocked yes)
			(layer "F.Fab")
			(hide yes)
			(effects
				(font
					(size 1 1)
					(thickness 0.15)
				)
			)
		)
		(property "License" "Apache-2.0"
			(at 0 0 270)
			(unlocked yes)
			(layer "F.Fab")
			(hide yes)
			(effects
				(font
					(size 1 1)
					(thickness 0.15)
				)
			)
		)
		(property "Author" "Antmicro"
			(at 0 0 270)
			(unlocked yes)
			(layer "F.Fab")
			(hide yes)
			(effects
				(font
					(size 1 1)
					(thickness 0.15)
				)
			)
		)
		(property "Val" "0R"
			(at 0 0 270)
			(unlocked yes)
			(layer "F.Fab")
			(hide yes)
			(effects
				(font
					(size 1 1)
					(thickness 0.15)
				)
			)
		)
		(property "Tolerance" "~"
			(at 0 0 270)
			(unlocked yes)
			(layer "F.Fab")
			(hide yes)
			(effects
				(font
					(size 1 1)
					(thickness 0.15)
				)
			)
		)
		(property "Current" "1A"
			(at 0 0 270)
			(unlocked yes)
			(layer "F.Fab")
			(hide yes)
			(effects
				(font
					(size 1 1)
					(thickness 0.15)
				)
			)
		)
		(sheetname "/Power/")
		(sheetfile "power.kicad_sch")
		(attr smd)
		(fp_rect
			(start -0.925 -0.47)
			(end 0.925 0.47)
			(stroke
				(width 0.05)
				(type default)
			)
			(fill no)
			(layer "F.CrtYd")
		)
		(fp_rect
			(start -0.5 -0.25)
			(end 0.5 0.25)
			(stroke
				(width 0.15)
				(type solid)
			)
			(fill no)
			(layer "F.Fab")
		)
		(pad "1" smd roundrect
			(at -0.48 0 270)
			(size 0.59 0.64)
			(layers "F.Cu" "F.Mask" "F.Paste")
			(roundrect_rratio 0.25)
			(net 338 "/Power/3V3_PG")
			(pintype "passive")
		)
		(pad "2" smd roundrect
			(at 0.48 0 270)
			(size 0.59 0.64)
			(layers "F.Cu" "F.Mask" "F.Paste")
			(roundrect_rratio 0.25)
			(net 340 "/Power/VCCD_EN")
			(pintype "passive")
		)
	)
	(footprint "antmicro-footprints:C_0603_1608Metric"
		(layer "F.Cu")
		(at 72.9 110.35 90)
		(descr "Capacitor SMD 0603")
		(tags "capacitor 0603")
		(property "Reference" "C165"
			(at -3.62 3.64 90)
			(layer "F.SilkS")
			(effects
				(font
					(size 0.7 0.7)
					(thickness 0.15)
				)
				(justify left bottom)
			)
		)
		(property "Value" "C_10u_10V_X7R_0603"
			(at -1.42757 1.770288 90)
			(layer "F.Fab")
			(hide yes)
			(effects
				(font
					(size 0.7 0.7)
					(thickness 0.15)
				)
				(justify left bottom)
			)
		)
		(property "Datasheet" "https://www.murata.com/products/productdetail?partno=GRM188Z71A106KA73%23"
			(at 0 0 90)
			(layer "F.Fab")
			(hide yes)
			(effects
				(font
					(size 1.27 1.27)
					(thickness 0.15)
				)
			)
		)
		(property "Description" "SMD Multilayer Ceramic Capacitor,  10µF, 10V, 0603, ±10%, X7R"
			(at 0 0 90)
			(layer "F.Fab")
			(hide yes)
			(effects
				(font
					(size 1.27 1.27)
					(thickness 0.15)
				)
			)
		)
		(property "MPN" "GRM188Z71A106KA73D"
			(at 0 0 90)
			(unlocked yes)
			(layer "F.Fab")
			(hide yes)
			(effects
				(font
					(size 1 1)
					(thickness 0.15)
				)
			)
		)
		(property "Val" "10u"
			(at 0 0 90)
			(unlocked yes)
			(layer "F.Fab")
			(hide yes)
			(effects
				(font
					(size 1 1)
					(thickness 0.15)
				)
			)
		)
		(property "Voltage" "10V"
			(at 0 0 90)
			(unlocked yes)
			(layer "F.Fab")
			(hide yes)
			(effects
				(font
					(size 1 1)
					(thickness 0.15)
				)
			)
		)
		(property "Dielectric" "X7R"
			(at 0 0 90)
			(unlocked yes)
			(layer "F.Fab")
			(hide yes)
			(effects
				(font
					(size 1 1)
					(thickness 0.15)
				)
			)
		)
		(property "Manufacturer" "Murata"
			(at 0 0 90)
			(unlocked yes)
			(layer "F.Fab")
			(hide yes)
			(effects
				(font
					(size 1 1)
					(thickness 0.15)
				)
			)
		)
		(property "License" "Apache-2.0"
			(at 0 0 90)
			(unlocked yes)
			(layer "F.Fab")
			(hide yes)
			(effects
				(font
					(size 1 1)
					(thickness 0.15)
				)
			)
		)
		(property "Author" "Antmicro"
			(at 0 0 90)
			(unlocked yes)
			(layer "F.Fab")
			(hide yes)
			(effects
				(font
					(size 1 1)
					(thickness 0.15)
				)
			)
		)
		(sheetname "/X710-AT2 power/")
		(sheetfile "x710-at2-power.kicad_sch")
		(attr smd)
		(fp_line
			(start -0.15 -0.4)
			(end 0.15 -0.4)
			(stroke
				(width 0.15)
				(type solid)
			)
			(layer "F.SilkS")
		)
		(fp_line
			(start -0.15 0.4)
			(end 0.15 0.4)
			(stroke
				(width 0.15)
				(type solid)
			)
			(layer "F.SilkS")
		)
		(fp_rect
			(start -1.25 -0.65)
			(end 1.25 0.65)
			(stroke
				(width 0.05)
				(type solid)
			)
			(fill no)
			(layer "F.CrtYd")
		)
		(fp_rect
			(start -0.8 -0.4)
			(end 0.8 0.4)
			(stroke
				(width 0.15)
				(type solid)
			)
			(fill no)
			(layer "F.Fab")
		)
		(pad "1" smd roundrect
			(at -0.7 0 90)
			(size 0.8 1)
			(layers "F.Cu" "F.Mask" "F.Paste")
			(roundrect_rratio 0.2)
			(net 28 "GND")
			(pintype "passive")
		)
		(pad "2" smd roundrect
			(at 0.7 0 90)
			(size 0.8 1)
			(layers "F.Cu" "F.Mask" "F.Paste")
			(roundrect_rratio 0.2)
			(net 5 "P0_AVDDL")
			(pintype "passive")
		)
	)
	(footprint "antmicro-footprints:C_0603_1608Metric_EIA"
		(layer "F.Cu")
		(at 60.649999 108.55)
		(descr "Capacitor SMD 0603, IPC-7351 Density Level A")
		(tags "Capacitor 0603")
		(property "Reference" "C35"
			(at -3.209999 -1.09 0)
			(layer "F.SilkS")
			(effects
				(font
					(size 0.7 0.7)
					(thickness 0.15)
				)
				(justify left bottom)
			)
		)
		(property "Value" "C_22u_16V_0603"
			(at -1.42757 1.770288 0)
			(layer "F.Fab")
			(hide yes)
			(effects
				(font
					(size 0.7 0.7)
					(thickness 0.15)
				)
				(justify left bottom)
			)
		)
		(property "Datasheet" "https://product.samsungsem.com/mlcc/CL10A226MO7JZN.do"
			(at 0 0 0)
			(layer "F.Fab")
			(hide yes)
			(effects
				(font
					(size 1.27 1.27)
					(thickness 0.15)
				)
			)
		)
		(property "Description" "SMD Multilayer Ceramic Capacitor"
			(at 0 0 0)
			(layer "F.Fab")
			(hide yes)
			(effects
				(font
					(size 1.27 1.27)
					(thickness 0.15)
				)
			)
		)
		(property "MPN" "CL10A226MO7JZNC"
			(at 0 0 0)
			(unlocked yes)
			(layer "F.Fab")
			(hide yes)
			(effects
				(font
					(size 1 1)
					(thickness 0.15)
				)
			)
		)
		(property "Manufacturer" "Samsung Electro-Mechanics"
			(at 0 0 0)
			(unlocked yes)
			(layer "F.Fab")
			(hide yes)
			(effects
				(font
					(size 1 1)
					(thickness 0.15)
				)
			)
		)
		(property "License" "Apache-2.0"
			(at 0 0 0)
			(unlocked yes)
			(layer "F.Fab")
			(hide yes)
			(effects
				(font
					(size 1 1)
					(thickness 0.15)
				)
			)
		)
		(property "Author" "Antmicro"
			(at 0 0 0)
			(unlocked yes)
			(layer "F.Fab")
			(hide yes)
			(effects
				(font
					(size 1 1)
					(thickness 0.15)
				)
			)
		)
		(property "Val" "22u"
			(at 0 0 0)
			(unlocked yes)
			(layer "F.Fab")
			(hide yes)
			(effects
				(font
					(size 1 1)
					(thickness 0.15)
				)
			)
		)
		(property "Voltage" "16V"
			(at 0 0 0)
			(unlocked yes)
			(layer "F.Fab")
			(hide yes)
			(effects
				(font
					(size 1 1)
					(thickness 0.15)
				)
			)
		)
		(property "Dielectric" ""
			(at 0 0 0)
			(unlocked yes)
			(layer "F.Fab")
			(hide yes)
			(effects
				(font
					(size 1 1)
					(thickness 0.15)
				)
			)
		)
		(property "Public" "False"
			(at 0 0 0)
			(unlocked yes)
			(layer "F.Fab")
			(hide yes)
			(effects
				(font
					(size 1 1)
					(thickness 0.15)
				)
			)
		)
		(sheetname "/Power/")
		(sheetfile "power.kicad_sch")
		(attr smd)
		(fp_line
			(start -0.15 -0.55)
			(end 0.15 -0.55)
			(stroke
				(width 0.15)
				(type solid)
			)
			(layer "F.SilkS")
		)
		(fp_line
			(start -0.15 0.55)
			(end 0.15 0.55)
			(stroke
				(width 0.15)
				(type solid)
			)
			(layer "F.SilkS")
		)
		(fp_rect
			(start -1.25 -0.65)
			(end 1.25 0.65)
			(stroke
				(width 0.05)
				(type solid)
			)
			(fill no)
			(layer "F.CrtYd")
		)
		(fp_rect
			(start -0.8 -0.45)
			(end 0.8 0.45)
			(stroke
				(width 0.15)
				(type solid)
			)
			(fill no)
			(layer "F.Fab")
		)
		(pad "1" smd roundrect
			(at -0.7 0)
			(size 0.8 1.1)
			(layers "F.Cu" "F.Mask" "F.Paste")
			(roundrect_rratio 0.2)
			(net 28 "GND")
			(pintype "passive")
		)
		(pad "2" smd roundrect
			(at 0.7 0)
			(size 0.8 1.1)
			(layers "F.Cu" "F.Mask" "F.Paste")
			(roundrect_rratio 0.2)
			(net 312 "/Power/+1V0_OUT")
			(pintype "passive")
		)
	)
	(footprint "antmicro-footprints:C_0402_1005Metric"
		(layer "F.Cu")
		(at 109.35 95.35 -90)
		(descr "Capacitor SMD 0402")
		(tags "capacitor SMD 0402")
		(property "Reference" "C216"
			(at -2.9 -0.334999 90)
			(layer "F.SilkS")
			(effects
				(font
					(size 0.7 0.7)
					(thickness 0.15)
				)
				(justify left bottom)
			)
		)
		(property "Value" "C_10p_0402"
			(at -1.022927 2.155213 90)
			(layer "F.Fab")
			(hide yes)
			(effects
				(font
					(size 0.7 0.7)
					(thickness 0.15)
				)
				(justify right top)
			)
		)
		(property "Datasheet" "https://www.murata.com/products/productdetail?partno=GCM1555C1H100GA16%23"
			(at 0 0 90)
			(layer "F.Fab")
			(hide yes)
			(effects
				(font
					(size 1.27 1.27)
					(thickness 0.15)
				)
			)
		)
		(property "Description" "SMD Multilayer Ceramic Capacitor, 10 pF, 50 V, 0402 [1005 Metric], ± 2%, C0G / NP0, GCM"
			(at 0 0 90)
			(layer "F.Fab")
			(hide yes)
			(effects
				(font
					(size 1.27 1.27)
					(thickness 0.15)
				)
			)
		)
		(property "MPN" "GCM1555C1H100GA16D"
			(at 0 0 270)
			(unlocked yes)
			(layer "F.Fab")
			(hide yes)
			(effects
				(font
					(size 1 1)
					(thickness 0.15)
				)
			)
		)
		(property "Manufacturer" "Murata"
			(at 0 0 270)
			(unlocked yes)
			(layer "F.Fab")
			(hide yes)
			(effects
				(font
					(size 1 1)
					(thickness 0.15)
				)
			)
		)
		(property "License" "Apache-2.0"
			(at 0 0 270)
			(unlocked yes)
			(layer "F.Fab")
			(hide yes)
			(effects
				(font
					(size 1 1)
					(thickness 0.15)
				)
			)
		)
		(property "Author" "Antmicro"
			(at 0 0 270)
			(unlocked yes)
			(layer "F.Fab")
			(hide yes)
			(effects
				(font
					(size 1 1)
					(thickness 0.15)
				)
			)
		)
		(property "Val" "10p"
			(at 0 0 270)
			(unlocked yes)
			(layer "F.Fab")
			(hide yes)
			(effects
				(font
					(size 1 1)
					(thickness 0.15)
				)
			)
		)
		(property "Voltage" "50V"
			(at 0 0 270)
			(unlocked yes)
			(layer "F.Fab")
			(hide yes)
			(effects
				(font
					(size 1 1)
					(thickness 0.15)
				)
			)
		)
		(property "Dielectric" "C0G"
			(at 0 0 270)
			(unlocked yes)
			(layer "F.Fab")
			(hide yes)
			(effects
				(font
					(size 1 1)
					(thickness 0.15)
				)
			)
		)
		(sheetname "/X710-AT2 10GbE/")
		(sheetfile "x710-at2-10gbe.kicad_sch")
		(attr smd)
		(fp_rect
			(start -0.925 -0.47)
			(end 0.925 0.47)
			(stroke
				(width 0.05)
				(type default)
			)
			(fill no)
			(layer "F.CrtYd")
		)
		(fp_line
			(start -0.494 0.248)
			(end -0.494 -0.25)
			(stroke
				(width 0.15)
				(type solid)
			)
			(layer "F.Fab")
		)
		(fp_line
			(start 0.504 0.248)
			(end -0.494 0.248)
			(stroke
				(width 0.15)
				(type solid)
			)
			(layer "F.Fab")
		)
		(fp_line
			(start -0.494 -0.25)
			(end 0.504 -0.25)
			(stroke
				(width 0.15)
				(type solid)
			)
			(layer "F.Fab")
		)
		(fp_line
			(start 0.504 -0.25)
			(end 0.504 0.248)
			(stroke
				(width 0.15)
				(type solid)
			)
			(layer "F.Fab")
		)
		(fp_text user "License: Apache-2.0"
			(at -0.939 5.799 270)
			(layer "F.Fab")
			(effects
				(font
					(size 0.7 0.7)
					(thickness 0.15)
				)
				(justify left bottom)
			)
		)
		(fp_text user "Author: Antmicro"
			(at -0.939 3.399 270)
			(layer "F.Fab")
			(effects
				(font
					(size 0.7 0.7)
					(thickness 0.15)
				)
				(justify left bottom)
			)
		)
		(fp_text user "${REFERENCE}"
			(at -0.939 4.599 270)
			(layer "F.Fab")
			(effects
				(font
					(size 0.7 0.7)
					(thickness 0.15)
				)
				(justify left bottom)
			)
		)
		(pad "1" smd roundrect
			(at -0.48 0 270)
			(size 0.59 0.64)
			(layers "F.Cu" "F.Mask" "F.Paste")
			(roundrect_rratio 0.25)
			(net 28 "GND")
			(pintype "passive")
		)
		(pad "2" smd roundrect
			(at 0.48 0 270)
			(size 0.59 0.64)
			(layers "F.Cu" "F.Mask" "F.Paste")
			(roundrect_rratio 0.25)
			(net 288 "/X710-AT2 10GbE/MDIO0_I2C0.MDC")
			(pintype "passive")
		)
	)
	(footprint "antmicro-footprints:R_0402_1005Metric"
		(layer "F.Cu")
		(at 53.099998 92.85 -90)
		(descr "Resistor SMD 0402")
		(tags "resistor SMD 0402")
		(property "Reference" "R30"
			(at -1.05 2.889998 90)
			(layer "F.SilkS")
			(effects
				(font
					(size 0.7 0.7)
					(thickness 0.15)
				)
				(justify right top)
			)
		)
		(property "Value" "R_0R_0402"
			(at -1.011843 1.772046 90)
			(layer "F.Fab")
			(hide yes)
			(effects
				(font
					(size 0.7 0.7)
					(thickness 0.15)
				)
				(justify right top)
			)
		)
		(property "Datasheet" "https://industrial.panasonic.com/cdbs/www-data/pdf/RDA0000/AOA0000C301.pdf"
			(at 0 0 90)
			(layer "F.Fab")
			(hide yes)
			(effects
				(font
					(size 1.27 1.27)
					(thickness 0.15)
				)
			)
		)
		(property "Description" "SMD Chip Resistor, Jumper, 0 ohm, 100 mW, 0402 [1005 Metric], Thick Film, General Purpose"
			(at 0 0 90)
			(layer "F.Fab")
			(hide yes)
			(effects
				(font
					(size 1.27 1.27)
					(thickness 0.15)
				)
			)
		)
		(property "MPN" "ERJ2GE0R00X"
			(at 0 0 270)
			(unlocked yes)
			(layer "F.Fab")
			(hide yes)
			(effects
				(font
					(size 1 1)
					(thickness 0.15)
				)
			)
		)
		(property "Manufacturer" "Panasonic"
			(at 0 0 270)
			(unlocked yes)
			(layer "F.Fab")
			(hide yes)
			(effects
				(font
					(size 1 1)
					(thickness 0.15)
				)
			)
		)
		(property "License" "Apache-2.0"
			(at 0 0 270)
			(unlocked yes)
			(layer "F.Fab")
			(hide yes)
			(effects
				(font
					(size 1 1)
					(thickness 0.15)
				)
			)
		)
		(property "Author" "Antmicro"
			(at 0 0 270)
			(unlocked yes)
			(layer "F.Fab")
			(hide yes)
			(effects
				(font
					(size 1 1)
					(thickness 0.15)
				)
			)
		)
		(property "Val" "0R"
			(at 0 0 270)
			(unlocked yes)
			(layer "F.Fab")
			(hide yes)
			(effects
				(font
					(size 1 1)
					(thickness 0.15)
				)
			)
		)
		(property "Tolerance" "~"
			(at 0 0 270)
			(unlocked yes)
			(layer "F.Fab")
			(hide yes)
			(effects
				(font
					(size 1 1)
					(thickness 0.15)
				)
			)
		)
		(property "Current" "1A"
			(at 0 0 270)
			(unlocked yes)
			(layer "F.Fab")
			(hide yes)
			(effects
				(font
					(size 1 1)
					(thickness 0.15)
				)
			)
		)
		(sheetname "/Power/")
		(sheetfile "power.kicad_sch")
		(attr smd)
		(fp_rect
			(start -0.925 -0.47)
			(end 0.925 0.47)
			(stroke
				(width 0.05)
				(type default)
			)
			(fill no)
			(layer "F.CrtYd")
		)
		(fp_rect
			(start -0.5 -0.25)
			(end 0.5 0.25)
			(stroke
				(width 0.15)
				(type solid)
			)
			(fill no)
			(layer "F.Fab")
		)
		(pad "1" smd roundrect
			(at -0.48 0 270)
			(size 0.59 0.64)
			(layers "F.Cu" "F.Mask" "F.Paste")
			(roundrect_rratio 0.25)
			(net 341 "/Power/1V0_PG")
			(pintype "passive")
		)
		(pad "2" smd roundrect
			(at 0.48 0 270)
			(size 0.59 0.64)
			(layers "F.Cu" "F.Mask" "F.Paste")
			(roundrect_rratio 0.25)
			(net 376 "/Power/DVDD_EN")
			(pintype "passive")
		)
	)
	(footprint "antmicro-footprints:USON-10_2.5x1mm_P0.5mm"
		(layer "F.Cu")
		(at 97.248 59.985 -90)
		(descr "USON-10 2.5x1mm_ Pitch 0.5mm")
		(tags "USON-10 2.5x1mm Pitch 0.5mm")
		(property "Reference" "D8"
			(at 1.7 0.748 0)
			(layer "F.SilkS")
			(effects
				(font
					(size 0.7 0.7)
					(thickness 0.15)
				)
				(justify left bottom)
			)
		)
		(property "Value" "ESD204DQAR"
			(at 0.018 2.499 90)
			(layer "F.Fab")
			(hide yes)
			(effects
				(font
					(size 0.7 0.7)
					(thickness 0.15)
				)
				(justify right top)
			)
		)
		(property "Datasheet" "https://www.ti.com/lit/ds/symlink/esd204.pdf?ts=1706004844383&ref_url=https%253A%252F%252Fwww.ti.com%252Finterface%252Fdiodes%252Fesd-protection-diodes%252Fproducts.html"
			(at 0 0 90)
			(layer "F.Fab")
			(hide yes)
			(effects
				(font
					(size 1.27 1.27)
					(thickness 0.15)
				)
			)
		)
		(property "Description" "TVS diode array, 30 kV, USON-10, 3.6 V, 0.55 pF"
			(at 0 0 90)
			(layer "F.Fab")
			(hide yes)
			(effects
				(font
					(size 1.27 1.27)
					(thickness 0.15)
				)
			)
		)
		(property "MPN" "ESD204DQAR"
			(at 0 0 270)
			(unlocked yes)
			(layer "F.Fab")
			(hide yes)
			(effects
				(font
					(size 1 1)
					(thickness 0.15)
				)
			)
		)
		(property "Manufacturer" "Texas Instruments"
			(at 0 0 270)
			(unlocked yes)
			(layer "F.Fab")
			(hide yes)
			(effects
				(font
					(size 1 1)
					(thickness 0.15)
				)
			)
		)
		(property "Author" "Antmicro"
			(at 0 0 270)
			(unlocked yes)
			(layer "F.Fab")
			(hide yes)
			(effects
				(font
					(size 1 1)
					(thickness 0.15)
				)
			)
		)
		(property "License" "Apache-2.0"
			(at 0 0 270)
			(unlocked yes)
			(layer "F.Fab")
			(hide yes)
			(effects
				(font
					(size 1 1)
					(thickness 0.15)
				)
			)
		)
		(sheetname "/OCuLink/")
		(sheetfile "oculink.kicad_sch")
		(attr smd)
		(fp_line
			(start 0.498 1.398)
			(end -0.5 1.398)
			(stroke
				(width 0.15)
				(type solid)
			)
			(layer "F.SilkS")
		)
		(fp_line
			(start 0.498 -1.401)
			(end -0.5 -1.401)
			(stroke
				(width 0.15)
				(type solid)
			)
			(layer "F.SilkS")
		)
		(fp_circle
			(center -0.68 -1.27)
			(end -0.63 -1.27)
			(stroke
				(width 0.15)
				(type solid)
			)
			(fill yes)
			(layer "F.SilkS")
		)
		(fp_rect
			(start -0.8 -1.5)
			(end 0.8 1.499)
			(stroke
				(width 0.05)
				(type solid)
			)
			(fill no)
			(layer "F.CrtYd")
		)
		(fp_line
			(start -0.5 1.249)
			(end 0.498 1.249)
			(stroke
				(width 0.15)
				(type solid)
			)
			(layer "F.Fab")
		)
		(fp_line
			(start -0.5 -1)
			(end -0.5 1.249)
			(stroke
				(width 0.15)
				(type solid)
			)
			(layer "F.Fab")
		)
		(fp_line
			(start -0.25 -1.25)
			(end -0.5 -1)
			(stroke
				(width 0.15)
				(type solid)
			)
			(layer "F.Fab")
		)
		(fp_line
			(start 0.498 -1.25)
			(end 0.498 1.249)
			(stroke
				(width 0.15)
				(type solid)
			)
			(layer "F.Fab")
		)
		(fp_line
			(start 0.498 -1.25)
			(end -0.25 -1.25)
			(stroke
				(width 0.15)
				(type solid)
			)
			(layer "F.Fab")
		)
		(pad "1" smd roundrect
			(at -0.387 -1 180)
			(size 0.25 0.55)
			(layers "F.Cu" "F.Mask" "F.Paste")
			(roundrect_rratio 0.25)
			(net 21 "/OCuLink/PCIe_{x4}.TX2+")
			(pintype "passive")
		)
		(pad "2" smd roundrect
			(at -0.387 -0.5 180)
			(size 0.25 0.55)
			(layers "F.Cu" "F.Mask" "F.Paste")
			(roundrect_rratio 0.25)
			(net 22 "/OCuLink/PCIe_{x4}.TX2-")
			(pintype "passive")
		)
		(pad "3" smd roundrect
			(at -0.387 0 180)
			(size 0.4 0.55)
			(layers "F.Cu" "F.Mask" "F.Paste")
			(roundrect_rratio 0.25)
			(net 28 "GND")
			(pintype "power_in")
		)
		(pad "4" smd roundrect
			(at -0.387 0.498 180)
			(size 0.25 0.55)
			(layers "F.Cu" "F.Mask" "F.Paste")
			(roundrect_rratio 0.25)
			(net 25 "/OCuLink/PCIe_{x4}.TX3+")
			(pintype "passive")
		)
		(pad "5" smd roundrect
			(at -0.387 0.998 180)
			(size 0.25 0.55)
			(layers "F.Cu" "F.Mask" "F.Paste")
			(roundrect_rratio 0.25)
			(net 26 "/OCuLink/PCIe_{x4}.TX3-")
			(pintype "passive")
		)
		(pad "6" smd roundrect
			(at 0.385 0.998 180)
			(size 0.25 0.55)
			(layers "F.Cu" "F.Mask" "F.Paste")
			(roundrect_rratio 0.25)
			(net 26 "/OCuLink/PCIe_{x4}.TX3-")
			(pintype "passive")
		)
		(pad "7" smd roundrect
			(at 0.385 0.498 180)
			(size 0.25 0.55)
			(layers "F.Cu" "F.Mask" "F.Paste")
			(roundrect_rratio 0.25)
			(net 25 "/OCuLink/PCIe_{x4}.TX3+")
			(pintype "passive")
		)
		(pad "8" smd roundrect
			(at 0.385 0 180)
			(size 0.4 0.55)
			(layers "F.Cu" "F.Mask" "F.Paste")
			(roundrect_rratio 0.25)
			(net 28 "GND")
			(pintype "passive")
		)
		(pad "9" smd roundrect
			(at 0.385 -0.5 180)
			(size 0.25 0.55)
			(layers "F.Cu" "F.Mask" "F.Paste")
			(roundrect_rratio 0.25)
			(net 22 "/OCuLink/PCIe_{x4}.TX2-")
			(pintype "passive")
		)
		(pad "10" smd roundrect
			(at 0.385 -1 180)
			(size 0.25 0.55)
			(layers "F.Cu" "F.Mask" "F.Paste")
			(roundrect_rratio 0.25)
			(net 21 "/OCuLink/PCIe_{x4}.TX2+")
			(pintype "passive")
		)
	)
	(footprint "antmicro-footprints:VQFN-HR-9_2x1.5mm"
		(layer "F.Cu")
		(at 56.099999 95.75 -90)
		(property "Reference" "U5"
			(at -1.32 0.929999 180)
			(layer "F.SilkS")
			(effects
				(font
					(size 0.7 0.7)
					(thickness 0.15)
				)
				(justify right top)
			)
		)
		(property "Value" "TPS566231P"
			(at -1.45 2.45 90)
			(layer "F.Fab")
			(hide yes)
			(effects
				(font
					(size 0.7 0.7)
					(thickness 0.15)
				)
				(justify right top)
			)
		)
		(property "Datasheet" "https://www.ti.com/lit/ds/symlink/tps566231.pdf"
			(at 0 -0.045 90)
			(layer "F.Fab")
			(hide yes)
			(effects
				(font
					(size 0.7 0.7)
					(thickness 0.15)
				)
				(justify right top)
			)
		)
		(property "Description" "Switching Voltage Regulators 3-V to 18-V, 6-A synchronous buck converter"
			(at -1.45 3.65 90)
			(layer "F.Fab")
			(hide yes)
			(effects
				(font
					(size 0.7 0.7)
					(thickness 0.15)
				)
				(justify right top)
			)
		)
		(property "Manufacturer" "Texas Instruments"
			(at 0 0 270)
			(unlocked yes)
			(layer "F.Fab")
			(hide yes)
			(effects
				(font
					(size 1 1)
					(thickness 0.15)
				)
			)
		)
		(property "MPN" "TPS566231PRQFR"
			(at 0 0 270)
			(unlocked yes)
			(layer "F.Fab")
			(hide yes)
			(effects
				(font
					(size 1 1)
					(thickness 0.15)
				)
			)
		)
		(property "Author" "Antmicro"
			(at 0 0 270)
			(unlocked yes)
			(layer "F.Fab")
			(hide yes)
			(effects
				(font
					(size 1 1)
					(thickness 0.15)
				)
			)
		)
		(property "License" "Apache-2.0"
			(at 0 0 270)
			(unlocked yes)
			(layer "F.Fab")
			(hide yes)
			(effects
				(font
					(size 1 1)
					(thickness 0.15)
				)
			)
		)
		(sheetname "/Power/")
		(sheetfile "power.kicad_sch")
		(attr smd)
		(fp_line
			(start -1 0.945)
			(end -0.695 0.945)
			(stroke
				(width 0.15)
				(type solid)
			)
			(layer "F.SilkS")
		)
		(fp_line
			(start 1 0.945)
			(end 0.2 0.945)
			(stroke
				(width 0.15)
				(type solid)
			)
			(layer "F.SilkS")
		)
		(fp_line
			(start -1 -0.945)
			(end -0.695 -0.945)
			(stroke
				(width 0.15)
				(type solid)
			)
			(layer "F.SilkS")
		)
		(fp_line
			(start 1 -0.945)
			(end 0.695 -0.945)
			(stroke
				(width 0.15)
				(type solid)
			)
			(layer "F.SilkS")
		)
		(fp_circle
			(center -1.18 -0.77)
			(end -1.13 -0.77)
			(stroke
				(width 0.15)
				(type solid)
			)
			(fill yes)
			(layer "F.SilkS")
		)
		(fp_rect
			(start -1.3 -1.05)
			(end 1.3 1.05)
			(stroke
				(width 0.05)
				(type solid)
			)
			(fill no)
			(layer "F.CrtYd")
		)
		(fp_rect
			(start -1 -0.75)
			(end 1 0.75)
			(stroke
				(width 0.15)
				(type solid)
			)
			(fill no)
			(layer "F.Fab")
		)
		(pad "1" smd roundrect
			(at -0.925 -0.5 270)
			(size 0.55 0.25)
			(layers "F.Cu" "F.Mask" "F.Paste")
			(roundrect_rratio 0.125)
			(net 326 "/Power/DVDD_VCC")
			(pinfunction "V_{CC}")
			(pintype "passive")
		)
		(pad "2" smd roundrect
			(at -0.925 0 270)
			(size 0.55 0.25)
			(layers "F.Cu" "F.Mask" "F.Paste")
			(roundrect_rratio 0.125)
			(net 331 "/Power/DVDD_FB")
			(pinfunction "FB")
			(pintype "input")
		)
		(pad "3" smd roundrect
			(at -0.925 0.5 270)
			(size 0.55 0.25)
			(layers "F.Cu" "F.Mask" "F.Paste")
			(roundrect_rratio 0.125)
			(net 376 "/Power/DVDD_EN")
			(pinfunction "EN")
			(pintype "input")
		)
		(pad "4" smd roundrect
			(at -0.25 0.45 270)
			(size 0.25 1)
			(layers "F.Cu" "F.Mask" "F.Paste")
			(roundrect_rratio 0.125)
			(net 28 "GND")
			(pinfunction "PGND")
			(pintype "power_in")
		)
		(pad "5" smd roundrect
			(at 0.925 0.5 270)
			(size 0.55 0.25)
			(layers "F.Cu" "F.Mask" "F.Paste")
			(roundrect_rratio 0.125)
			(net 314 "VCC")
			(pinfunction "V_{IN}")
			(pintype "power_in")
		)
		(pad "6" smd roundrect
			(at 0.925 0 270)
			(size 0.55 0.25)
			(layers "F.Cu" "F.Mask" "F.Paste")
			(roundrect_rratio 0.125)
			(net 314 "VCC")
			(pinfunction "V_{IN}")
			(pintype "passive")
		)
		(pad "7" smd roundrect
			(at 0.925 -0.5 270)
			(size 0.55 0.25)
			(layers "F.Cu" "F.Mask" "F.Paste")
			(roundrect_rratio 0.125)
			(net 325 "/Power/DVDD_BST")
			(pinfunction "BST")
			(pintype "passive")
		)
		(pad "8" smd roundrect
			(at 0.25 -0.3 270)
			(size 0.25 1.3)
			(layers "F.Cu" "F.Mask" "F.Paste")
			(roundrect_rratio 0.125)
			(net 336 "/Power/DVDD_SW")
			(pinfunction "SW")
			(pintype "power_out")
		)
		(pad "9" smd roundrect
			(at -0.25 -0.675 270)
			(size 0.25 0.55)
			(layers "F.Cu" "F.Mask" "F.Paste")
			(roundrect_rratio 0.125)
			(net 378 "/Power/DVDD_PG")
			(pinfunction "PG")
			(pintype "passive")
		)
	)
	(footprint "antmicro-footprints:R_0402_1005Metric"
		(layer "F.Cu")
		(at 85.07 115)
		(descr "Resistor SMD 0402")
		(tags "resistor SMD 0402")
		(property "Reference" "RT1"
			(at -0.97 0.55 0)
			(layer "F.SilkS")
			(effects
				(font
					(size 0.7 0.7)
					(thickness 0.15)
				)
				(justify left top)
			)
		)
		(property "Value" "RT_NTC_10k_0402"
			(at -1.011843 1.772047 0)
			(layer "F.Fab")
			(hide yes)
			(effects
				(font
					(size 0.7 0.7)
					(thickness 0.15)
				)
				(justify left bottom)
			)
		)
		(property "Datasheet" "https://eu.mouser.com/datasheet/2/281/r44e-522712.pdf"
			(at 0 0 0)
			(layer "F.Fab")
			(hide yes)
			(effects
				(font
					(size 1.27 1.27)
					(thickness 0.15)
				)
			)
		)
		(property "Description" "10k NTC in 0402 package with 5V max voltage"
			(at 0 0 0)
			(layer "F.Fab")
			(hide yes)
			(effects
				(font
					(size 1.27 1.27)
					(thickness 0.15)
				)
			)
		)
		(property "MPN" "NCP15XH103F03RC"
			(at 0 0 0)
			(unlocked yes)
			(layer "F.Fab")
			(hide yes)
			(effects
				(font
					(size 1 1)
					(thickness 0.15)
				)
			)
		)
		(property "Manufacturer" "Murata"
			(at 0 0 0)
			(unlocked yes)
			(layer "F.Fab")
			(hide yes)
			(effects
				(font
					(size 1 1)
					(thickness 0.15)
				)
			)
		)
		(property "License" "Apache-2.0"
			(at 0 0 0)
			(unlocked yes)
			(layer "F.Fab")
			(hide yes)
			(effects
				(font
					(size 1 1)
					(thickness 0.15)
				)
			)
		)
		(property "Author" "Antmicro"
			(at 0 0 0)
			(unlocked yes)
			(layer "F.Fab")
			(hide yes)
			(effects
				(font
					(size 1 1)
					(thickness 0.15)
				)
			)
		)
		(property "Val" "10k"
			(at 0 0 0)
			(unlocked yes)
			(layer "F.Fab")
			(hide yes)
			(effects
				(font
					(size 1 1)
					(thickness 0.15)
				)
			)
		)
		(property "Voltage" "5V"
			(at 0 0 0)
			(unlocked yes)
			(layer "F.Fab")
			(hide yes)
			(effects
				(font
					(size 1 1)
					(thickness 0.15)
				)
			)
		)
		(sheetname "/Fan controller/")
		(sheetfile "fan-controller.kicad_sch")
		(attr smd exclude_from_pos_files exclude_from_bom dnp)
		(fp_rect
			(start -0.925 -0.47)
			(end 0.925 0.47)
			(stroke
				(width 0.05)
				(type default)
			)
			(fill no)
			(layer "F.CrtYd")
		)
		(fp_rect
			(start -0.5 -0.25)
			(end 0.5 0.25)
			(stroke
				(width 0.15)
				(type solid)
			)
			(fill no)
			(layer "F.Fab")
		)
		(pad "1" smd roundrect
			(at -0.48 0)
			(size 0.59 0.64)
			(layers "F.Cu" "F.Mask" "F.Paste")
			(roundrect_rratio 0.25)
			(net 397 "Net-(R175-Pad1)")
			(pintype "passive")
		)
		(pad "2" smd roundrect
			(at 0.48 0)
			(size 0.59 0.64)
			(layers "F.Cu" "F.Mask" "F.Paste")
			(roundrect_rratio 0.25)
			(net 28 "GND")
			(pintype "passive")
		)
	)
	(footprint "antmicro-footprints:R_0402_1005Metric"
		(layer "F.Cu")
		(at 99.35 103.3 180)
		(descr "Resistor SMD 0402")
		(tags "resistor SMD 0402")
		(property "Reference" "R80"
			(at 1.25 -15.05 0)
			(layer "F.SilkS")
			(effects
				(font
					(size 0.7 0.7)
					(thickness 0.15)
				)
				(justify left bottom)
			)
		)
		(property "Value" "R_100k_0402"
			(at -1.011843 1.772046 0)
			(layer "F.Fab")
			(hide yes)
			(effects
				(font
					(size 0.7 0.7)
					(thickness 0.15)
				)
				(justify right top)
			)
		)
		(property "Datasheet" "https://www.bourns.com/docs/product-datasheets/cr.pdf"
			(at 0 0 0)
			(layer "F.Fab")
			(hide yes)
			(effects
				(font
					(size 1.27 1.27)
					(thickness 0.15)
				)
			)
		)
		(property "Description" "SMD Chip Resistor, 100 kohm, ± 1%, 62.5 mW, 0402 [1005 Metric], Thick Film, General Purpose"
			(at 0 0 0)
			(layer "F.Fab")
			(hide yes)
			(effects
				(font
					(size 1.27 1.27)
					(thickness 0.15)
				)
			)
		)
		(property "MPN" "CR0402-FX-1003GLF"
			(at 0 0 180)
			(unlocked yes)
			(layer "F.Fab")
			(hide yes)
			(effects
				(font
					(size 1 1)
					(thickness 0.15)
				)
			)
		)
		(property "Manufacturer" "Bourns"
			(at 0 0 180)
			(unlocked yes)
			(layer "F.Fab")
			(hide yes)
			(effects
				(font
					(size 1 1)
					(thickness 0.15)
				)
			)
		)
		(property "License" "Apache-2.0"
			(at 0 0 180)
			(unlocked yes)
			(layer "F.Fab")
			(hide yes)
			(effects
				(font
					(size 1 1)
					(thickness 0.15)
				)
			)
		)
		(property "Author" "Antmicro"
			(at 0 0 180)
			(unlocked yes)
			(layer "F.Fab")
			(hide yes)
			(effects
				(font
					(size 1 1)
					(thickness 0.15)
				)
			)
		)
		(property "Val" "100k"
			(at 0 0 180)
			(unlocked yes)
			(layer "F.Fab")
			(hide yes)
			(effects
				(font
					(size 1 1)
					(thickness 0.15)
				)
			)
		)
		(property "Tolerance" "1%"
			(at 0 0 180)
			(unlocked yes)
			(layer "F.Fab")
			(hide yes)
			(effects
				(font
					(size 1 1)
					(thickness 0.15)
				)
			)
		)
		(sheetname "/X710-AT2 Misc/")
		(sheetfile "x710-at2-mics.kicad_sch")
		(attr smd)
		(fp_rect
			(start -0.925 -0.47)
			(end 0.925 0.47)
			(stroke
				(width 0.05)
				(type default)
			)
			(fill no)
			(layer "F.CrtYd")
		)
		(fp_rect
			(start -0.5 -0.25)
			(end 0.5 0.25)
			(stroke
				(width 0.15)
				(type solid)
			)
			(fill no)
			(layer "F.Fab")
		)
		(pad "1" smd roundrect
			(at -0.48 0 180)
			(size 0.59 0.64)
			(layers "F.Cu" "F.Mask" "F.Paste")
			(roundrect_rratio 0.25)
			(net 362 "/X710-AT2 Misc/NCSI.RXD_0")
			(pintype "passive")
		)
		(pad "2" smd roundrect
			(at 0.48 0 180)
			(size 0.59 0.64)
			(layers "F.Cu" "F.Mask" "F.Paste")
			(roundrect_rratio 0.25)
			(net 7 "+3V3")
			(pintype "passive")
		)
	)
	(footprint "antmicro-footprints:R_0402_1005Metric"
		(layer "F.Cu")
		(at 91.1 112.45 -90)
		(descr "Resistor SMD 0402")
		(tags "resistor SMD 0402")
		(property "Reference" "R171"
			(at 0.85 -0.4875 90)
			(layer "F.SilkS")
			(effects
				(font
					(size 0.7 0.7)
					(thickness 0.15)
				)
				(justify right bottom)
			)
		)
		(property "Value" "R_2k_0402"
			(at -1.011843 1.772046 90)
			(layer "F.Fab")
			(hide yes)
			(effects
				(font
					(size 0.7 0.7)
					(thickness 0.15)
				)
				(justify right top)
			)
		)
		(property "Datasheet" "https://www.bourns.com/docs/product-datasheets/cr.pdf"
			(at 0 0 90)
			(layer "F.Fab")
			(hide yes)
			(effects
				(font
					(size 1.27 1.27)
					(thickness 0.15)
				)
			)
		)
		(property "Description" "SMD Chip Resistor, 2 kohm, ± 1%, 62.5 mW, 0402 [1005 Metric], Thick Film, General Purpose"
			(at 0 0 90)
			(layer "F.Fab")
			(hide yes)
			(effects
				(font
					(size 1.27 1.27)
					(thickness 0.15)
				)
			)
		)
		(property "MPN" "CR0402-FX-2001GLF"
			(at 0 0 270)
			(unlocked yes)
			(layer "F.Fab")
			(hide yes)
			(effects
				(font
					(size 1 1)
					(thickness 0.15)
				)
			)
		)
		(property "Manufacturer" "Bourns"
			(at 0 0 270)
			(unlocked yes)
			(layer "F.Fab")
			(hide yes)
			(effects
				(font
					(size 1 1)
					(thickness 0.15)
				)
			)
		)
		(property "License" "Apache-2.0"
			(at 0 0 270)
			(unlocked yes)
			(layer "F.Fab")
			(hide yes)
			(effects
				(font
					(size 1 1)
					(thickness 0.15)
				)
			)
		)
		(property "Author" "Antmicro"
			(at 0 0 270)
			(unlocked yes)
			(layer "F.Fab")
			(hide yes)
			(effects
				(font
					(size 1 1)
					(thickness 0.15)
				)
			)
		)
		(property "Val" "2k"
			(at 0 0 270)
			(unlocked yes)
			(layer "F.Fab")
			(hide yes)
			(effects
				(font
					(size 1 1)
					(thickness 0.15)
				)
			)
		)
		(property "Tolerance" "1%"
			(at 0 0 270)
			(unlocked yes)
			(layer "F.Fab")
			(hide yes)
			(effects
				(font
					(size 1 1)
					(thickness 0.15)
				)
			)
		)
		(sheetname "/X710-AT2 Misc/")
		(sheetfile "x710-at2-mics.kicad_sch")
		(attr smd)
		(fp_rect
			(start -0.925 -0.47)
			(end 0.925 0.47)
			(stroke
				(width 0.05)
				(type default)
			)
			(fill no)
			(layer "F.CrtYd")
		)
		(fp_rect
			(start -0.5 -0.25)
			(end 0.5 0.25)
			(stroke
				(width 0.15)
				(type solid)
			)
			(fill no)
			(layer "F.Fab")
		)
		(pad "1" smd roundrect
			(at -0.48 0 270)
			(size 0.59 0.64)
			(layers "F.Cu" "F.Mask" "F.Paste")
			(roundrect_rratio 0.25)
			(net 380 "/X710-AT2 10GbE/~{PHY_RESET_3V3}")
			(pintype "passive")
		)
		(pad "2" smd roundrect
			(at 0.48 0 270)
			(size 0.59 0.64)
			(layers "F.Cu" "F.Mask" "F.Paste")
			(roundrect_rratio 0.25)
			(net 7 "+3V3")
			(pintype "passive")
		)
	)
	(footprint "antmicro-footprints:C_0603_1608Metric_EIA"
		(layer "F.Cu")
		(at 66.7 87.699999 180)
		(descr "Capacitor SMD 0603, IPC-7351 Density Level A")
		(tags "Capacitor 0603")
		(property "Reference" "C126"
			(at 0.99 0.539999 0)
			(layer "F.SilkS")
			(effects
				(font
					(size 0.7 0.7)
					(thickness 0.15)
				)
				(justify right top)
			)
		)
		(property "Value" "C_22u_16V_0603"
			(at -1.42757 1.770288 0)
			(layer "F.Fab")
			(hide yes)
			(effects
				(font
					(size 0.7 0.7)
					(thickness 0.15)
				)
				(justify right top)
			)
		)
		(property "Datasheet" "https://product.samsungsem.com/mlcc/CL10A226MO7JZN.do"
			(at 0 0 0)
			(layer "F.Fab")
			(hide yes)
			(effects
				(font
					(size 1.27 1.27)
					(thickness 0.15)
				)
			)
		)
		(property "Description" "SMD Multilayer Ceramic Capacitor"
			(at 0 0 0)
			(layer "F.Fab")
			(hide yes)
			(effects
				(font
					(size 1.27 1.27)
					(thickness 0.15)
				)
			)
		)
		(property "MPN" "CL10A226MO7JZNC"
			(at 0 0 180)
			(unlocked yes)
			(layer "F.Fab")
			(hide yes)
			(effects
				(font
					(size 1 1)
					(thickness 0.15)
				)
			)
		)
		(property "Manufacturer" "Samsung Electro-Mechanics"
			(at 0 0 180)
			(unlocked yes)
			(layer "F.Fab")
			(hide yes)
			(effects
				(font
					(size 1 1)
					(thickness 0.15)
				)
			)
		)
		(property "License" "Apache-2.0"
			(at 0 0 180)
			(unlocked yes)
			(layer "F.Fab")
			(hide yes)
			(effects
				(font
					(size 1 1)
					(thickness 0.15)
				)
			)
		)
		(property "Author" "Antmicro"
			(at 0 0 180)
			(unlocked yes)
			(layer "F.Fab")
			(hide yes)
			(effects
				(font
					(size 1 1)
					(thickness 0.15)
				)
			)
		)
		(property "Val" "22u"
			(at 0 0 180)
			(unlocked yes)
			(layer "F.Fab")
			(hide yes)
			(effects
				(font
					(size 1 1)
					(thickness 0.15)
				)
			)
		)
		(property "Voltage" "16V"
			(at 0 0 180)
			(unlocked yes)
			(layer "F.Fab")
			(hide yes)
			(effects
				(font
					(size 1 1)
					(thickness 0.15)
				)
			)
		)
		(property "Dielectric" ""
			(at 0 0 180)
			(unlocked yes)
			(layer "F.Fab")
			(hide yes)
			(effects
				(font
					(size 1 1)
					(thickness 0.15)
				)
			)
		)
		(sheetname "/X710-AT2 power/")
		(sheetfile "x710-at2-power.kicad_sch")
		(attr smd)
		(fp_line
			(start -0.15 0.55)
			(end 0.15 0.55)
			(stroke
				(width 0.15)
				(type solid)
			)
			(layer "F.SilkS")
		)
		(fp_line
			(start -0.15 -0.55)
			(end 0.15 -0.55)
			(stroke
				(width 0.15)
				(type solid)
			)
			(layer "F.SilkS")
		)
		(fp_rect
			(start -1.25 -0.65)
			(end 1.25 0.65)
			(stroke
				(width 0.05)
				(type solid)
			)
			(fill no)
			(layer "F.CrtYd")
		)
		(fp_rect
			(start -0.8 -0.45)
			(end 0.8 0.45)
			(stroke
				(width 0.15)
				(type solid)
			)
			(fill no)
			(layer "F.Fab")
		)
		(pad "1" smd roundrect
			(at -0.7 0 180)
			(size 0.8 1.1)
			(layers "F.Cu" "F.Mask" "F.Paste")
			(roundrect_rratio 0.2)
			(net 28 "GND")
			(pintype "passive")
		)
		(pad "2" smd roundrect
			(at 0.7 0 180)
			(size 0.8 1.1)
			(layers "F.Cu" "F.Mask" "F.Paste")
			(roundrect_rratio 0.2)
			(net 9 "VCCD")
			(pintype "passive")
		)
	)
	(footprint "antmicro-footprints:FB_0603_1608Metric"
		(layer "F.Cu")
		(at 67.25 109.15)
		(property "Reference" "FB5"
			(at -2.56 -0.53 0)
			(layer "F.SilkS")
			(effects
				(font
					(size 0.7 0.7)
					(thickness 0.15)
				)
				(justify left bottom)
			)
		)
		(property "Value" "FB_33Z_3A_Murata-BLM18PG_0603"
			(at 0 1.5 0)
			(layer "F.Fab")
			(hide yes)
			(effects
				(font
					(size 0.7 0.7)
					(thickness 0.15)
				)
				(justify left bottom)
			)
		)
		(property "Datasheet" "https://www.murata.com/products/productdata/8796737273886/QNFA9101.pdf?1649080818000"
			(at 0 0 0)
			(layer "F.Fab")
			(hide yes)
			(effects
				(font
					(size 1.27 1.27)
					(thickness 0.15)
				)
			)
		)
		(property "Description" "Ferrite Bead, 0603 [1608 Metric], 33 ohm, 3 A, BLM18PG, 0.025 ohm, ± 25%, DC power line"
			(at 0 0 0)
			(layer "F.Fab")
			(hide yes)
			(effects
				(font
					(size 1.27 1.27)
					(thickness 0.15)
				)
			)
		)
		(property "Val" "33Z/3A"
			(at 0 0 0)
			(unlocked yes)
			(layer "F.Fab")
			(hide yes)
			(effects
				(font
					(size 1 1)
					(thickness 0.15)
				)
			)
		)
		(property "MPN" "BLM18PG330SH1D"
			(at 0 0 0)
			(unlocked yes)
			(layer "F.Fab")
			(hide yes)
			(effects
				(font
					(size 1 1)
					(thickness 0.15)
				)
			)
		)
		(property "Manufacturer" "Murata"
			(at 0 0 0)
			(unlocked yes)
			(layer "F.Fab")
			(hide yes)
			(effects
				(font
					(size 1 1)
					(thickness 0.15)
				)
			)
		)
		(property "Current" ""
			(at 0 0 0)
			(unlocked yes)
			(layer "F.Fab")
			(hide yes)
			(effects
				(font
					(size 1 1)
					(thickness 0.15)
				)
			)
		)
		(property "Author" "Antmicro"
			(at 0 0 0)
			(unlocked yes)
			(layer "F.Fab")
			(hide yes)
			(effects
				(font
					(size 1 1)
					(thickness 0.15)
				)
			)
		)
		(property "License" "Apache-2.0"
			(at 0 0 0)
			(unlocked yes)
			(layer "F.Fab")
			(hide yes)
			(effects
				(font
					(size 1 1)
					(thickness 0.15)
				)
			)
		)
		(sheetname "/X710-AT2 power/")
		(sheetfile "x710-at2-power.kicad_sch")
		(attr smd)
		(fp_line
			(start -0.15 -0.4)
			(end 0.15 -0.4)
			(stroke
				(width 0.15)
				(type solid)
			)
			(layer "F.SilkS")
		)
		(fp_line
			(start -0.15 0.4)
			(end 0.15 0.4)
			(stroke
				(width 0.15)
				(type solid)
			)
			(layer "F.SilkS")
		)
		(fp_rect
			(start -1.25 -0.65)
			(end 1.25 0.65)
			(stroke
				(width 0.05)
				(type solid)
			)
			(fill no)
			(layer "F.CrtYd")
		)
		(fp_line
			(start -0.803 0.406)
			(end -0.803 -0.408)
			(stroke
				(width 0.15)
				(type solid)
			)
			(layer "F.Fab")
		)
		(fp_line
			(start 0.8 -0.408)
			(end -0.803 -0.408)
			(stroke
				(width 0.15)
				(type solid)
			)
			(layer "F.Fab")
		)
		(fp_line
			(start 0.8 -0.408)
			(end 0.8 0.406)
			(stroke
				(width 0.15)
				(type solid)
			)
			(layer "F.Fab")
		)
		(fp_line
			(start 0.8 0.406)
			(end -0.803 0.406)
			(stroke
				(width 0.15)
				(type solid)
			)
			(layer "F.Fab")
		)
		(pad "1" smd roundrect
			(at -0.7 0)
			(size 0.8 1)
			(layers "F.Cu" "F.Mask" "F.Paste")
			(roundrect_rratio 0.2)
			(net 302 "+1V0")
			(pintype "passive")
		)
		(pad "2" smd roundrect
			(at 0.7 0)
			(size 0.8 1)
			(layers "F.Cu" "F.Mask" "F.Paste")
			(roundrect_rratio 0.2)
			(net 5 "P0_AVDDL")
			(pintype "passive")
		)
	)
	(footprint "antmicro-footprints:R_0402_1005Metric"
		(layer "F.Cu")
		(at 53.161 80.7 90)
		(descr "Resistor SMD 0402")
		(tags "resistor SMD 0402")
		(property "Reference" "R51"
			(at -1.07 1.239 90)
			(layer "F.SilkS")
			(effects
				(font
					(size 0.7 0.7)
					(thickness 0.15)
				)
				(justify left bottom)
			)
		)
		(property "Value" "R_3k3_0402"
			(at -1.011843 1.772046 90)
			(layer "F.Fab")
			(hide yes)
			(effects
				(font
					(size 0.7 0.7)
					(thickness 0.15)
				)
				(justify left bottom)
			)
		)
		(property "Datasheet" "https://www.bourns.com/docs/product-datasheets/cr.pdf"
			(at 0 0 90)
			(layer "F.Fab")
			(hide yes)
			(effects
				(font
					(size 1.27 1.27)
					(thickness 0.15)
				)
			)
		)
		(property "Description" "SMD Chip Resistor, 3.3 kohm, ± 1%, 63 mW, 0402 [1005 Metric], Thick Film, General Purpose"
			(at 0 0 90)
			(layer "F.Fab")
			(hide yes)
			(effects
				(font
					(size 1.27 1.27)
					(thickness 0.15)
				)
			)
		)
		(property "MPN" "CR0402-FX-3301GLF"
			(at 0 0 90)
			(unlocked yes)
			(layer "F.Fab")
			(hide yes)
			(effects
				(font
					(size 1 1)
					(thickness 0.15)
				)
			)
		)
		(property "Manufacturer" "Bourns"
			(at 0 0 90)
			(unlocked yes)
			(layer "F.Fab")
			(hide yes)
			(effects
				(font
					(size 1 1)
					(thickness 0.15)
				)
			)
		)
		(property "License" "Apache-2.0"
			(at 0 0 90)
			(unlocked yes)
			(layer "F.Fab")
			(hide yes)
			(effects
				(font
					(size 1 1)
					(thickness 0.15)
				)
			)
		)
		(property "Author" "Antmicro"
			(at 0 0 90)
			(unlocked yes)
			(layer "F.Fab")
			(hide yes)
			(effects
				(font
					(size 1 1)
					(thickness 0.15)
				)
			)
		)
		(property "Val" "3k3"
			(at 0 0 90)
			(unlocked yes)
			(layer "F.Fab")
			(hide yes)
			(effects
				(font
					(size 1 1)
					(thickness 0.15)
				)
			)
		)
		(property "Tolerance" "1%"
			(at 0 0 90)
			(unlocked yes)
			(layer "F.Fab")
			(hide yes)
			(effects
				(font
					(size 1 1)
					(thickness 0.15)
				)
			)
		)
		(sheetname "/X710-AT2 PCIe/")
		(sheetfile "x710-at2-pcie.kicad_sch")
		(attr smd)
		(fp_rect
			(start -0.925 -0.47)
			(end 0.925 0.47)
			(stroke
				(width 0.05)
				(type default)
			)
			(fill no)
			(layer "F.CrtYd")
		)
		(fp_rect
			(start -0.5 -0.25)
			(end 0.5 0.25)
			(stroke
				(width 0.15)
				(type solid)
			)
			(fill no)
			(layer "F.Fab")
		)
		(pad "1" smd roundrect
			(at -0.48 0 90)
			(size 0.59 0.64)
			(layers "F.Cu" "F.Mask" "F.Paste")
			(roundrect_rratio 0.25)
			(net 8 "/X710-AT2 PCIe/PCIe_JTAG.JTDO")
			(pintype "passive")
		)
		(pad "2" smd roundrect
			(at 0.48 0 90)
			(size 0.59 0.64)
			(layers "F.Cu" "F.Mask" "F.Paste")
			(roundrect_rratio 0.25)
			(net 7 "+3V3")
			(pintype "passive")
		)
	)
	(footprint "antmicro-footprints:TP_SMD_0.75mm"
		(layer "F.Cu")
		(at 79.55 65.443001)
		(property "Reference" "TP24"
			(at 0.35 -0.343001 90)
			(layer "F.SilkS")
			(effects
				(font
					(size 0.7 0.7)
					(thickness 0.15)
				)
				(justify left bottom)
			)
		)
		(property "Value" "TP_0.75mm_SMD"
			(at 0 1.2 0)
			(layer "F.Fab")
			(hide yes)
			(effects
				(font
					(size 0.7 0.7)
					(thickness 0.15)
				)
				(justify left bottom)
			)
		)
		(property "Description" "SMT test point"
			(at 0 0 0)
			(layer "F.Fab")
			(hide yes)
			(effects
				(font
					(size 1.27 1.27)
					(thickness 0.15)
				)
			)
		)
		(property "MPN" ""
			(at 0 0 0)
			(unlocked yes)
			(layer "F.Fab")
			(hide yes)
			(effects
				(font
					(size 1 1)
					(thickness 0.15)
				)
			)
		)
		(property "Manufacturer" ""
			(at 0 0 0)
			(unlocked yes)
			(layer "F.Fab")
			(hide yes)
			(effects
				(font
					(size 1 1)
					(thickness 0.15)
				)
			)
		)
		(property "Author" "Antmicro"
			(at 0 0 0)
			(unlocked yes)
			(layer "F.Fab")
			(hide yes)
			(effects
				(font
					(size 1 1)
					(thickness 0.15)
				)
			)
		)
		(property "License" "Apache-2.0"
			(at 0 0 0)
			(unlocked yes)
			(layer "F.Fab")
			(hide yes)
			(effects
				(font
					(size 1 1)
					(thickness 0.15)
				)
			)
		)
		(sheetname "/Power/")
		(sheetfile "power.kicad_sch")
		(attr exclude_from_pos_files exclude_from_bom)
		(fp_circle
			(center 0 0)
			(end 0.475 0)
			(stroke
				(width 0.05)
				(type default)
			)
			(fill no)
			(layer "F.CrtYd")
		)
		(pad "1" smd circle
			(at 0 0)
			(size 0.75 0.75)
			(layers "F.Cu" "F.Mask")
			(net 351 "/Power/+5V_USB")
			(pinfunction "1")
			(pintype "passive")
		)
	)
	(footprint "antmicro-footprints:R_0402_1005Metric"
		(layer "F.Cu")
		(at 116.95 106.55 180)
		(descr "Resistor SMD 0402")
		(tags "resistor SMD 0402")
		(property "Reference" "R181"
			(at 0.85 0.45 0)
			(layer "F.SilkS")
			(effects
				(font
					(size 0.7 0.7)
					(thickness 0.15)
				)
				(justify right top)
			)
		)
		(property "Value" "R_0R_0402"
			(at -1.011843 1.772046 0)
			(layer "F.Fab")
			(hide yes)
			(effects
				(font
					(size 0.7 0.7)
					(thickness 0.15)
				)
				(justify right top)
			)
		)
		(property "Datasheet" "https://industrial.panasonic.com/cdbs/www-data/pdf/RDA0000/AOA0000C301.pdf"
			(at 0 0 0)
			(layer "F.Fab")
			(hide yes)
			(effects
				(font
					(size 1.27 1.27)
					(thickness 0.15)
				)
			)
		)
		(property "Description" "SMD Chip Resistor, Jumper, 0 ohm, 100 mW, 0402 [1005 Metric], Thick Film, General Purpose"
			(at 0 0 0)
			(layer "F.Fab")
			(hide yes)
			(effects
				(font
					(size 1.27 1.27)
					(thickness 0.15)
				)
			)
		)
		(property "MPN" "ERJ2GE0R00X"
			(at 0 0 180)
			(unlocked yes)
			(layer "F.Fab")
			(hide yes)
			(effects
				(font
					(size 1 1)
					(thickness 0.15)
				)
			)
		)
		(property "Manufacturer" "Panasonic"
			(at 0 0 180)
			(unlocked yes)
			(layer "F.Fab")
			(hide yes)
			(effects
				(font
					(size 1 1)
					(thickness 0.15)
				)
			)
		)
		(property "License" "Apache-2.0"
			(at 0 0 180)
			(unlocked yes)
			(layer "F.Fab")
			(hide yes)
			(effects
				(font
					(size 1 1)
					(thickness 0.15)
				)
			)
		)
		(property "Author" "Antmicro"
			(at 0 0 180)
			(unlocked yes)
			(layer "F.Fab")
			(hide yes)
			(effects
				(font
					(size 1 1)
					(thickness 0.15)
				)
			)
		)
		(property "Val" "0R"
			(at 0 0 180)
			(unlocked yes)
			(layer "F.Fab")
			(hide yes)
			(effects
				(font
					(size 1 1)
					(thickness 0.15)
				)
			)
		)
		(property "Tolerance" "~"
			(at 0 0 180)
			(unlocked yes)
			(layer "F.Fab")
			(hide yes)
			(effects
				(font
					(size 1 1)
					(thickness 0.15)
				)
			)
		)
		(property "Current" "1A"
			(at 0 0 180)
			(unlocked yes)
			(layer "F.Fab")
			(hide yes)
			(effects
				(font
					(size 1 1)
					(thickness 0.15)
				)
			)
		)
		(sheetname "/Fan controller/")
		(sheetfile "fan-controller.kicad_sch")
		(attr smd exclude_from_pos_files exclude_from_bom dnp)
		(fp_rect
			(start -0.925 -0.47)
			(end 0.925 0.47)
			(stroke
				(width 0.05)
				(type default)
			)
			(fill no)
			(layer "F.CrtYd")
		)
		(fp_rect
			(start -0.5 -0.25)
			(end 0.5 0.25)
			(stroke
				(width 0.15)
				(type solid)
			)
			(fill no)
			(layer "F.Fab")
		)
		(pad "1" smd roundrect
			(at -0.48 0 180)
			(size 0.59 0.64)
			(layers "F.Cu" "F.Mask" "F.Paste")
			(roundrect_rratio 0.25)
			(net 389 "/Fan controller/V_{FAN}")
			(pintype "passive")
		)
		(pad "2" smd roundrect
			(at 0.48 0 180)
			(size 0.59 0.64)
			(layers "F.Cu" "F.Mask" "F.Paste")
			(roundrect_rratio 0.25)
			(net 314 "VCC")
			(pintype "passive")
		)
	)
	(footprint "antmicro-footprints:R_0402_1005Metric"
		(layer "F.Cu")
		(at 99.16 89.2145 180)
		(descr "Resistor SMD 0402")
		(tags "resistor SMD 0402")
		(property "Reference" "R101"
			(at -1.39 0.4645 0)
			(layer "F.SilkS")
			(effects
				(font
					(size 0.7 0.7)
					(thickness 0.15)
				)
				(justify right bottom)
			)
		)
		(property "Value" "R_0R_0402"
			(at -1.011843 1.772047 0)
			(layer "F.Fab")
			(hide yes)
			(effects
				(font
					(size 0.7 0.7)
					(thickness 0.15)
				)
				(justify right top)
			)
		)
		(property "Datasheet" "https://industrial.panasonic.com/cdbs/www-data/pdf/RDA0000/AOA0000C301.pdf"
			(at 0 0 0)
			(layer "F.Fab")
			(hide yes)
			(effects
				(font
					(size 1.27 1.27)
					(thickness 0.15)
				)
			)
		)
		(property "Description" "SMD Chip Resistor, Jumper, 0 ohm, 100 mW, 0402 [1005 Metric], Thick Film, General Purpose"
			(at 0 0 0)
			(layer "F.Fab")
			(hide yes)
			(effects
				(font
					(size 1.27 1.27)
					(thickness 0.15)
				)
			)
		)
		(property "MPN" "ERJ2GE0R00X"
			(at 0 0 180)
			(unlocked yes)
			(layer "F.Fab")
			(hide yes)
			(effects
				(font
					(size 1 1)
					(thickness 0.15)
				)
			)
		)
		(property "Manufacturer" "Panasonic"
			(at 0 0 180)
			(unlocked yes)
			(layer "F.Fab")
			(hide yes)
			(effects
				(font
					(size 1 1)
					(thickness 0.15)
				)
			)
		)
		(property "License" "Apache-2.0"
			(at 0 0 180)
			(unlocked yes)
			(layer "F.Fab")
			(hide yes)
			(effects
				(font
					(size 1 1)
					(thickness 0.15)
				)
			)
		)
		(property "Author" "Antmicro"
			(at 0 0 180)
			(unlocked yes)
			(layer "F.Fab")
			(hide yes)
			(effects
				(font
					(size 1 1)
					(thickness 0.15)
				)
			)
		)
		(property "Val" "0R"
			(at 0 0 180)
			(unlocked yes)
			(layer "F.Fab")
			(hide yes)
			(effects
				(font
					(size 1 1)
					(thickness 0.15)
				)
			)
		)
		(property "Tolerance" "~"
			(at 0 0 180)
			(unlocked yes)
			(layer "F.Fab")
			(hide yes)
			(effects
				(font
					(size 1 1)
					(thickness 0.15)
				)
			)
		)
		(property "Current" "1A"
			(at 0 0 180)
			(unlocked yes)
			(layer "F.Fab")
			(hide yes)
			(effects
				(font
					(size 1 1)
					(thickness 0.15)
				)
			)
		)
		(sheetname "/X710-AT2 PCIe/")
		(sheetfile "x710-at2-pcie.kicad_sch")
		(attr smd)
		(fp_rect
			(start -0.925 -0.47)
			(end 0.925 0.47)
			(stroke
				(width 0.05)
				(type default)
			)
			(fill no)
			(layer "F.CrtYd")
		)
		(fp_rect
			(start -0.5 -0.25)
			(end 0.5 0.25)
			(stroke
				(width 0.15)
				(type solid)
			)
			(fill no)
			(layer "F.Fab")
		)
		(pad "1" smd roundrect
			(at -0.48 0 180)
			(size 0.59 0.64)
			(layers "F.Cu" "F.Mask" "F.Paste")
			(roundrect_rratio 0.25)
			(net 45 "/OCuLink/REFCLK.-")
			(pintype "passive")
		)
		(pad "2" smd roundrect
			(at 0.48 0 180)
			(size 0.59 0.64)
			(layers "F.Cu" "F.Mask" "F.Paste")
			(roundrect_rratio 0.25)
			(net 403 "/X710-AT2 PCIe/CLK-")
			(pintype "passive")
		)
	)
	(footprint "antmicro-footprints:TP_SMD_0.75mm"
		(layer "F.Cu")
		(at 75.65 68.45)
		(property "Reference" "TP22"
			(at 0.45 -0.45 90)
			(layer "F.SilkS")
			(effects
				(font
					(size 0.7 0.7)
					(thickness 0.15)
				)
				(justify left bottom)
			)
		)
		(property "Value" "TP_0.75mm_SMD"
			(at 0 1.2 0)
			(layer "F.Fab")
			(hide yes)
			(effects
				(font
					(size 0.7 0.7)
					(thickness 0.15)
				)
				(justify left bottom)
			)
		)
		(property "Description" "SMT test point"
			(at 0 0 0)
			(layer "F.Fab")
			(hide yes)
			(effects
				(font
					(size 1.27 1.27)
					(thickness 0.15)
				)
			)
		)
		(property "MPN" ""
			(at 0 0 0)
			(unlocked yes)
			(layer "F.Fab")
			(hide yes)
			(effects
				(font
					(size 1 1)
					(thickness 0.15)
				)
			)
		)
		(property "Manufacturer" ""
			(at 0 0 0)
			(unlocked yes)
			(layer "F.Fab")
			(hide yes)
			(effects
				(font
					(size 1 1)
					(thickness 0.15)
				)
			)
		)
		(property "Author" "Antmicro"
			(at 0 0 0)
			(unlocked yes)
			(layer "F.Fab")
			(hide yes)
			(effects
				(font
					(size 1 1)
					(thickness 0.15)
				)
			)
		)
		(property "License" "Apache-2.0"
			(at 0 0 0)
			(unlocked yes)
			(layer "F.Fab")
			(hide yes)
			(effects
				(font
					(size 1 1)
					(thickness 0.15)
				)
			)
		)
		(sheetname "/Power/")
		(sheetfile "power.kicad_sch")
		(attr exclude_from_pos_files exclude_from_bom)
		(fp_circle
			(center 0 0)
			(end 0.475 0)
			(stroke
				(width 0.05)
				(type default)
			)
			(fill no)
			(layer "F.CrtYd")
		)
		(pad "1" smd circle
			(at 0 0)
			(size 0.75 0.75)
			(layers "F.Cu" "F.Mask")
			(net 314 "VCC")
			(pinfunction "1")
			(pintype "passive")
		)
	)
	(footprint "antmicro-footprints:R_0402_1005Metric"
		(layer "F.Cu")
		(at 110.15 100.1 -90)
		(descr "Resistor SMD 0402")
		(tags "resistor SMD 0402")
		(property "Reference" "R175"
			(at -0.8 -1.45 90)
			(layer "F.SilkS")
			(effects
				(font
					(size 0.7 0.7)
					(thickness 0.15)
				)
				(justify left bottom)
			)
		)
		(property "Value" "R_10k_0402"
			(at -1.011843 1.772046 90)
			(layer "F.Fab")
			(hide yes)
			(effects
				(font
					(size 0.7 0.7)
					(thickness 0.15)
				)
				(justify right top)
			)
		)
		(property "Datasheet" "https://www.bourns.com/docs/product-datasheets/cr.pdf"
			(at 0 0 90)
			(layer "F.Fab")
			(hide yes)
			(effects
				(font
					(size 1.27 1.27)
					(thickness 0.15)
				)
			)
		)
		(property "Description" "SMD Chip Resistor, 10 kohm, ± 1%, 62.5 mW, 0402 [1005 Metric], Thick Film, General Purpose"
			(at 0 0 90)
			(layer "F.Fab")
			(hide yes)
			(effects
				(font
					(size 1.27 1.27)
					(thickness 0.15)
				)
			)
		)
		(property "MPN" "CR0402-FX-1002GLF"
			(at 0 0 270)
			(unlocked yes)
			(layer "F.Fab")
			(hide yes)
			(effects
				(font
					(size 1 1)
					(thickness 0.15)
				)
			)
		)
		(property "Manufacturer" "Bourns"
			(at 0 0 270)
			(unlocked yes)
			(layer "F.Fab")
			(hide yes)
			(effects
				(font
					(size 1 1)
					(thickness 0.15)
				)
			)
		)
		(property "License" "Apache-2.0"
			(at 0 0 270)
			(unlocked yes)
			(layer "F.Fab")
			(hide yes)
			(effects
				(font
					(size 1 1)
					(thickness 0.15)
				)
			)
		)
		(property "Author" "Antmicro"
			(at 0 0 270)
			(unlocked yes)
			(layer "F.Fab")
			(hide yes)
			(effects
				(font
					(size 1 1)
					(thickness 0.15)
				)
			)
		)
		(property "Val" "10k"
			(at 0 0 270)
			(unlocked yes)
			(layer "F.Fab")
			(hide yes)
			(effects
				(font
					(size 1 1)
					(thickness 0.15)
				)
			)
		)
		(property "Tolerance" "1%"
			(at 0 0 270)
			(unlocked yes)
			(layer "F.Fab")
			(hide yes)
			(effects
				(font
					(size 1 1)
					(thickness 0.15)
				)
			)
		)
		(sheetname "/Fan controller/")
		(sheetfile "fan-controller.kicad_sch")
		(attr smd exclude_from_pos_files exclude_from_bom dnp)
		(fp_rect
			(start -0.925 -0.47)
			(end 0.925 0.47)
			(stroke
				(width 0.05)
				(type default)
			)
			(fill no)
			(layer "F.CrtYd")
		)
		(fp_rect
			(start -0.5 -0.25)
			(end 0.5 0.25)
			(stroke
				(width 0.15)
				(type solid)
			)
			(fill no)
			(layer "F.Fab")
		)
		(pad "1" smd roundrect
			(at -0.48 0 270)
			(size 0.59 0.64)
			(layers "F.Cu" "F.Mask" "F.Paste")
			(roundrect_rratio 0.25)
			(net 397 "Net-(R175-Pad1)")
			(pintype "passive")
		)
		(pad "2" smd roundrect
			(at 0.48 0 270)
			(size 0.59 0.64)
			(layers "F.Cu" "F.Mask" "F.Paste")
			(roundrect_rratio 0.25)
			(net 385 "/Fan controller/SENSE")
			(pintype "passive")
		)
	)
	(footprint "antmicro-footprints:C_0603_1608Metric_EIA"
		(layer "F.Cu")
		(at 77.2 86.35 180)
		(descr "Capacitor SMD 0603, IPC-7351 Density Level A")
		(tags "Capacitor 0603")
		(property "Reference" "C151"
			(at -1.4 8.144 0)
			(layer "F.SilkS")
			(effects
				(font
					(size 0.7 0.7)
					(thickness 0.15)
				)
				(justify right top)
			)
		)
		(property "Value" "C_22u_16V_0603"
			(at -1.42757 1.770288 0)
			(layer "F.Fab")
			(hide yes)
			(effects
				(font
					(size 0.7 0.7)
					(thickness 0.15)
				)
				(justify right top)
			)
		)
		(property "Datasheet" "https://product.samsungsem.com/mlcc/CL10A226MO7JZN.do"
			(at 0 0 0)
			(layer "F.Fab")
			(hide yes)
			(effects
				(font
					(size 1.27 1.27)
					(thickness 0.15)
				)
			)
		)
		(property "Description" "SMD Multilayer Ceramic Capacitor"
			(at 0 0 0)
			(layer "F.Fab")
			(hide yes)
			(effects
				(font
					(size 1.27 1.27)
					(thickness 0.15)
				)
			)
		)
		(property "MPN" "CL10A226MO7JZNC"
			(at 0 0 180)
			(unlocked yes)
			(layer "F.Fab")
			(hide yes)
			(effects
				(font
					(size 1 1)
					(thickness 0.15)
				)
			)
		)
		(property "Manufacturer" "Samsung Electro-Mechanics"
			(at 0 0 180)
			(unlocked yes)
			(layer "F.Fab")
			(hide yes)
			(effects
				(font
					(size 1 1)
					(thickness 0.15)
				)
			)
		)
		(property "License" "Apache-2.0"
			(at 0 0 180)
			(unlocked yes)
			(layer "F.Fab")
			(hide yes)
			(effects
				(font
					(size 1 1)
					(thickness 0.15)
				)
			)
		)
		(property "Author" "Antmicro"
			(at 0 0 180)
			(unlocked yes)
			(layer "F.Fab")
			(hide yes)
			(effects
				(font
					(size 1 1)
					(thickness 0.15)
				)
			)
		)
		(property "Val" "22u"
			(at 0 0 180)
			(unlocked yes)
			(layer "F.Fab")
			(hide yes)
			(effects
				(font
					(size 1 1)
					(thickness 0.15)
				)
			)
		)
		(property "Voltage" "16V"
			(at 0 0 180)
			(unlocked yes)
			(layer "F.Fab")
			(hide yes)
			(effects
				(font
					(size 1 1)
					(thickness 0.15)
				)
			)
		)
		(property "Dielectric" ""
			(at 0 0 180)
			(unlocked yes)
			(layer "F.Fab")
			(hide yes)
			(effects
				(font
					(size 1 1)
					(thickness 0.15)
				)
			)
		)
		(sheetname "/X710-AT2 power/")
		(sheetfile "x710-at2-power.kicad_sch")
		(attr smd)
		(fp_line
			(start -0.15 0.55)
			(end 0.15 0.55)
			(stroke
				(width 0.15)
				(type solid)
			)
			(layer "F.SilkS")
		)
		(fp_line
			(start -0.15 -0.55)
			(end 0.15 -0.55)
			(stroke
				(width 0.15)
				(type solid)
			)
			(layer "F.SilkS")
		)
		(fp_rect
			(start -1.25 -0.65)
			(end 1.25 0.65)
			(stroke
				(width 0.05)
				(type solid)
			)
			(fill no)
			(layer "F.CrtYd")
		)
		(fp_rect
			(start -0.8 -0.45)
			(end 0.8 0.45)
			(stroke
				(width 0.15)
				(type solid)
			)
			(fill no)
			(layer "F.Fab")
		)
		(pad "1" smd roundrect
			(at -0.7 0 180)
			(size 0.8 1.1)
			(layers "F.Cu" "F.Mask" "F.Paste")
			(roundrect_rratio 0.2)
			(net 28 "GND")
			(pintype "passive")
		)
		(pad "2" smd roundrect
			(at 0.7 0 180)
			(size 0.8 1.1)
			(layers "F.Cu" "F.Mask" "F.Paste")
			(roundrect_rratio 0.2)
			(net 7 "+3V3")
			(pintype "passive")
		)
	)
	(footprint "antmicro-footprints:R_0402_1005Metric"
		(layer "F.Cu")
		(at 82.25 82.15 180)
		(descr "Resistor SMD 0402")
		(tags "resistor SMD 0402")
		(property "Reference" "R172"
			(at -0.8 -0.35 0)
			(layer "F.SilkS")
			(effects
				(font
					(size 0.7 0.7)
					(thickness 0.15)
				)
				(justify left bottom)
			)
		)
		(property "Value" "R_0R_0402"
			(at -1.011843 1.772046 0)
			(layer "F.Fab")
			(hide yes)
			(effects
				(font
					(size 0.7 0.7)
					(thickness 0.15)
				)
				(justify right top)
			)
		)
		(property "Datasheet" "https://industrial.panasonic.com/cdbs/www-data/pdf/RDA0000/AOA0000C301.pdf"
			(at 0 0 0)
			(layer "F.Fab")
			(hide yes)
			(effects
				(font
					(size 1.27 1.27)
					(thickness 0.15)
				)
			)
		)
		(property "Description" "SMD Chip Resistor, Jumper, 0 ohm, 100 mW, 0402 [1005 Metric], Thick Film, General Purpose"
			(at 0 0 0)
			(layer "F.Fab")
			(hide yes)
			(effects
				(font
					(size 1.27 1.27)
					(thickness 0.15)
				)
			)
		)
		(property "MPN" "ERJ2GE0R00X"
			(at 0 0 180)
			(unlocked yes)
			(layer "F.Fab")
			(hide yes)
			(effects
				(font
					(size 1 1)
					(thickness 0.15)
				)
			)
		)
		(property "Manufacturer" "Panasonic"
			(at 0 0 180)
			(unlocked yes)
			(layer "F.Fab")
			(hide yes)
			(effects
				(font
					(size 1 1)
					(thickness 0.15)
				)
			)
		)
		(property "License" "Apache-2.0"
			(at 0 0 180)
			(unlocked yes)
			(layer "F.Fab")
			(hide yes)
			(effects
				(font
					(size 1 1)
					(thickness 0.15)
				)
			)
		)
		(property "Author" "Antmicro"
			(at 0 0 180)
			(unlocked yes)
			(layer "F.Fab")
			(hide yes)
			(effects
				(font
					(size 1 1)
					(thickness 0.15)
				)
			)
		)
		(property "Val" "0R"
			(at 0 0 180)
			(unlocked yes)
			(layer "F.Fab")
			(hide yes)
			(effects
				(font
					(size 1 1)
					(thickness 0.15)
				)
			)
		)
		(property "Tolerance" "~"
			(at 0 0 180)
			(unlocked yes)
			(layer "F.Fab")
			(hide yes)
			(effects
				(font
					(size 1 1)
					(thickness 0.15)
				)
			)
		)
		(property "Current" "1A"
			(at 0 0 180)
			(unlocked yes)
			(layer "F.Fab")
			(hide yes)
			(effects
				(font
					(size 1 1)
					(thickness 0.15)
				)
			)
		)
		(sheetname "/X710-AT2 Misc/")
		(sheetfile "x710-at2-mics.kicad_sch")
		(attr smd exclude_from_pos_files exclude_from_bom dnp)
		(fp_rect
			(start -0.925 -0.47)
			(end 0.925 0.47)
			(stroke
				(width 0.05)
				(type default)
			)
			(fill no)
			(layer "F.CrtYd")
		)
		(fp_rect
			(start -0.5 -0.25)
			(end 0.5 0.25)
			(stroke
				(width 0.15)
				(type solid)
			)
			(fill no)
			(layer "F.Fab")
		)
		(pad "1" smd roundrect
			(at -0.48 0 180)
			(size 0.59 0.64)
			(layers "F.Cu" "F.Mask" "F.Paste")
			(roundrect_rratio 0.25)
			(net 78 "Net-(U10-VCC)")
			(pintype "passive")
		)
		(pad "2" smd roundrect
			(at 0.48 0 180)
			(size 0.59 0.64)
			(layers "F.Cu" "F.Mask" "F.Paste")
			(roundrect_rratio 0.25)
			(net 90 "+3V3_AUX")
			(pintype "passive")
		)
	)
	(footprint "antmicro-footprints:R_0402_1005Metric"
		(layer "F.Cu")
		(at 54.099999 108.249997 -90)
		(descr "Resistor SMD 0402")
		(tags "resistor SMD 0402")
		(property "Reference" "R26"
			(at -1.069997 3.019999 90)
			(layer "F.SilkS")
			(effects
				(font
					(size 0.7 0.7)
					(thickness 0.15)
				)
				(justify right top)
			)
		)
		(property "Value" "R_30k_0402"
			(at -1.011843 1.772046 90)
			(layer "F.Fab")
			(hide yes)
			(effects
				(font
					(size 0.7 0.7)
					(thickness 0.15)
				)
				(justify right top)
			)
		)
		(property "Datasheet" "https://www.bourns.com/docs/product-datasheets/cr.pdf"
			(at 0 0 90)
			(layer "F.Fab")
			(hide yes)
			(effects
				(font
					(size 1.27 1.27)
					(thickness 0.15)
				)
			)
		)
		(property "Description" "SMD Chip Resistor, 30 kohm, ± 1%, 63 mW, 0402 [1005 Metric], Thick Film, General Purpose"
			(at 0 0 90)
			(layer "F.Fab")
			(hide yes)
			(effects
				(font
					(size 1.27 1.27)
					(thickness 0.15)
				)
			)
		)
		(property "MPN" "CR0402-FX-3002GLF"
			(at 0 0 270)
			(unlocked yes)
			(layer "F.Fab")
			(hide yes)
			(effects
				(font
					(size 1 1)
					(thickness 0.15)
				)
			)
		)
		(property "Manufacturer" "Bourns"
			(at 0 0 270)
			(unlocked yes)
			(layer "F.Fab")
			(hide yes)
			(effects
				(font
					(size 1 1)
					(thickness 0.15)
				)
			)
		)
		(property "License" "Apache-2.0"
			(at 0 0 270)
			(unlocked yes)
			(layer "F.Fab")
			(hide yes)
			(effects
				(font
					(size 1 1)
					(thickness 0.15)
				)
			)
		)
		(property "Author" "Antmicro"
			(at 0 0 270)
			(unlocked yes)
			(layer "F.Fab")
			(hide yes)
			(effects
				(font
					(size 1 1)
					(thickness 0.15)
				)
			)
		)
		(property "Val" "30k"
			(at 0 0 270)
			(unlocked yes)
			(layer "F.Fab")
			(hide yes)
			(effects
				(font
					(size 1 1)
					(thickness 0.15)
				)
			)
		)
		(property "Tolerance" "1%"
			(at 0 0 270)
			(unlocked yes)
			(layer "F.Fab")
			(hide yes)
			(effects
				(font
					(size 1 1)
					(thickness 0.15)
				)
			)
		)
		(sheetname "/Power/")
		(sheetfile "power.kicad_sch")
		(attr smd)
		(fp_rect
			(start -0.925 -0.47)
			(end 0.925 0.47)
			(stroke
				(width 0.05)
				(type default)
			)
			(fill no)
			(layer "F.CrtYd")
		)
		(fp_rect
			(start -0.5 -0.25)
			(end 0.5 0.25)
			(stroke
				(width 0.15)
				(type solid)
			)
			(fill no)
			(layer "F.Fab")
		)
		(pad "1" smd roundrect
			(at -0.48 0 270)
			(size 0.59 0.64)
			(layers "F.Cu" "F.Mask" "F.Paste")
			(roundrect_rratio 0.25)
			(net 28 "GND")
			(pintype "passive")
		)
		(pad "2" smd roundrect
			(at 0.48 0 270)
			(size 0.59 0.64)
			(layers "F.Cu" "F.Mask" "F.Paste")
			(roundrect_rratio 0.25)
			(net 332 "/Power/1V0_FB")
			(pintype "passive")
		)
	)
	(footprint "antmicro-footprints:R_0402_1005Metric"
		(layer "F.Cu")
		(at 53.5 78 -90)
		(descr "Resistor SMD 0402")
		(tags "resistor SMD 0402")
		(property "Reference" "R170"
			(at -3.6 -0.02 90)
			(layer "F.SilkS")
			(effects
				(font
					(size 0.7 0.7)
					(thickness 0.15)
				)
				(justify right top)
			)
		)
		(property "Value" "R_1k_0402"
			(at -1.011843 1.772046 90)
			(layer "F.Fab")
			(hide yes)
			(effects
				(font
					(size 0.7 0.7)
					(thickness 0.15)
				)
				(justify right top)
			)
		)
		(property "Datasheet" "https://www.bourns.com/docs/product-datasheets/cr.pdf"
			(at 0 0 90)
			(layer "F.Fab")
			(hide yes)
			(effects
				(font
					(size 1.27 1.27)
					(thickness 0.15)
				)
			)
		)
		(property "Description" "SMD Chip Resistor, 1 kohm, ± 1%, 63 mW, 0402 [1005 Metric], Thick Film, General Purpose"
			(at 0 0 90)
			(layer "F.Fab")
			(hide yes)
			(effects
				(font
					(size 1.27 1.27)
					(thickness 0.15)
				)
			)
		)
		(property "MPN" "CR0402-FX-1001GLF"
			(at 0 0 270)
			(unlocked yes)
			(layer "F.Fab")
			(hide yes)
			(effects
				(font
					(size 1 1)
					(thickness 0.15)
				)
			)
		)
		(property "Manufacturer" "Bourns"
			(at 0 0 270)
			(unlocked yes)
			(layer "F.Fab")
			(hide yes)
			(effects
				(font
					(size 1 1)
					(thickness 0.15)
				)
			)
		)
		(property "License" "Apache-2.0"
			(at 0 0 270)
			(unlocked yes)
			(layer "F.Fab")
			(hide yes)
			(effects
				(font
					(size 1 1)
					(thickness 0.15)
				)
			)
		)
		(property "Author" "Antmicro"
			(at 0 0 270)
			(unlocked yes)
			(layer "F.Fab")
			(hide yes)
			(effects
				(font
					(size 1 1)
					(thickness 0.15)
				)
			)
		)
		(property "Val" "1k"
			(at 0 0 270)
			(unlocked yes)
			(layer "F.Fab")
			(hide yes)
			(effects
				(font
					(size 1 1)
					(thickness 0.15)
				)
			)
		)
		(property "Tolerance" "1%"
			(at 0 0 270)
			(unlocked yes)
			(layer "F.Fab")
			(hide yes)
			(effects
				(font
					(size 1 1)
					(thickness 0.15)
				)
			)
		)
		(sheetname "/Power/")
		(sheetfile "power.kicad_sch")
		(attr smd)
		(fp_rect
			(start -0.925 -0.47)
			(end 0.925 0.47)
			(stroke
				(width 0.05)
				(type default)
			)
			(fill no)
			(layer "F.CrtYd")
		)
		(fp_rect
			(start -0.5 -0.25)
			(end 0.5 0.25)
			(stroke
				(width 0.15)
				(type solid)
			)
			(fill no)
			(layer "F.Fab")
		)
		(pad "1" smd roundrect
			(at -0.48 0 270)
			(size 0.59 0.64)
			(layers "F.Cu" "F.Mask" "F.Paste")
			(roundrect_rratio 0.25)
			(net 79 "Net-(D11-A)")
			(pintype "passive")
		)
		(pad "2" smd roundrect
			(at 0.48 0 270)
			(size 0.59 0.64)
			(layers "F.Cu" "F.Mask" "F.Paste")
			(roundrect_rratio 0.25)
			(net 7 "+3V3")
			(pintype "passive")
		)
	)
	(footprint "antmicro-footprints:R_0402_1005Metric"
		(layer "F.Cu")
		(at 63.793 62.02)
		(descr "Resistor SMD 0402")
		(tags "resistor SMD 0402")
		(property "Reference" "R13"
			(at -1.023 -0.55 0)
			(layer "F.SilkS")
			(effects
				(font
					(size 0.7 0.7)
					(thickness 0.15)
				)
				(justify left bottom)
			)
		)
		(property "Value" "R_10k_0402"
			(at -1.011843 1.772046 0)
			(layer "F.Fab")
			(hide yes)
			(effects
				(font
					(size 0.7 0.7)
					(thickness 0.15)
				)
				(justify left bottom)
			)
		)
		(property "Datasheet" "https://www.bourns.com/docs/product-datasheets/cr.pdf"
			(at 0 0 0)
			(layer "F.Fab")
			(hide yes)
			(effects
				(font
					(size 1.27 1.27)
					(thickness 0.15)
				)
			)
		)
		(property "Description" "SMD Chip Resistor, 10 kohm, ± 1%, 62.5 mW, 0402 [1005 Metric], Thick Film, General Purpose"
			(at 0 0 0)
			(layer "F.Fab")
			(hide yes)
			(effects
				(font
					(size 1.27 1.27)
					(thickness 0.15)
				)
			)
		)
		(property "MPN" "CR0402-FX-1002GLF"
			(at 0 0 0)
			(unlocked yes)
			(layer "F.Fab")
			(hide yes)
			(effects
				(font
					(size 1 1)
					(thickness 0.15)
				)
			)
		)
		(property "Manufacturer" "Bourns"
			(at 0 0 0)
			(unlocked yes)
			(layer "F.Fab")
			(hide yes)
			(effects
				(font
					(size 1 1)
					(thickness 0.15)
				)
			)
		)
		(property "License" "Apache-2.0"
			(at 0 0 0)
			(unlocked yes)
			(layer "F.Fab")
			(hide yes)
			(effects
				(font
					(size 1 1)
					(thickness 0.15)
				)
			)
		)
		(property "Author" "Antmicro"
			(at 0 0 0)
			(unlocked yes)
			(layer "F.Fab")
			(hide yes)
			(effects
				(font
					(size 1 1)
					(thickness 0.15)
				)
			)
		)
		(property "Val" "10k"
			(at 0 0 0)
			(unlocked yes)
			(layer "F.Fab")
			(hide yes)
			(effects
				(font
					(size 1 1)
					(thickness 0.15)
				)
			)
		)
		(property "Tolerance" "1%"
			(at 0 0 0)
			(unlocked yes)
			(layer "F.Fab")
			(hide yes)
			(effects
				(font
					(size 1 1)
					(thickness 0.15)
				)
			)
		)
		(sheetname "/Power/")
		(sheetfile "power.kicad_sch")
		(attr smd)
		(fp_rect
			(start -0.925 -0.47)
			(end 0.925 0.47)
			(stroke
				(width 0.05)
				(type default)
			)
			(fill no)
			(layer "F.CrtYd")
		)
		(fp_rect
			(start -0.5 -0.25)
			(end 0.5 0.25)
			(stroke
				(width 0.15)
				(type solid)
			)
			(fill no)
			(layer "F.Fab")
		)
		(pad "1" smd roundrect
			(at -0.48 0)
			(size 0.59 0.64)
			(layers "F.Cu" "F.Mask" "F.Paste")
			(roundrect_rratio 0.25)
			(net 70 "Net-(D2-A)")
			(pintype "passive")
		)
		(pad "2" smd roundrect
			(at 0.48 0)
			(size 0.59 0.64)
			(layers "F.Cu" "F.Mask" "F.Paste")
			(roundrect_rratio 0.25)
			(net 350 "/Power/+12V_IN")
			(pintype "passive")
		)
	)
	(footprint "antmicro-footprints:R_0402_1005Metric"
		(layer "F.Cu")
		(at 88.1 112.45 90)
		(descr "Resistor SMD 0402")
		(tags "resistor SMD 0402")
		(property "Reference" "R75"
			(at -0.85 0.45 90)
			(layer "F.SilkS")
			(effects
				(font
					(size 0.7 0.7)
					(thickness 0.15)
				)
				(justify right bottom)
			)
		)
		(property "Value" "R_0R_0402"
			(at -1.011843 1.772046 90)
			(layer "F.Fab")
			(hide yes)
			(effects
				(font
					(size 0.7 0.7)
					(thickness 0.15)
				)
				(justify left bottom)
			)
		)
		(property "Datasheet" "https://industrial.panasonic.com/cdbs/www-data/pdf/RDA0000/AOA0000C301.pdf"
			(at 0 0 90)
			(layer "F.Fab")
			(hide yes)
			(effects
				(font
					(size 1.27 1.27)
					(thickness 0.15)
				)
			)
		)
		(property "Description" "SMD Chip Resistor, Jumper, 0 ohm, 100 mW, 0402 [1005 Metric], Thick Film, General Purpose"
			(at 0 0 90)
			(layer "F.Fab")
			(hide yes)
			(effects
				(font
					(size 1.27 1.27)
					(thickness 0.15)
				)
			)
		)
		(property "MPN" "ERJ2GE0R00X"
			(at 0 0 90)
			(unlocked yes)
			(layer "F.Fab")
			(hide yes)
			(effects
				(font
					(size 1 1)
					(thickness 0.15)
				)
			)
		)
		(property "Manufacturer" "Panasonic"
			(at 0 0 90)
			(unlocked yes)
			(layer "F.Fab")
			(hide yes)
			(effects
				(font
					(size 1 1)
					(thickness 0.15)
				)
			)
		)
		(property "License" "Apache-2.0"
			(at 0 0 90)
			(unlocked yes)
			(layer "F.Fab")
			(hide yes)
			(effects
				(font
					(size 1 1)
					(thickness 0.15)
				)
			)
		)
		(property "Author" "Antmicro"
			(at 0 0 90)
			(unlocked yes)
			(layer "F.Fab")
			(hide yes)
			(effects
				(font
					(size 1 1)
					(thickness 0.15)
				)
			)
		)
		(property "Val" "0R"
			(at 0 0 90)
			(unlocked yes)
			(layer "F.Fab")
			(hide yes)
			(effects
				(font
					(size 1 1)
					(thickness 0.15)
				)
			)
		)
		(property "Tolerance" "~"
			(at 0 0 90)
			(unlocked yes)
			(layer "F.Fab")
			(hide yes)
			(effects
				(font
					(size 1 1)
					(thickness 0.15)
				)
			)
		)
		(property "Current" "1A"
			(at 0 0 90)
			(unlocked yes)
			(layer "F.Fab")
			(hide yes)
			(effects
				(font
					(size 1 1)
					(thickness 0.15)
				)
			)
		)
		(sheetname "/X710-AT2 10GbE/")
		(sheetfile "x710-at2-10gbe.kicad_sch")
		(attr smd)
		(fp_rect
			(start -0.925 -0.47)
			(end 0.925 0.47)
			(stroke
				(width 0.05)
				(type default)
			)
			(fill no)
			(layer "F.CrtYd")
		)
		(fp_rect
			(start -0.5 -0.25)
			(end 0.5 0.25)
			(stroke
				(width 0.15)
				(type solid)
			)
			(fill no)
			(layer "F.Fab")
		)
		(pad "1" smd roundrect
			(at -0.48 0 90)
			(size 0.59 0.64)
			(layers "F.Cu" "F.Mask" "F.Paste")
			(roundrect_rratio 0.25)
			(net 28 "GND")
			(pintype "passive")
		)
		(pad "2" smd roundrect
			(at 0.48 0 90)
			(size 0.59 0.64)
			(layers "F.Cu" "F.Mask" "F.Paste")
			(roundrect_rratio 0.25)
			(net 294 "/X710-AT2 10GbE/TPIN_5")
			(pintype "passive")
		)
	)
	(footprint "antmicro-footprints:MP_Pad6mm_Drill3.2mm"
		(layer "F.Cu")
		(at 62.975 77.995)
		(property "Reference" "MP5"
			(at 0 -3.2 0)
			(layer "F.SilkS")
			(hide yes)
			(effects
				(font
					(size 0.7 0.7)
					(thickness 0.15)
				)
				(justify left bottom)
			)
		)
		(property "Value" "MP_Pad6mm_Drill3.2mm"
			(at 0 3.9 0)
			(layer "F.Fab")
			(hide yes)
			(effects
				(font
					(size 0.7 0.7)
					(thickness 0.15)
				)
				(justify left bottom)
			)
		)
		(property "Description" "Mechanical part"
			(at 0 0 0)
			(layer "F.Fab")
			(hide yes)
			(effects
				(font
					(size 1.27 1.27)
					(thickness 0.15)
				)
			)
		)
		(property "Author" "Antmicro"
			(at 0 0 0)
			(unlocked yes)
			(layer "F.Fab")
			(hide yes)
			(effects
				(font
					(size 1 1)
					(thickness 0.15)
				)
			)
		)
		(property "License" "Apache-2.0"
			(at 0 0 0)
			(unlocked yes)
			(layer "F.Fab")
			(hide yes)
			(effects
				(font
					(size 1 1)
					(thickness 0.15)
				)
			)
		)
		(sheetname "/")
		(sheetfile "oculink-to-10gbe-adapter.kicad_sch")
		(attr exclude_from_pos_files exclude_from_bom)
		(fp_circle
			(center 0 0)
			(end 3.25 0)
			(stroke
				(width 0.05)
				(type default)
			)
			(fill no)
			(layer "F.CrtYd")
		)
		(fp_text user "License: Apache-2.0"
			(at -0.178 8.425 0)
			(layer "F.Fab")
			(effects
				(font
					(size 0.7 0.7)
					(thickness 0.15)
				)
				(justify left bottom)
			)
		)
		(fp_text user "Author: Antmicro"
			(at -0.178 7.225 0)
			(layer "F.Fab")
			(effects
				(font
					(size 0.7 0.7)
					(thickness 0.15)
				)
				(justify left bottom)
			)
		)
		(fp_text user "${REFERENCE}"
			(at -0.178 6.025 0)
			(layer "F.Fab")
			(effects
				(font
					(size 0.7 0.7)
					(thickness 0.15)
				)
				(justify left bottom)
			)
		)
		(pad "1" thru_hole circle
			(at 0 0)
			(size 6 6)
			(drill 3.2)
			(layers "*.Cu" "*.Mask")
			(remove_unused_layers no)
			(net 28 "GND")
			(pintype "passive")
		)
	)
	(footprint "antmicro-footprints:C_0402_1005Metric"
		(layer "F.Cu")
		(at 97.399999 109.1)
		(descr "Capacitor SMD 0402")
		(tags "capacitor SMD 0402")
		(property "Reference" "C69"
			(at -2.249999 15.7 0)
			(layer "F.SilkS")
			(effects
				(font
					(size 0.7 0.7)
					(thickness 0.15)
				)
				(justify left bottom)
			)
		)
		(property "Value" "C_100n_0402"
			(at -1.022927 2.155213 0)
			(layer "F.Fab")
			(hide yes)
			(effects
				(font
					(size 0.7 0.7)
					(thickness 0.15)
				)
				(justify left bottom)
			)
		)
		(property "Datasheet" "https://www.murata.com/products/productdetail?partno=GRM155R61H104KE14%23"
			(at 0 0 0)
			(layer "F.Fab")
			(hide yes)
			(effects
				(font
					(size 1.27 1.27)
					(thickness 0.15)
				)
			)
		)
		(property "Description" "SMD Multilayer Ceramic Capacitor, 0.1 µF, 50 V, 0402 [1005 Metric], ± 10%, X5R, GRM Series"
			(at 0 0 0)
			(layer "F.Fab")
			(hide yes)
			(effects
				(font
					(size 1.27 1.27)
					(thickness 0.15)
				)
			)
		)
		(property "MPN" "GRM155R61H104KE14D"
			(at 0 0 0)
			(unlocked yes)
			(layer "F.Fab")
			(hide yes)
			(effects
				(font
					(size 1 1)
					(thickness 0.15)
				)
			)
		)
		(property "Val" "100n"
			(at 0 0 0)
			(unlocked yes)
			(layer "F.Fab")
			(hide yes)
			(effects
				(font
					(size 1 1)
					(thickness 0.15)
				)
			)
		)
		(property "Voltage" "50V"
			(at 0 0 0)
			(unlocked yes)
			(layer "F.Fab")
			(hide yes)
			(effects
				(font
					(size 1 1)
					(thickness 0.15)
				)
			)
		)
		(property "Dielectric" "X5R"
			(at 0 0 0)
			(unlocked yes)
			(layer "F.Fab")
			(hide yes)
			(effects
				(font
					(size 1 1)
					(thickness 0.15)
				)
			)
		)
		(property "Manufacturer" "Murata"
			(at 0 0 0)
			(unlocked yes)
			(layer "F.Fab")
			(hide yes)
			(effects
				(font
					(size 1 1)
					(thickness 0.15)
				)
			)
		)
		(property "License" "Apache-2.0"
			(at 0 0 0)
			(unlocked yes)
			(layer "F.Fab")
			(hide yes)
			(effects
				(font
					(size 1 1)
					(thickness 0.15)
				)
			)
		)
		(property "Author" "Antmicro"
			(at 0 0 0)
			(unlocked yes)
			(layer "F.Fab")
			(hide yes)
			(effects
				(font
					(size 1 1)
					(thickness 0.15)
				)
			)
		)
		(sheetname "/X710-AT2 10GbE/")
		(sheetfile "x710-at2-10gbe.kicad_sch")
		(attr smd)
		(fp_rect
			(start -0.925 -0.47)
			(end 0.925 0.47)
			(stroke
				(width 0.05)
				(type default)
			)
			(fill no)
			(layer "F.CrtYd")
		)
		(fp_line
			(start -0.494 -0.25)
			(end 0.504 -0.25)
			(stroke
				(width 0.15)
				(type solid)
			)
			(layer "F.Fab")
		)
		(fp_line
			(start -0.494 0.248)
			(end -0.494 -0.25)
			(stroke
				(width 0.15)
				(type solid)
			)
			(layer "F.Fab")
		)
		(fp_line
			(start 0.504 -0.25)
			(end 0.504 0.248)
			(stroke
				(width 0.15)
				(type solid)
			)
			(layer "F.Fab")
		)
		(fp_line
			(start 0.504 0.248)
			(end -0.494 0.248)
			(stroke
				(width 0.15)
				(type solid)
			)
			(layer "F.Fab")
		)
		(pad "1" smd roundrect
			(at -0.48 0)
			(size 0.59 0.64)
			(layers "F.Cu" "F.Mask" "F.Paste")
			(roundrect_rratio 0.25)
			(net 31 "/X710-AT2 10GbE/25MHZ_OSC.-")
			(pintype "passive")
		)
		(pad "2" smd roundrect
			(at 0.48 0)
			(size 0.59 0.64)
			(layers "F.Cu" "F.Mask" "F.Paste")
			(roundrect_rratio 0.25)
			(net 73 "/X710-AT2 10GbE/25MHZ_OSC_AC.-")
			(pintype "passive")
		)
	)
	(footprint "antmicro-footprints:R_0402_1005Metric"
		(layer "F.Cu")
		(at 54.099999 85.149999 -90)
		(descr "Resistor SMD 0402")
		(tags "resistor SMD 0402")
		(property "Reference" "R12"
			(at -1.029999 2.989999 90)
			(layer "F.SilkS")
			(effects
				(font
					(size 0.7 0.7)
					(thickness 0.15)
				)
				(justify right top)
			)
		)
		(property "Value" "R_30k_0402"
			(at -1.011843 1.772046 90)
			(layer "F.Fab")
			(hide yes)
			(effects
				(font
					(size 0.7 0.7)
					(thickness 0.15)
				)
				(justify right top)
			)
		)
		(property "Datasheet" "https://www.bourns.com/docs/product-datasheets/cr.pdf"
			(at 0 0 90)
			(layer "F.Fab")
			(hide yes)
			(effects
				(font
					(size 1.27 1.27)
					(thickness 0.15)
				)
			)
		)
		(property "Description" "SMD Chip Resistor, 30 kohm, ± 1%, 63 mW, 0402 [1005 Metric], Thick Film, General Purpose"
			(at 0 0 90)
			(layer "F.Fab")
			(hide yes)
			(effects
				(font
					(size 1.27 1.27)
					(thickness 0.15)
				)
			)
		)
		(property "MPN" "CR0402-FX-3002GLF"
			(at 0 0 270)
			(unlocked yes)
			(layer "F.Fab")
			(hide yes)
			(effects
				(font
					(size 1 1)
					(thickness 0.15)
				)
			)
		)
		(property "Manufacturer" "Bourns"
			(at 0 0 270)
			(unlocked yes)
			(layer "F.Fab")
			(hide yes)
			(effects
				(font
					(size 1 1)
					(thickness 0.15)
				)
			)
		)
		(property "License" "Apache-2.0"
			(at 0 0 270)
			(unlocked yes)
			(layer "F.Fab")
			(hide yes)
			(effects
				(font
					(size 1 1)
					(thickness 0.15)
				)
			)
		)
		(property "Author" "Antmicro"
			(at 0 0 270)
			(unlocked yes)
			(layer "F.Fab")
			(hide yes)
			(effects
				(font
					(size 1 1)
					(thickness 0.15)
				)
			)
		)
		(property "Val" "30k"
			(at 0 0 270)
			(unlocked yes)
			(layer "F.Fab")
			(hide yes)
			(effects
				(font
					(size 1 1)
					(thickness 0.15)
				)
			)
		)
		(property "Tolerance" "1%"
			(at 0 0 270)
			(unlocked yes)
			(layer "F.Fab")
			(hide yes)
			(effects
				(font
					(size 1 1)
					(thickness 0.15)
				)
			)
		)
		(sheetname "/Power/")
		(sheetfile "power.kicad_sch")
		(attr smd)
		(fp_rect
			(start -0.925 -0.47)
			(end 0.925 0.47)
			(stroke
				(width 0.05)
				(type default)
			)
			(fill no)
			(layer "F.CrtYd")
		)
		(fp_rect
			(start -0.5 -0.25)
			(end 0.5 0.25)
			(stroke
				(width 0.15)
				(type solid)
			)
			(fill no)
			(layer "F.Fab")
		)
		(pad "1" smd roundrect
			(at -0.48 0 270)
			(size 0.59 0.64)
			(layers "F.Cu" "F.Mask" "F.Paste")
			(roundrect_rratio 0.25)
			(net 28 "GND")
			(pintype "passive")
		)
		(pad "2" smd roundrect
			(at 0.48 0 270)
			(size 0.59 0.64)
			(layers "F.Cu" "F.Mask" "F.Paste")
			(roundrect_rratio 0.25)
			(net 329 "/Power/VCCD_FB")
			(pintype "passive")
		)
	)
	(footprint "antmicro-footprints:RJ45_JTH-0024NL"
		(layer "F.Cu")
		(at 79.05 132.39 180)
		(property "Reference" "J3"
			(at -2.555 4.4 0)
			(unlocked yes)
			(layer "F.SilkS")
			(effects
				(font
					(size 0.7 0.7)
					(thickness 0.15)
				)
				(justify left bottom)
			)
		)
		(property "Value" "Bus_RJ45_JTH-0024NL"
			(at 5.06 1 180)
			(unlocked yes)
			(layer "F.Fab")
			(hide yes)
			(effects
				(font
					(size 0.7 0.7)
					(thickness 0.15)
				)
				(justify left bottom)
			)
		)
		(property "Datasheet" "https://www.mouser.com/datasheet/2/447/JTH_0024NL-3072047.pdf"
			(at 0 0 0)
			(layer "F.Fab")
			(hide yes)
			(effects
				(font
					(size 1.27 1.27)
					(thickness 0.15)
				)
			)
		)
		(property "Description" "Modular Connectors / Ethernet Connectors 1X1 TAB DOWN W/LED'S ETHERNET (NON PoE)"
			(at 0 0 0)
			(layer "F.Fab")
			(hide yes)
			(effects
				(font
					(size 1.27 1.27)
					(thickness 0.15)
				)
			)
		)
		(property "MPN" "JTH-0024NL"
			(at 0 0 180)
			(unlocked yes)
			(layer "F.Fab")
			(hide yes)
			(effects
				(font
					(size 1 1)
					(thickness 0.15)
				)
			)
		)
		(property "Manufacturer" "Pulse Electronics"
			(at 0 0 180)
			(unlocked yes)
			(layer "F.Fab")
			(hide yes)
			(effects
				(font
					(size 1 1)
					(thickness 0.15)
				)
			)
		)
		(property "Author" "Antmicro"
			(at 0 0 180)
			(unlocked yes)
			(layer "F.Fab")
			(hide yes)
			(effects
				(font
					(size 1 1)
					(thickness 0.15)
				)
			)
		)
		(property "License" "Apache-2.0"
			(at 0 0 180)
			(unlocked yes)
			(layer "F.Fab")
			(hide yes)
			(effects
				(font
					(size 1 1)
					(thickness 0.15)
				)
			)
		)
		(property ki_fp_filters "CONN18_5-2337992-8_TEC")
		(sheetname "/2xRJ45/")
		(sheetfile "2xrj45.kicad_sch")
		(attr through_hole)
		(fp_line
			(start 14 4)
			(end 14 -5.25)
			(stroke
				(width 0.1)
				(type default)
			)
			(layer "F.SilkS")
		)
		(fp_line
			(start -3.75 4)
			(end 14 4)
			(stroke
				(width 0.1)
				(type default)
			)
			(layer "F.SilkS")
		)
		(fp_line
			(start -3.75 -5.25)
			(end -3.75 4)
			(stroke
				(width 0.1)
				(type default)
			)
			(layer "F.SilkS")
		)
		(fp_rect
			(start -5.4 -20.72)
			(end 15.58 4.45)
			(stroke
				(width 0.05)
				(type solid)
			)
			(fill no)
			(layer "F.CrtYd")
		)
		(fp_text user "${REFERENCE}"
			(at -5.75 6.45 180)
			(unlocked yes)
			(layer "F.Fab")
			(effects
				(font
					(size 0.7 0.7)
					(thickness 0.15)
				)
				(justify left bottom)
			)
		)
		(fp_text user "License: Apache-2.0"
			(at -5.75 7.65 180)
			(layer "F.Fab")
			(effects
				(font
					(size 0.7 0.7)
					(thickness 0.15)
				)
				(justify left bottom)
			)
		)
		(fp_text user "Author: Antmicro"
			(at -5.75 8.85 180)
			(layer "F.Fab")
			(effects
				(font
					(size 0.7 0.7)
					(thickness 0.15)
				)
				(justify left bottom)
			)
		)
		(pad "" np_thru_hole circle
			(at 0.245 -6.6 180)
			(size 3.2 3.2)
			(drill 3.2)
			(layers "*.Cu" "*.Mask")
		)
		(pad "" np_thru_hole circle
			(at 9.895 -6.6 180)
			(size 3.2 3.2)
			(drill 3.2)
			(layers "*.Cu" "*.Mask")
		)
		(pad "1" thru_hole circle
			(at 0 0 180)
			(size 1.39 1.39)
			(drill 0.89)
			(layers "*.Cu" "*.Mask")
			(remove_unused_layers no)
			(net 299 "/2xRJ45/P0_CT")
			(pinfunction "CT3")
			(pintype "bidirectional")
		)
		(pad "2" thru_hole circle
			(at 2.03 0 180)
			(size 1.39 1.39)
			(drill 0.89)
			(layers "*.Cu" "*.Mask")
			(remove_unused_layers no)
			(net 50 "/2xRJ45/Ethernet_P0.D3-")
			(pinfunction "T2-")
			(pintype "bidirectional")
		)
		(pad "3" thru_hole circle
			(at 4.06 0 180)
			(size 1.39 1.39)
			(drill 0.89)
			(layers "*.Cu" "*.Mask")
			(remove_unused_layers no)
			(net 58 "/2xRJ45/Ethernet_P0.D3+")
			(pinfunction "T2+")
			(pintype "bidirectional")
		)
		(pad "4" thru_hole circle
			(at 6.09 0 180)
			(size 1.39 1.39)
			(drill 0.89)
			(layers "*.Cu" "*.Mask")
			(remove_unused_layers no)
			(net 51 "/2xRJ45/Ethernet_P0.D2+")
			(pinfunction "T3+")
			(pintype "bidirectional")
		)
		(pad "5" thru_hole circle
			(at 8.12 0 180)
			(size 1.39 1.39)
			(drill 0.89)
			(layers "*.Cu" "*.Mask")
			(remove_unused_layers no)
			(net 48 "/2xRJ45/Ethernet_P0.D2-")
			(pinfunction "T3-")
			(pintype "bidirectional")
		)
		(pad "6" thru_hole circle
			(at 10.15 0 180)
			(size 1.39 1.39)
			(drill 0.89)
			(layers "*.Cu" "*.Mask")
			(remove_unused_layers no)
			(net 299 "/2xRJ45/P0_CT")
			(pinfunction "CT2")
			(pintype "bidirectional")
		)
		(pad "7" thru_hole circle
			(at -1.02 2.54 180)
			(size 1.39 1.39)
			(drill 0.89)
			(layers "*.Cu" "*.Mask")
			(remove_unused_layers no)
			(net 299 "/2xRJ45/P0_CT")
			(pinfunction "CT4")
			(pintype "bidirectional")
		)
		(pad "8" thru_hole circle
			(at 1.01 2.54 180)
			(size 1.39 1.39)
			(drill 0.89)
			(layers "*.Cu" "*.Mask")
			(remove_unused_layers no)
			(net 55 "/2xRJ45/Ethernet_P0.D4+")
			(pinfunction "T1+")
			(pintype "bidirectional")
		)
		(pad "9" thru_hole circle
			(at 3.04 2.54 180)
			(size 1.39 1.39)
			(drill 0.89)
			(layers "*.Cu" "*.Mask")
			(remove_unused_layers no)
			(net 57 "/2xRJ45/Ethernet_P0.D4-")
			(pinfunction "T1-")
			(pintype "bidirectional")
		)
		(pad "10" thru_hole circle
			(at 7.11 2.54 180)
			(size 1.39 1.39)
			(drill 0.89)
			(layers "*.Cu" "*.Mask")
			(remove_unused_layers no)
			(net 49 "/2xRJ45/Ethernet_P0.D1-")
			(pinfunction "T4-")
			(pintype "bidirectional")
		)
		(pad "11" thru_hole circle
			(at 9.14 2.54 180)
			(size 1.39 1.39)
			(drill 0.89)
			(layers "*.Cu" "*.Mask")
			(remove_unused_layers no)
			(net 56 "/2xRJ45/Ethernet_P0.D1+")
			(pinfunction "T4+")
			(pintype "bidirectional")
		)
		(pad "12" thru_hole circle
			(at 11.17 2.54 180)
			(size 1.39 1.39)
			(drill 0.89)
			(layers "*.Cu" "*.Mask")
			(remove_unused_layers no)
			(net 299 "/2xRJ45/P0_CT")
			(pinfunction "CT1")
			(pintype "bidirectional")
		)
		(pad "13" thru_hole circle
			(at 12.59 -12.95 180)
			(size 1.77 1.77)
			(drill 1.27)
			(layers "*.Cu" "*.Mask")
			(remove_unused_layers no)
			(net 54 "Net-(J3-LED_GRN-)")
			(pinfunction "LED_GRN-")
			(pintype "passive")
		)
		(pad "14" thru_hole circle
			(at 12.59 -15.49 180)
			(size 1.77 1.77)
			(drill 1.27)
			(layers "*.Cu" "*.Mask")
			(remove_unused_layers no)
			(net 7 "+3V3")
			(pinfunction "LED_GRN+")
			(pintype "passive")
		)
		(pad "15" thru_hole circle
			(at -2.45 -10.41 180)
			(size 1.77 1.77)
			(drill 1.27)
			(layers "*.Cu" "*.Mask")
			(remove_unused_layers no)
			(net 52 "Net-(J3-LED_YG_Y-)")
			(pinfunction "LED_YG_Y-")
			(pintype "passive")
		)
		(pad "16" thru_hole circle
			(at -2.45 -12.95 180)
			(size 1.77 1.77)
			(drill 1.27)
			(layers "*.Cu" "*.Mask")
			(remove_unused_layers no)
			(net 7 "+3V3")
			(pinfunction "LED_COM+")
			(pintype "passive")
		)
		(pad "17" thru_hole circle
			(at -2.45 -15.49 180)
			(size 1.77 1.77)
			(drill 1.27)
			(layers "*.Cu" "*.Mask")
			(remove_unused_layers no)
			(net 53 "Net-(J3-LED_YG_G-)")
			(pinfunction "LED_YG_G-")
			(pintype "passive")
		)
		(pad "SH" thru_hole circle
			(at -3.72 -6.6 180)
			(size 2.07 2.07)
			(drill 1.57)
			(layers "*.Cu" "*.Mask")
			(remove_unused_layers no)
			(net 28 "GND")
			(pinfunction "SHIELD")
			(pintype "passive")
		)
		(pad "SH" thru_hole circle
			(at 13.86 -6.6 180)
			(size 2.07 2.07)
			(drill 1.57)
			(layers "*.Cu" "*.Mask")
			(remove_unused_layers no)
			(net 28 "GND")
			(pinfunction "SHIELD")
			(pintype "passive")
		)
	)
	(footprint "antmicro-footprints:SOT-23-6"
		(layer "F.Cu")
		(at 70.21 66 180)
		(property "Reference" "U11"
			(at -1.71 0.31 90)
			(layer "F.SilkS")
			(effects
				(font
					(size 0.7 0.7)
					(thickness 0.15)
				)
				(justify right top)
			)
		)
		(property "Value" "LTC4412IS6"
			(at -1.749999 2.693 0)
			(layer "F.Fab")
			(hide yes)
			(effects
				(font
					(size 0.7 0.7)
					(thickness 0.15)
				)
				(justify right top)
			)
		)
		(property "Datasheet" "https://www.analog.com/media/en/technical-documentation/data-sheets/4412fb.pdf"
			(at 0 -0.057 0)
			(layer "F.Fab")
			(hide yes)
			(effects
				(font
					(size 1.27 1.27)
					(thickness 0.15)
				)
			)
		)
		(property "Description" "Ideal diode controller"
			(at 0 -0.057 0)
			(layer "F.Fab")
			(hide yes)
			(effects
				(font
					(size 1.27 1.27)
					(thickness 0.15)
				)
			)
		)
		(property "MPN" "LTC4412IS6#TRMPBF"
			(at 0 0 180)
			(unlocked yes)
			(layer "F.Fab")
			(hide yes)
			(effects
				(font
					(size 1 1)
					(thickness 0.15)
				)
			)
		)
		(property "Manufacturer" "Analog Devices"
			(at 0 0 180)
			(unlocked yes)
			(layer "F.Fab")
			(hide yes)
			(effects
				(font
					(size 1 1)
					(thickness 0.15)
				)
			)
		)
		(property "Author" "Antmicro"
			(at 0 0 180)
			(unlocked yes)
			(layer "F.Fab")
			(hide yes)
			(effects
				(font
					(size 1 1)
					(thickness 0.15)
				)
			)
		)
		(property "License" "Apache-2.0"
			(at 0 0 180)
			(unlocked yes)
			(layer "F.Fab")
			(hide yes)
			(effects
				(font
					(size 1 1)
					(thickness 0.15)
				)
			)
		)
		(sheetname "/Power/Ideal diode 1/")
		(sheetfile "ideal-diode.kicad_sch")
		(attr smd)
		(fp_line
			(start 1.45 0.643)
			(end 1.45 0.343)
			(stroke
				(width 0.12)
				(type solid)
			)
			(layer "F.SilkS")
		)
		(fp_line
			(start 1.45 -0.757)
			(end 1.45 -0.457)
			(stroke
				(width 0.12)
				(type solid)
			)
			(layer "F.SilkS")
		)
		(fp_line
			(start 1.3 0.643)
			(end 1.45 0.643)
			(stroke
				(width 0.12)
				(type solid)
			)
			(layer "F.SilkS")
		)
		(fp_line
			(start 1.3 -0.757)
			(end 1.45 -0.757)
			(stroke
				(width 0.12)
				(type solid)
			)
			(layer "F.SilkS")
		)
		(fp_line
			(start -1.3 -0.757)
			(end -1.45 -0.757)
			(stroke
				(width 0.12)
				(type solid)
			)
			(layer "F.SilkS")
		)
		(fp_line
			(start -1.45 0.643)
			(end -1.45 0.343)
			(stroke
				(width 0.12)
				(type solid)
			)
			(layer "F.SilkS")
		)
		(fp_line
			(start -1.45 -0.757)
			(end -1.45 -0.457)
			(stroke
				(width 0.12)
				(type solid)
			)
			(layer "F.SilkS")
		)
		(fp_rect
			(start -1.55 -1.85)
			(end 1.55 1.75)
			(stroke
				(width 0.05)
				(type solid)
			)
			(fill no)
			(layer "F.CrtYd")
		)
		(fp_line
			(start 1.5 0.643)
			(end -1.5 0.643)
			(stroke
				(width 0.1)
				(type solid)
			)
			(layer "F.Fab")
		)
		(fp_line
			(start 1.5 -0.757)
			(end 1.5 0.643)
			(stroke
				(width 0.1)
				(type solid)
			)
			(layer "F.Fab")
		)
		(fp_line
			(start -1.5 0.643)
			(end -1.5 -0.757)
			(stroke
				(width 0.1)
				(type solid)
			)
			(layer "F.Fab")
		)
		(fp_line
			(start -1.5 -0.757)
			(end 1.5 -0.757)
			(stroke
				(width 0.1)
				(type solid)
			)
			(layer "F.Fab")
		)
		(pad "1" smd roundrect
			(at -0.954 1.1 180)
			(size 0.55 1)
			(layers "F.Cu" "F.Mask" "F.Paste")
			(roundrect_rratio 0.15)
			(net 350 "/Power/+12V_IN")
			(pinfunction "IN")
			(pintype "power_in")
		)
		(pad "2" smd roundrect
			(at -0.003 1.1 180)
			(size 0.55 1)
			(layers "F.Cu" "F.Mask" "F.Paste")
			(roundrect_rratio 0.15)
			(net 28 "GND")
			(pinfunction "GND")
			(pintype "power_in")
		)
		(pad "3" smd roundrect
			(at 0.947 1.1 180)
			(size 0.55 1)
			(layers "F.Cu" "F.Mask" "F.Paste")
			(roundrect_rratio 0.15)
			(net 28 "GND")
			(pinfunction "CTL")
			(pintype "input")
		)
		(pad "4" smd roundrect
			(at 0.947 -1.214 180)
			(size 0.55 1)
			(layers "F.Cu" "F.Mask" "F.Paste")
			(roundrect_rratio 0.15)
			(net 374 "unconnected-(U11-STAT-Pad4)")
			(pinfunction "STAT")
			(pintype "output+no_connect")
		)
		(pad "5" smd roundrect
			(at -0.003 -1.214 180)
			(size 0.55 1)
			(layers "F.Cu" "F.Mask" "F.Paste")
			(roundrect_rratio 0.15)
			(net 373 "Net-(Q2-G)")
			(pinfunction "GATE")
			(pintype "output")
		)
		(pad "6" smd roundrect
			(at -0.954 -1.214 180)
			(size 0.55 1)
			(layers "F.Cu" "F.Mask" "F.Paste")
			(roundrect_rratio 0.15)
			(net 314 "VCC")
			(pinfunction "SENSE")
			(pintype "input")
		)
	)
	(footprint "antmicro-footprints:R_0402_1005Metric"
		(layer "F.Cu")
		(at 101.3 107.1 180)
		(descr "Resistor SMD 0402")
		(tags "resistor SMD 0402")
		(property "Reference" "R81"
			(at 0.8 -15.55 0)
			(layer "F.SilkS")
			(effects
				(font
					(size 0.7 0.7)
					(thickness 0.15)
				)
				(justify left bottom)
			)
		)
		(property "Value" "R_100k_0402"
			(at -1.011843 1.772046 0)
			(layer "F.Fab")
			(hide yes)
			(effects
				(font
					(size 0.7 0.7)
					(thickness 0.15)
				)
				(justify right top)
			)
		)
		(property "Datasheet" "https://www.bourns.com/docs/product-datasheets/cr.pdf"
			(at 0 0 0)
			(layer "F.Fab")
			(hide yes)
			(effects
				(font
					(size 1.27 1.27)
					(thickness 0.15)
				)
			)
		)
		(property "Description" "SMD Chip Resistor, 100 kohm, ± 1%, 62.5 mW, 0402 [1005 Metric], Thick Film, General Purpose"
			(at 0 0 0)
			(layer "F.Fab")
			(hide yes)
			(effects
				(font
					(size 1.27 1.27)
					(thickness 0.15)
				)
			)
		)
		(property "MPN" "CR0402-FX-1003GLF"
			(at 0 0 180)
			(unlocked yes)
			(layer "F.Fab")
			(hide yes)
			(effects
				(font
					(size 1 1)
					(thickness 0.15)
				)
			)
		)
		(property "Manufacturer" "Bourns"
			(at 0 0 180)
			(unlocked yes)
			(layer "F.Fab")
			(hide yes)
			(effects
				(font
					(size 1 1)
					(thickness 0.15)
				)
			)
		)
		(property "License" "Apache-2.0"
			(at 0 0 180)
			(unlocked yes)
			(layer "F.Fab")
			(hide yes)
			(effects
				(font
					(size 1 1)
					(thickness 0.15)
				)
			)
		)
		(property "Author" "Antmicro"
			(at 0 0 180)
			(unlocked yes)
			(layer "F.Fab")
			(hide yes)
			(effects
				(font
					(size 1 1)
					(thickness 0.15)
				)
			)
		)
		(property "Val" "100k"
			(at 0 0 180)
			(unlocked yes)
			(layer "F.Fab")
			(hide yes)
			(effects
				(font
					(size 1 1)
					(thickness 0.15)
				)
			)
		)
		(property "Tolerance" "1%"
			(at 0 0 180)
			(unlocked yes)
			(layer "F.Fab")
			(hide yes)
			(effects
				(font
					(size 1 1)
					(thickness 0.15)
				)
			)
		)
		(sheetname "/X710-AT2 Misc/")
		(sheetfile "x710-at2-mics.kicad_sch")
		(attr smd)
		(fp_rect
			(start -0.925 -0.47)
			(end 0.925 0.47)
			(stroke
				(width 0.05)
				(type default)
			)
			(fill no)
			(layer "F.CrtYd")
		)
		(fp_rect
			(start -0.5 -0.25)
			(end 0.5 0.25)
			(stroke
				(width 0.15)
				(type solid)
			)
			(fill no)
			(layer "F.Fab")
		)
		(pad "1" smd roundrect
			(at -0.48 0 180)
			(size 0.59 0.64)
			(layers "F.Cu" "F.Mask" "F.Paste")
			(roundrect_rratio 0.25)
			(net 363 "/X710-AT2 Misc/NCSI.TXD_0")
			(pintype "passive")
		)
		(pad "2" smd roundrect
			(at 0.48 0 180)
			(size 0.59 0.64)
			(layers "F.Cu" "F.Mask" "F.Paste")
			(roundrect_rratio 0.25)
			(net 7 "+3V3")
			(pintype "passive")
		)
	)
	(footprint "antmicro-footprints:C_0402_1005Metric"
		(layer "F.Cu")
		(at 109.35 93.45 90)
		(descr "Capacitor SMD 0402")
		(tags "capacitor SMD 0402")
		(property "Reference" "C215"
			(at 3.85 0.3 90)
			(layer "F.SilkS")
			(effects
				(font
					(size 0.7 0.7)
					(thickness 0.15)
				)
				(justify left bottom)
			)
		)
		(property "Value" "C_10p_0402"
			(at -1.022927 2.155213 90)
			(layer "F.Fab")
			(hide yes)
			(effects
				(font
					(size 0.7 0.7)
					(thickness 0.15)
				)
				(justify left bottom)
			)
		)
		(property "Datasheet" "https://www.murata.com/products/productdetail?partno=GCM1555C1H100GA16%23"
			(at 0 0 90)
			(layer "F.Fab")
			(hide yes)
			(effects
				(font
					(size 1.27 1.27)
					(thickness 0.15)
				)
			)
		)
		(property "Description" "SMD Multilayer Ceramic Capacitor, 10 pF, 50 V, 0402 [1005 Metric], ± 2%, C0G / NP0, GCM"
			(at 0 0 90)
			(layer "F.Fab")
			(hide yes)
			(effects
				(font
					(size 1.27 1.27)
					(thickness 0.15)
				)
			)
		)
		(property "MPN" "GCM1555C1H100GA16D"
			(at 0 0 90)
			(unlocked yes)
			(layer "F.Fab")
			(hide yes)
			(effects
				(font
					(size 1 1)
					(thickness 0.15)
				)
			)
		)
		(property "Manufacturer" "Murata"
			(at 0 0 90)
			(unlocked yes)
			(layer "F.Fab")
			(hide yes)
			(effects
				(font
					(size 1 1)
					(thickness 0.15)
				)
			)
		)
		(property "License" "Apache-2.0"
			(at 0 0 90)
			(unlocked yes)
			(layer "F.Fab")
			(hide yes)
			(effects
				(font
					(size 1 1)
					(thickness 0.15)
				)
			)
		)
		(property "Author" "Antmicro"
			(at 0 0 90)
			(unlocked yes)
			(layer "F.Fab")
			(hide yes)
			(effects
				(font
					(size 1 1)
					(thickness 0.15)
				)
			)
		)
		(property "Val" "10p"
			(at 0 0 90)
			(unlocked yes)
			(layer "F.Fab")
			(hide yes)
			(effects
				(font
					(size 1 1)
					(thickness 0.15)
				)
			)
		)
		(property "Voltage" "50V"
			(at 0 0 90)
			(unlocked yes)
			(layer "F.Fab")
			(hide yes)
			(effects
				(font
					(size 1 1)
					(thickness 0.15)
				)
			)
		)
		(property "Dielectric" "C0G"
			(at 0 0 90)
			(unlocked yes)
			(layer "F.Fab")
			(hide yes)
			(effects
				(font
					(size 1 1)
					(thickness 0.15)
				)
			)
		)
		(sheetname "/X710-AT2 10GbE/")
		(sheetfile "x710-at2-10gbe.kicad_sch")
		(attr smd)
		(fp_rect
			(start -0.925 -0.47)
			(end 0.925 0.47)
			(stroke
				(width 0.05)
				(type default)
			)
			(fill no)
			(layer "F.CrtYd")
		)
		(fp_line
			(start 0.504 -0.25)
			(end 0.504 0.248)
			(stroke
				(width 0.15)
				(type solid)
			)
			(layer "F.Fab")
		)
		(fp_line
			(start -0.494 -0.25)
			(end 0.504 -0.25)
			(stroke
				(width 0.15)
				(type solid)
			)
			(layer "F.Fab")
		)
		(fp_line
			(start 0.504 0.248)
			(end -0.494 0.248)
			(stroke
				(width 0.15)
				(type solid)
			)
			(layer "F.Fab")
		)
		(fp_line
			(start -0.494 0.248)
			(end -0.494 -0.25)
			(stroke
				(width 0.15)
				(type solid)
			)
			(layer "F.Fab")
		)
		(fp_text user "License: Apache-2.0"
			(at -0.939 5.799 90)
			(layer "F.Fab")
			(effects
				(font
					(size 0.7 0.7)
					(thickness 0.15)
				)
				(justify left bottom)
			)
		)
		(fp_text user "Author: Antmicro"
			(at -0.939 3.399 90)
			(layer "F.Fab")
			(effects
				(font
					(size 0.7 0.7)
					(thickness 0.15)
				)
				(justify left bottom)
			)
		)
		(fp_text user "${REFERENCE}"
			(at -0.939 4.599 90)
			(layer "F.Fab")
			(effects
				(font
					(size 0.7 0.7)
					(thickness 0.15)
				)
				(justify left bottom)
			)
		)
		(pad "1" smd roundrect
			(at -0.48 0 90)
			(size 0.59 0.64)
			(layers "F.Cu" "F.Mask" "F.Paste")
			(roundrect_rratio 0.25)
			(net 28 "GND")
			(pintype "passive")
		)
		(pad "2" smd roundrect
			(at 0.48 0 90)
			(size 0.59 0.64)
			(layers "F.Cu" "F.Mask" "F.Paste")
			(roundrect_rratio 0.25)
			(net 215 "/X710-AT2 10GbE/MDIO0_I2C0.MDIO")
			(pintype "passive")
		)
	)
	(footprint "antmicro-footprints:R_0402_1005Metric"
		(layer "F.Cu")
		(at 97.4 107.1 180)
		(descr "Resistor SMD 0402")
		(tags "resistor SMD 0402")
		(property "Reference" "R109"
			(at 2.25 -15.55 0)
			(layer "F.SilkS")
			(effects
				(font
					(size 0.7 0.7)
					(thickness 0.15)
				)
				(justify left bottom)
			)
		)
		(property "Value" "R_100R_0402"
			(at -1.011843 1.772046 0)
			(layer "F.Fab")
			(hide yes)
			(effects
				(font
					(size 0.7 0.7)
					(thickness 0.15)
				)
				(justify right top)
			)
		)
		(property "Datasheet" "https://www.bourns.com/docs/product-datasheets/cr.pdf"
			(at 0 0 0)
			(layer "F.Fab")
			(hide yes)
			(effects
				(font
					(size 1.27 1.27)
					(thickness 0.15)
				)
			)
		)
		(property "Description" "SMD Chip Resistor, 100 ohm, ± 1%, 62.5 mW, 0402 [1005 Metric], Thick Film, General Purpose"
			(at 0 0 0)
			(layer "F.Fab")
			(hide yes)
			(effects
				(font
					(size 1.27 1.27)
					(thickness 0.15)
				)
			)
		)
		(property "MPN" "CR0402-FX-1000GLF"
			(at 0 0 180)
			(unlocked yes)
			(layer "F.Fab")
			(hide yes)
			(effects
				(font
					(size 1 1)
					(thickness 0.15)
				)
			)
		)
		(property "Manufacturer" "Bourns"
			(at 0 0 180)
			(unlocked yes)
			(layer "F.Fab")
			(hide yes)
			(effects
				(font
					(size 1 1)
					(thickness 0.15)
				)
			)
		)
		(property "License" "Apache-2.0"
			(at 0 0 180)
			(unlocked yes)
			(layer "F.Fab")
			(hide yes)
			(effects
				(font
					(size 1 1)
					(thickness 0.15)
				)
			)
		)
		(property "Author" "Antmicro"
			(at 0 0 180)
			(unlocked yes)
			(layer "F.Fab")
			(hide yes)
			(effects
				(font
					(size 1 1)
					(thickness 0.15)
				)
			)
		)
		(property "Val" "100R"
			(at 0 0 180)
			(unlocked yes)
			(layer "F.Fab")
			(hide yes)
			(effects
				(font
					(size 1 1)
					(thickness 0.15)
				)
			)
		)
		(property "Tolerance" "1%"
			(at 0 0 180)
			(unlocked yes)
			(layer "F.Fab")
			(hide yes)
			(effects
				(font
					(size 1 1)
					(thickness 0.15)
				)
			)
		)
		(sheetname "/X710-AT2 Misc/")
		(sheetfile "x710-at2-mics.kicad_sch")
		(attr smd exclude_from_pos_files exclude_from_bom dnp)
		(fp_rect
			(start -0.925 -0.47)
			(end 0.925 0.47)
			(stroke
				(width 0.05)
				(type default)
			)
			(fill no)
			(layer "F.CrtYd")
		)
		(fp_rect
			(start -0.5 -0.25)
			(end 0.5 0.25)
			(stroke
				(width 0.15)
				(type solid)
			)
			(fill no)
			(layer "F.Fab")
		)
		(pad "1" smd roundrect
			(at -0.48 0 180)
			(size 0.59 0.64)
			(layers "F.Cu" "F.Mask" "F.Paste")
			(roundrect_rratio 0.25)
			(net 28 "GND")
			(pintype "passive")
		)
		(pad "2" smd roundrect
			(at 0.48 0 180)
			(size 0.59 0.64)
			(layers "F.Cu" "F.Mask" "F.Paste")
			(roundrect_rratio 0.25)
			(net 290 "/X710-AT2 Misc/~{DEV_DIS}")
			(pintype "passive")
		)
	)
	(footprint "antmicro-footprints:C_0603_1608Metric_EIA"
		(layer "F.Cu")
		(at 60.649999 93.150001)
		(descr "Capacitor SMD 0603, IPC-7351 Density Level A")
		(tags "Capacitor 0603")
		(property "Reference" "C45"
			(at -3.319999 -1.130001 0)
			(layer "F.SilkS")
			(effects
				(font
					(size 0.7 0.7)
					(thickness 0.15)
				)
				(justify left bottom)
			)
		)
		(property "Value" "C_22u_16V_0603"
			(at -1.42757 1.770288 0)
			(layer "F.Fab")
			(hide yes)
			(effects
				(font
					(size 0.7 0.7)
					(thickness 0.15)
				)
				(justify left bottom)
			)
		)
		(property "Datasheet" "https://product.samsungsem.com/mlcc/CL10A226MO7JZN.do"
			(at 0 0 0)
			(layer "F.Fab")
			(hide yes)
			(effects
				(font
					(size 1.27 1.27)
					(thickness 0.15)
				)
			)
		)
		(property "Description" "SMD Multilayer Ceramic Capacitor"
			(at 0 0 0)
			(layer "F.Fab")
			(hide yes)
			(effects
				(font
					(size 1.27 1.27)
					(thickness 0.15)
				)
			)
		)
		(property "MPN" "CL10A226MO7JZNC"
			(at 0 0 0)
			(unlocked yes)
			(layer "F.Fab")
			(hide yes)
			(effects
				(font
					(size 1 1)
					(thickness 0.15)
				)
			)
		)
		(property "Manufacturer" "Samsung Electro-Mechanics"
			(at 0 0 0)
			(unlocked yes)
			(layer "F.Fab")
			(hide yes)
			(effects
				(font
					(size 1 1)
					(thickness 0.15)
				)
			)
		)
		(property "License" "Apache-2.0"
			(at 0 0 0)
			(unlocked yes)
			(layer "F.Fab")
			(hide yes)
			(effects
				(font
					(size 1 1)
					(thickness 0.15)
				)
			)
		)
		(property "Author" "Antmicro"
			(at 0 0 0)
			(unlocked yes)
			(layer "F.Fab")
			(hide yes)
			(effects
				(font
					(size 1 1)
					(thickness 0.15)
				)
			)
		)
		(property "Val" "22u"
			(at 0 0 0)
			(unlocked yes)
			(layer "F.Fab")
			(hide yes)
			(effects
				(font
					(size 1 1)
					(thickness 0.15)
				)
			)
		)
		(property "Voltage" "16V"
			(at 0 0 0)
			(unlocked yes)
			(layer "F.Fab")
			(hide yes)
			(effects
				(font
					(size 1 1)
					(thickness 0.15)
				)
			)
		)
		(property "Dielectric" ""
			(at 0 0 0)
			(unlocked yes)
			(layer "F.Fab")
			(hide yes)
			(effects
				(font
					(size 1 1)
					(thickness 0.15)
				)
			)
		)
		(property "Public" "False"
			(at 0 0 0)
			(unlocked yes)
			(layer "F.Fab")
			(hide yes)
			(effects
				(font
					(size 1 1)
					(thickness 0.15)
				)
			)
		)
		(sheetname "/Power/")
		(sheetfile "power.kicad_sch")
		(attr smd)
		(fp_line
			(start -0.15 -0.55)
			(end 0.15 -0.55)
			(stroke
				(width 0.15)
				(type solid)
			)
			(layer "F.SilkS")
		)
		(fp_line
			(start -0.15 0.55)
			(end 0.15 0.55)
			(stroke
				(width 0.15)
				(type solid)
			)
			(layer "F.SilkS")
		)
		(fp_rect
			(start -1.25 -0.65)
			(end 1.25 0.65)
			(stroke
				(width 0.05)
				(type solid)
			)
			(fill no)
			(layer "F.CrtYd")
		)
		(fp_rect
			(start -0.8 -0.45)
			(end 0.8 0.45)
			(stroke
				(width 0.15)
				(type solid)
			)
			(fill no)
			(layer "F.Fab")
		)
		(pad "1" smd roundrect
			(at -0.7 0)
			(size 0.8 1.1)
			(layers "F.Cu" "F.Mask" "F.Paste")
			(roundrect_rratio 0.2)
			(net 28 "GND")
			(pintype "passive")
		)
		(pad "2" smd roundrect
			(at 0.7 0)
			(size 0.8 1.1)
			(layers "F.Cu" "F.Mask" "F.Paste")
			(roundrect_rratio 0.2)
			(net 311 "/Power/+DVDD_OUT")
			(pintype "passive")
		)
	)
	(footprint "antmicro-footprints:L_WE-PMFI-353220"
		(layer "F.Cu")
		(at 70.7 83.589996 -90)
		(descr "https://www.we-online.com/en/components/products/WE-PMFI#/articles/WE-PMFI-353220")
		(property "Reference" "L1"
			(at 2.410004 2 0)
			(unlocked yes)
			(layer "F.SilkS")
			(effects
				(font
					(size 0.7 0.7)
					(thickness 0.15)
				)
				(justify left top)
			)
		)
		(property "Value" "L_2u2_5.8A_WE-PMFI-35329222"
			(at -2.600001 3.1 270)
			(unlocked yes)
			(layer "F.Fab")
			(hide yes)
			(effects
				(font
					(size 0.7 0.7)
					(thickness 0.15)
				)
				(justify left bottom)
			)
		)
		(property "Datasheet" "https://www.we-online.com/components/products/datasheet/74479335329222.pdf"
			(at 0 0 90)
			(layer "F.Fab")
			(hide yes)
			(effects
				(font
					(size 0.7 0.7)
					(thickness 0.15)
				)
				(justify right top)
			)
		)
		(property "Description" "Power Inductors - SMD WE-PMFI 2.2 uH 5.8 A 40 mOhms AEC-Q200"
			(at 0 0 90)
			(layer "F.Fab")
			(hide yes)
			(effects
				(font
					(size 0.7 0.7)
					(thickness 0.15)
				)
				(justify right top)
			)
		)
		(property "Val" "2u2/5.8A"
			(at 0 0 270)
			(unlocked yes)
			(layer "F.Fab")
			(hide yes)
			(effects
				(font
					(size 1 1)
					(thickness 0.15)
				)
			)
		)
		(property "Manufacturer" "Würth Elektronik"
			(at 0 0 270)
			(unlocked yes)
			(layer "F.Fab")
			(hide yes)
			(effects
				(font
					(size 1 1)
					(thickness 0.15)
				)
			)
		)
		(property "MPN" "74479335329222"
			(at 0 0 270)
			(unlocked yes)
			(layer "F.Fab")
			(hide yes)
			(effects
				(font
					(size 1 1)
					(thickness 0.15)
				)
			)
		)
		(property "ISat" "7.8A"
			(at 0 0 270)
			(unlocked yes)
			(layer "F.Fab")
			(hide yes)
			(effects
				(font
					(size 1 1)
					(thickness 0.15)
				)
			)
		)
		(property "IMax" "5.8A"
			(at 0 0 270)
			(unlocked yes)
			(layer "F.Fab")
			(hide yes)
			(effects
				(font
					(size 1 1)
					(thickness 0.15)
				)
			)
		)
		(property "Size" "3.5x3.2x2.0"
			(at 0 0 270)
			(unlocked yes)
			(layer "F.Fab")
			(hide yes)
			(effects
				(font
					(size 1 1)
					(thickness 0.15)
				)
			)
		)
		(property "Author" "Antmicro"
			(at 0 0 270)
			(unlocked yes)
			(layer "F.Fab")
			(hide yes)
			(effects
				(font
					(size 1 1)
					(thickness 0.15)
				)
			)
		)
		(property "License" "Apache-2.0"
			(at 0 0 270)
			(unlocked yes)
			(layer "F.Fab")
			(hide yes)
			(effects
				(font
					(size 1 1)
					(thickness 0.15)
				)
			)
		)
		(sheetname "/Power/")
		(sheetfile "power.kicad_sch")
		(attr smd)
		(fp_line
			(start -1.75 1.85)
			(end 1.75 1.85)
			(stroke
				(width 0.15)
				(type solid)
			)
			(layer "F.SilkS")
		)
		(fp_line
			(start -1.75 -1.85)
			(end 1.75 -1.85)
			(stroke
				(width 0.15)
				(type solid)
			)
			(layer "F.SilkS")
		)
		(fp_rect
			(start -2.25 -2)
			(end 2.25 2)
			(stroke
				(width 0.05)
				(type solid)
			)
			(fill no)
			(layer "F.CrtYd")
		)
		(fp_rect
			(start -1.75 -1.6)
			(end 1.75 1.6)
			(stroke
				(width 0.15)
				(type solid)
			)
			(fill no)
			(layer "F.Fab")
		)
		(pad "1" smd rect
			(at -1.5 0 270)
			(size 1 3.5)
			(layers "F.Cu" "F.Mask" "F.Paste")
			(net 333 "/Power/3V3_SW")
			(pintype "passive")
		)
		(pad "2" smd rect
			(at 1.5 0 270)
			(size 1 3.5)
			(layers "F.Cu" "F.Mask" "F.Paste")
			(net 255 "/Power/+3V3_OUT")
			(pintype "passive")
		)
	)
	(footprint "antmicro-footprints:C_0402_1005Metric"
		(layer "F.Cu")
		(at 70.66 68.38)
		(descr "Capacitor SMD 0402")
		(tags "capacitor SMD 0402")
		(property "Reference" "C201"
			(at 0.95 0.47 0)
			(layer "F.SilkS")
			(effects
				(font
					(size 0.7 0.7)
					(thickness 0.15)
				)
				(justify left bottom)
			)
		)
		(property "Value" "C_1u_25V_0402"
			(at -1.022927 2.155213 0)
			(layer "F.Fab")
			(hide yes)
			(effects
				(font
					(size 0.7 0.7)
					(thickness 0.15)
				)
				(justify left bottom)
			)
		)
		(property "Datasheet" "https://www.murata.com/products/productdetail?partno=GRM155R61E105KE11%23"
			(at 0 0 0)
			(layer "F.Fab")
			(hide yes)
			(effects
				(font
					(size 1.27 1.27)
					(thickness 0.15)
				)
			)
		)
		(property "Description" "SMD Multilayer Ceramic Capacitor, 1 µF, 25 V, 0402 [1005 Metric], ± 10%, X5R, GRM Series"
			(at 0 0 0)
			(layer "F.Fab")
			(hide yes)
			(effects
				(font
					(size 1.27 1.27)
					(thickness 0.15)
				)
			)
		)
		(property "MPN" "GRM155R61E105KE11J"
			(at 0 0 0)
			(unlocked yes)
			(layer "F.Fab")
			(hide yes)
			(effects
				(font
					(size 1 1)
					(thickness 0.15)
				)
			)
		)
		(property "Manufacturer" "Murata"
			(at 0 0 0)
			(unlocked yes)
			(layer "F.Fab")
			(hide yes)
			(effects
				(font
					(size 1 1)
					(thickness 0.15)
				)
			)
		)
		(property "License" "Apache-2.0"
			(at 0 0 0)
			(unlocked yes)
			(layer "F.Fab")
			(hide yes)
			(effects
				(font
					(size 1 1)
					(thickness 0.15)
				)
			)
		)
		(property "Author" "Antmicro"
			(at 0 0 0)
			(unlocked yes)
			(layer "F.Fab")
			(hide yes)
			(effects
				(font
					(size 1 1)
					(thickness 0.15)
				)
			)
		)
		(property "Val" "1u"
			(at 0 0 0)
			(unlocked yes)
			(layer "F.Fab")
			(hide yes)
			(effects
				(font
					(size 1 1)
					(thickness 0.15)
				)
			)
		)
		(property "Voltage" "25V"
			(at 0 0 0)
			(unlocked yes)
			(layer "F.Fab")
			(hide yes)
			(effects
				(font
					(size 1 1)
					(thickness 0.15)
				)
			)
		)
		(property "Dielectric" "X5R"
			(at 0 0 0)
			(unlocked yes)
			(layer "F.Fab")
			(hide yes)
			(effects
				(font
					(size 1 1)
					(thickness 0.15)
				)
			)
		)
		(sheetname "/Power/Ideal diode 1/")
		(sheetfile "ideal-diode.kicad_sch")
		(attr smd)
		(fp_rect
			(start -0.925 -0.47)
			(end 0.925 0.47)
			(stroke
				(width 0.05)
				(type default)
			)
			(fill no)
			(layer "F.CrtYd")
		)
		(fp_line
			(start -0.494 -0.25)
			(end 0.504 -0.25)
			(stroke
				(width 0.15)
				(type solid)
			)
			(layer "F.Fab")
		)
		(fp_line
			(start -0.494 0.248)
			(end -0.494 -0.25)
			(stroke
				(width 0.15)
				(type solid)
			)
			(layer "F.Fab")
		)
		(fp_line
			(start 0.504 -0.25)
			(end 0.504 0.248)
			(stroke
				(width 0.15)
				(type solid)
			)
			(layer "F.Fab")
		)
		(fp_line
			(start 0.504 0.248)
			(end -0.494 0.248)
			(stroke
				(width 0.15)
				(type solid)
			)
			(layer "F.Fab")
		)
		(pad "1" smd roundrect
			(at -0.48 0)
			(size 0.59 0.64)
			(layers "F.Cu" "F.Mask" "F.Paste")
			(roundrect_rratio 0.25)
			(net 28 "GND")
			(pintype "passive")
		)
		(pad "2" smd roundrect
			(at 0.48 0)
			(size 0.59 0.64)
			(layers "F.Cu" "F.Mask" "F.Paste")
			(roundrect_rratio 0.25)
			(net 314 "VCC")
			(pintype "passive")
		)
	)
	(footprint "antmicro-footprints:C_0603_1608Metric_EIA"
		(layer "F.Cu")
		(at 73.549997 86.459996 90)
		(descr "Capacitor SMD 0603, IPC-7351 Density Level A")
		(tags "Capacitor 0603")
		(property "Reference" "C8"
			(at -2.520004 0.410003 90)
			(layer "F.SilkS")
			(effects
				(font
					(size 0.7 0.7)
					(thickness 0.15)
				)
				(justify left bottom)
			)
		)
		(property "Value" "C_22u_16V_0603"
			(at -1.42757 1.770288 90)
			(layer "F.Fab")
			(hide yes)
			(effects
				(font
					(size 0.7 0.7)
					(thickness 0.15)
				)
				(justify left bottom)
			)
		)
		(property "Datasheet" "https://product.samsungsem.com/mlcc/CL10A226MO7JZN.do"
			(at 0 0 90)
			(layer "F.Fab")
			(hide yes)
			(effects
				(font
					(size 1.27 1.27)
					(thickness 0.15)
				)
			)
		)
		(property "Description" "SMD Multilayer Ceramic Capacitor"
			(at 0 0 90)
			(layer "F.Fab")
			(hide yes)
			(effects
				(font
					(size 1.27 1.27)
					(thickness 0.15)
				)
			)
		)
		(property "MPN" "CL10A226MO7JZNC"
			(at 0 0 90)
			(unlocked yes)
			(layer "F.Fab")
			(hide yes)
			(effects
				(font
					(size 1 1)
					(thickness 0.15)
				)
			)
		)
		(property "Manufacturer" "Samsung Electro-Mechanics"
			(at 0 0 90)
			(unlocked yes)
			(layer "F.Fab")
			(hide yes)
			(effects
				(font
					(size 1 1)
					(thickness 0.15)
				)
			)
		)
		(property "License" "Apache-2.0"
			(at 0 0 90)
			(unlocked yes)
			(layer "F.Fab")
			(hide yes)
			(effects
				(font
					(size 1 1)
					(thickness 0.15)
				)
			)
		)
		(property "Author" "Antmicro"
			(at 0 0 90)
			(unlocked yes)
			(layer "F.Fab")
			(hide yes)
			(effects
				(font
					(size 1 1)
					(thickness 0.15)
				)
			)
		)
		(property "Val" "22u"
			(at 0 0 90)
			(unlocked yes)
			(layer "F.Fab")
			(hide yes)
			(effects
				(font
					(size 1 1)
					(thickness 0.15)
				)
			)
		)
		(property "Voltage" "16V"
			(at 0 0 90)
			(unlocked yes)
			(layer "F.Fab")
			(hide yes)
			(effects
				(font
					(size 1 1)
					(thickness 0.15)
				)
			)
		)
		(property "Dielectric" ""
			(at 0 0 90)
			(unlocked yes)
			(layer "F.Fab")
			(hide yes)
			(effects
				(font
					(size 1 1)
					(thickness 0.15)
				)
			)
		)
		(property "Public" "False"
			(at 0 0 90)
			(unlocked yes)
			(layer "F.Fab")
			(hide yes)
			(effects
				(font
					(size 1 1)
					(thickness 0.15)
				)
			)
		)
		(sheetname "/Power/")
		(sheetfile "power.kicad_sch")
		(attr smd)
		(fp_line
			(start -0.15 -0.55)
			(end 0.15 -0.55)
			(stroke
				(width 0.15)
				(type solid)
			)
			(layer "F.SilkS")
		)
		(fp_line
			(start -0.15 0.55)
			(end 0.15 0.55)
			(stroke
				(width 0.15)
				(type solid)
			)
			(layer "F.SilkS")
		)
		(fp_rect
			(start -1.25 -0.65)
			(end 1.25 0.65)
			(stroke
				(width 0.05)
				(type solid)
			)
			(fill no)
			(layer "F.CrtYd")
		)
		(fp_rect
			(start -0.8 -0.45)
			(end 0.8 0.45)
			(stroke
				(width 0.15)
				(type solid)
			)
			(fill no)
			(layer "F.Fab")
		)
		(pad "1" smd roundrect
			(at -0.7 0 90)
			(size 0.8 1.1)
			(layers "F.Cu" "F.Mask" "F.Paste")
			(roundrect_rratio 0.2)
			(net 28 "GND")
			(pintype "passive")
		)
		(pad "2" smd roundrect
			(at 0.7 0 90)
			(size 0.8 1.1)
			(layers "F.Cu" "F.Mask" "F.Paste")
			(roundrect_rratio 0.2)
			(net 255 "/Power/+3V3_OUT")
			(pintype "passive")
		)
	)
	(footprint "antmicro-footprints:VQFN-HR-9_2x1.5mm"
		(layer "F.Cu")
		(at 56.1 103.450001 -90)
		(property "Reference" "U3"
			(at -1.190001 0.92 180)
			(layer "F.SilkS")
			(effects
				(font
					(size 0.7 0.7)
					(thickness 0.14)
					(bold yes)
				)
				(justify right top)
			)
		)
		(property "Value" "TPS566231P"
			(at -1.45 2.45 90)
			(layer "F.Fab")
			(hide yes)
			(effects
				(font
					(size 0.7 0.7)
					(thickness 0.15)
				)
				(justify right top)
			)
		)
		(property "Datasheet" "https://www.ti.com/lit/ds/symlink/tps566231.pdf"
			(at 0 -0.045 90)
			(layer "F.Fab")
			(hide yes)
			(effects
				(font
					(size 0.7 0.7)
					(thickness 0.15)
				)
				(justify right top)
			)
		)
		(property "Description" "Switching Voltage Regulators 3-V to 18-V, 6-A synchronous buck converter"
			(at -1.45 3.65 90)
			(layer "F.Fab")
			(hide yes)
			(effects
				(font
					(size 0.7 0.7)
					(thickness 0.15)
				)
				(justify right top)
			)
		)
		(property "Manufacturer" "Texas Instruments"
			(at 0 0 270)
			(unlocked yes)
			(layer "F.Fab")
			(hide yes)
			(effects
				(font
					(size 1 1)
					(thickness 0.15)
				)
			)
		)
		(property "MPN" "TPS566231PRQFR"
			(at 0 0 270)
			(unlocked yes)
			(layer "F.Fab")
			(hide yes)
			(effects
				(font
					(size 1 1)
					(thickness 0.15)
				)
			)
		)
		(property "Author" "Antmicro"
			(at 0 0 270)
			(unlocked yes)
			(layer "F.Fab")
			(hide yes)
			(effects
				(font
					(size 1 1)
					(thickness 0.15)
				)
			)
		)
		(property "License" "Apache-2.0"
			(at 0 0 270)
			(unlocked yes)
			(layer "F.Fab")
			(hide yes)
			(effects
				(font
					(size 1 1)
					(thickness 0.15)
				)
			)
		)
		(sheetname "/Power/")
		(sheetfile "power.kicad_sch")
		(attr smd)
		(fp_line
			(start -1 0.945)
			(end -0.695 0.945)
			(stroke
				(width 0.15)
				(type solid)
			)
			(layer "F.SilkS")
		)
		(fp_line
			(start 1 0.945)
			(end 0.2 0.945)
			(stroke
				(width 0.15)
				(type solid)
			)
			(layer "F.SilkS")
		)
		(fp_line
			(start -1 -0.945)
			(end -0.695 -0.945)
			(stroke
				(width 0.15)
				(type solid)
			)
			(layer "F.SilkS")
		)
		(fp_line
			(start 1 -0.945)
			(end 0.695 -0.945)
			(stroke
				(width 0.15)
				(type solid)
			)
			(layer "F.SilkS")
		)
		(fp_circle
			(center -1.18 -0.77)
			(end -1.13 -0.77)
			(stroke
				(width 0.15)
				(type solid)
			)
			(fill yes)
			(layer "F.SilkS")
		)
		(fp_rect
			(start -1.3 -1.05)
			(end 1.3 1.05)
			(stroke
				(width 0.05)
				(type solid)
			)
			(fill no)
			(layer "F.CrtYd")
		)
		(fp_rect
			(start -1 -0.75)
			(end 1 0.75)
			(stroke
				(width 0.15)
				(type solid)
			)
			(fill no)
			(layer "F.Fab")
		)
		(pad "1" smd roundrect
			(at -0.925 -0.5 270)
			(size 0.55 0.25)
			(layers "F.Cu" "F.Mask" "F.Paste")
			(roundrect_rratio 0.125)
			(net 324 "/Power/1V88_VCC")
			(pinfunction "V_{CC}")
			(pintype "passive")
		)
		(pad "2" smd roundrect
			(at -0.925 0 270)
			(size 0.55 0.25)
			(layers "F.Cu" "F.Mask" "F.Paste")
			(roundrect_rratio 0.125)
			(net 330 "/Power/1V88_FB")
			(pinfunction "FB")
			(pintype "input")
		)
		(pad "3" smd roundrect
			(at -0.925 0.5 270)
			(size 0.55 0.25)
			(layers "F.Cu" "F.Mask" "F.Paste")
			(roundrect_rratio 0.125)
			(net 353 "/Power/1V88_EN")
			(pinfunction "EN")
			(pintype "input")
		)
		(pad "4" smd roundrect
			(at -0.25 0.45 270)
			(size 0.25 1)
			(layers "F.Cu" "F.Mask" "F.Paste")
			(roundrect_rratio 0.125)
			(net 28 "GND")
			(pinfunction "PGND")
			(pintype "power_in")
		)
		(pad "5" smd roundrect
			(at 0.925 0.5 270)
			(size 0.55 0.25)
			(layers "F.Cu" "F.Mask" "F.Paste")
			(roundrect_rratio 0.125)
			(net 314 "VCC")
			(pinfunction "V_{IN}")
			(pintype "power_in")
		)
		(pad "6" smd roundrect
			(at 0.925 0 270)
			(size 0.55 0.25)
			(layers "F.Cu" "F.Mask" "F.Paste")
			(roundrect_rratio 0.125)
			(net 314 "VCC")
			(pinfunction "V_{IN}")
			(pintype "passive")
		)
		(pad "7" smd roundrect
			(at 0.925 -0.5 270)
			(size 0.55 0.25)
			(layers "F.Cu" "F.Mask" "F.Paste")
			(roundrect_rratio 0.125)
			(net 323 "/Power/1V88_BST")
			(pinfunction "BST")
			(pintype "passive")
		)
		(pad "8" smd roundrect
			(at 0.25 -0.3 270)
			(size 0.25 1.3)
			(layers "F.Cu" "F.Mask" "F.Paste")
			(roundrect_rratio 0.125)
			(net 335 "/Power/1V88_SW")
			(pinfunction "SW")
			(pintype "power_out")
		)
		(pad "9" smd roundrect
			(at -0.25 -0.675 270)
			(size 0.25 0.55)
			(layers "F.Cu" "F.Mask" "F.Paste")
			(roundrect_rratio 0.125)
			(net 369 "/Power/1V88_PG")
			(pinfunction "PG")
			(pintype "passive")
		)
	)
	(footprint "antmicro-footprints:C_0603_1608Metric"
		(layer "F.Cu")
		(at 100.45 97.95)
		(descr "Capacitor SMD 0603")
		(tags "capacitor 0603")
		(property "Reference" "C160"
			(at 4.25 0.45 0)
			(layer "F.SilkS")
			(effects
				(font
					(size 0.7 0.7)
					(thickness 0.15)
				)
				(justify left bottom)
			)
		)
		(property "Value" "C_10u_10V_X7R_0603"
			(at -1.42757 1.770288 0)
			(layer "F.Fab")
			(hide yes)
			(effects
				(font
					(size 0.7 0.7)
					(thickness 0.15)
				)
				(justify left bottom)
			)
		)
		(property "Datasheet" "https://www.murata.com/products/productdetail?partno=GRM188Z71A106KA73%23"
			(at 0 0 0)
			(layer "F.Fab")
			(hide yes)
			(effects
				(font
					(size 1.27 1.27)
					(thickness 0.15)
				)
			)
		)
		(property "Description" "SMD Multilayer Ceramic Capacitor,  10µF, 10V, 0603, ±10%, X7R"
			(at 0 0 0)
			(layer "F.Fab")
			(hide yes)
			(effects
				(font
					(size 1.27 1.27)
					(thickness 0.15)
				)
			)
		)
		(property "MPN" "GRM188Z71A106KA73D"
			(at 0 0 0)
			(unlocked yes)
			(layer "F.Fab")
			(hide yes)
			(effects
				(font
					(size 1 1)
					(thickness 0.15)
				)
			)
		)
		(property "Val" "10u"
			(at 0 0 0)
			(unlocked yes)
			(layer "F.Fab")
			(hide yes)
			(effects
				(font
					(size 1 1)
					(thickness 0.15)
				)
			)
		)
		(property "Voltage" "10V"
			(at 0 0 0)
			(unlocked yes)
			(layer "F.Fab")
			(hide yes)
			(effects
				(font
					(size 1 1)
					(thickness 0.15)
				)
			)
		)
		(property "Dielectric" "X7R"
			(at 0 0 0)
			(unlocked yes)
			(layer "F.Fab")
			(hide yes)
			(effects
				(font
					(size 1 1)
					(thickness 0.15)
				)
			)
		)
		(property "Manufacturer" "Murata"
			(at 0 0 0)
			(unlocked yes)
			(layer "F.Fab")
			(hide yes)
			(effects
				(font
					(size 1 1)
					(thickness 0.15)
				)
			)
		)
		(property "License" "Apache-2.0"
			(at 0 0 0)
			(unlocked yes)
			(layer "F.Fab")
			(hide yes)
			(effects
				(font
					(size 1 1)
					(thickness 0.15)
				)
			)
		)
		(property "Author" "Antmicro"
			(at 0 0 0)
			(unlocked yes)
			(layer "F.Fab")
			(hide yes)
			(effects
				(font
					(size 1 1)
					(thickness 0.15)
				)
			)
		)
		(sheetname "/X710-AT2 power/")
		(sheetfile "x710-at2-power.kicad_sch")
		(attr smd)
		(fp_line
			(start -0.15 -0.4)
			(end 0.15 -0.4)
			(stroke
				(width 0.15)
				(type solid)
			)
			(layer "F.SilkS")
		)
		(fp_line
			(start -0.15 0.4)
			(end 0.15 0.4)
			(stroke
				(width 0.15)
				(type solid)
			)
			(layer "F.SilkS")
		)
		(fp_rect
			(start -1.25 -0.65)
			(end 1.25 0.65)
			(stroke
				(width 0.05)
				(type solid)
			)
			(fill no)
			(layer "F.CrtYd")
		)
		(fp_rect
			(start -0.8 -0.4)
			(end 0.8 0.4)
			(stroke
				(width 0.15)
				(type solid)
			)
			(fill no)
			(layer "F.Fab")
		)
		(pad "1" smd roundrect
			(at -0.7 0)
			(size 0.8 1)
			(layers "F.Cu" "F.Mask" "F.Paste")
			(roundrect_rratio 0.2)
			(net 28 "GND")
			(pintype "passive")
		)
		(pad "2" smd roundrect
			(at 0.7 0)
			(size 0.8 1)
			(layers "F.Cu" "F.Mask" "F.Paste")
			(roundrect_rratio 0.2)
			(net 1 "VCCA")
			(pintype "passive")
		)
	)
	(footprint "antmicro-footprints:R_0402_1005Metric"
		(layer "F.Cu")
		(at 53.099998 100.550002 -90)
		(descr "Resistor SMD 0402")
		(tags "resistor SMD 0402")
		(property "Reference" "R16"
			(at -1.090002 2.909998 90)
			(layer "F.SilkS")
			(effects
				(font
					(size 0.7 0.7)
					(thickness 0.15)
				)
				(justify right top)
			)
		)
		(property "Value" "R_0R_0402"
			(at -1.011843 1.772046 90)
			(layer "F.Fab")
			(hide yes)
			(effects
				(font
					(size 0.7 0.7)
					(thickness 0.15)
				)
				(justify right top)
			)
		)
		(property "Datasheet" "https://industrial.panasonic.com/cdbs/www-data/pdf/RDA0000/AOA0000C301.pdf"
			(at 0 0 90)
			(layer "F.Fab")
			(hide yes)
			(effects
				(font
					(size 1.27 1.27)
					(thickness 0.15)
				)
			)
		)
		(property "Description" "SMD Chip Resistor, Jumper, 0 ohm, 100 mW, 0402 [1005 Metric], Thick Film, General Purpose"
			(at 0 0 90)
			(layer "F.Fab")
			(hide yes)
			(effects
				(font
					(size 1.27 1.27)
					(thickness 0.15)
				)
			)
		)
		(property "MPN" "ERJ2GE0R00X"
			(at 0 0 270)
			(unlocked yes)
			(layer "F.Fab")
			(hide yes)
			(effects
				(font
					(size 1 1)
					(thickness 0.15)
				)
			)
		)
		(property "Manufacturer" "Panasonic"
			(at 0 0 270)
			(unlocked yes)
			(layer "F.Fab")
			(hide yes)
			(effects
				(font
					(size 1 1)
					(thickness 0.15)
				)
			)
		)
		(property "License" "Apache-2.0"
			(at 0 0 270)
			(unlocked yes)
			(layer "F.Fab")
			(hide yes)
			(effects
				(font
					(size 1 1)
					(thickness 0.15)
				)
			)
		)
		(property "Author" "Antmicro"
			(at 0 0 270)
			(unlocked yes)
			(layer "F.Fab")
			(hide yes)
			(effects
				(font
					(size 1 1)
					(thickness 0.15)
				)
			)
		)
		(property "Val" "0R"
			(at 0 0 270)
			(unlocked yes)
			(layer "F.Fab")
			(hide yes)
			(effects
				(font
					(size 1 1)
					(thickness 0.15)
				)
			)
		)
		(property "Tolerance" "~"
			(at 0 0 270)
			(unlocked yes)
			(layer "F.Fab")
			(hide yes)
			(effects
				(font
					(size 1 1)
					(thickness 0.15)
				)
			)
		)
		(property "Current" "1A"
			(at 0 0 270)
			(unlocked yes)
			(layer "F.Fab")
			(hide yes)
			(effects
				(font
					(size 1 1)
					(thickness 0.15)
				)
			)
		)
		(sheetname "/Power/")
		(sheetfile "power.kicad_sch")
		(attr smd)
		(fp_rect
			(start -0.925 -0.47)
			(end 0.925 0.47)
			(stroke
				(width 0.05)
				(type default)
			)
			(fill no)
			(layer "F.CrtYd")
		)
		(fp_rect
			(start -0.5 -0.25)
			(end 0.5 0.25)
			(stroke
				(width 0.15)
				(type solid)
			)
			(fill no)
			(layer "F.Fab")
		)
		(pad "1" smd roundrect
			(at -0.48 0 270)
			(size 0.59 0.64)
			(layers "F.Cu" "F.Mask" "F.Paste")
			(roundrect_rratio 0.25)
			(net 342 "/Power/VCCD_PG")
			(pintype "passive")
		)
		(pad "2" smd roundrect
			(at 0.48 0 270)
			(size 0.59 0.64)
			(layers "F.Cu" "F.Mask" "F.Paste")
			(roundrect_rratio 0.25)
			(net 353 "/Power/1V88_EN")
			(pintype "passive")
		)
	)
	(footprint "antmicro-footprints:FCBGA-503_22x22mm_Layout21x24_P1mm"
		(locked yes)
		(layer "F.Cu")
		(at 84.975 100 180)
		(property "Reference" "U9"
			(at -11.275 11.4 0)
			(layer "F.SilkS")
			(effects
				(font
					(size 0.7 0.7)
					(thickness 0.15)
				)
				(justify right bottom)
			)
		)
		(property "Value" "EZX710AT2_S_LMR5"
			(at -11.4 12.5 0)
			(layer "F.Fab")
			(hide yes)
			(effects
				(font
					(size 0.7 0.7)
					(thickness 0.15)
				)
				(justify right top)
			)
		)
		(property "Datasheet" "https://www.google.com/url?sa=t&source=web&rct=j&opi=89978449&url=https://cdrdv2-public.intel.com/596333/596333_X710-TM4_Datasheet_v_2_4.pdf&ved=2ahUKEwiSuv20_sCOAxXVCRAIHdxGO_UQFnoECBEQAQ&usg=AOvVaw1CjGyrGWE8ZvOdw4VBsY6U"
			(at -16.625 -13.91 0)
			(layer "F.Fab")
			(hide yes)
			(effects
				(font
					(size 0.7 0.7)
					(thickness 0.15)
				)
				(justify right top)
			)
		)
		(property "Description" "Ethernet ICs Intel Ethernet Controller 10 Gigabit X7"
			(at -12.015 -0.89 0)
			(layer "F.Fab")
			(hide yes)
			(effects
				(font
					(size 0.7 0.7)
					(thickness 0.15)
				)
				(justify right top)
			)
		)
		(property "MPN" "EZX710AT2 S LMR5"
			(at 0 0 180)
			(unlocked yes)
			(layer "F.Fab")
			(hide yes)
			(effects
				(font
					(size 1 1)
					(thickness 0.15)
				)
			)
		)
		(property "Manufacturer" "Intel"
			(at 0 0 180)
			(unlocked yes)
			(layer "F.Fab")
			(hide yes)
			(effects
				(font
					(size 1 1)
					(thickness 0.15)
				)
			)
		)
		(property "Author" "Antmicro"
			(at 0 0 180)
			(unlocked yes)
			(layer "F.Fab")
			(hide yes)
			(effects
				(font
					(size 1 1)
					(thickness 0.15)
				)
			)
		)
		(property "License" "Apache-2.0"
			(at 0 0 180)
			(unlocked yes)
			(layer "F.Fab")
			(hide yes)
			(effects
				(font
					(size 1 1)
					(thickness 0.15)
				)
			)
		)
		(sheetname "/X710-AT2 power/")
		(sheetfile "x710-at2-power.kicad_sch")
		(attr smd)
		(fp_line
			(start 11.12 11.12)
			(end 11.12 5.62)
			(stroke
				(width 0.15)
				(type solid)
			)
			(layer "F.SilkS")
		)
		(fp_line
			(start 11.12 -11.12)
			(end 11.12 -5.62)
			(stroke
				(width 0.15)
				(type solid)
			)
			(layer "F.SilkS")
		)
		(fp_line
			(start 5.62 11.12)
			(end 11.12 11.12)
			(stroke
				(width 0.15)
				(type solid)
			)
			(layer "F.SilkS")
		)
		(fp_line
			(start 5.62 -11.12)
			(end 11.12 -11.12)
			(stroke
				(width 0.15)
				(type solid)
			)
			(layer "F.SilkS")
		)
		(fp_line
			(start -5.62 11.12)
			(end -11.12 11.12)
			(stroke
				(width 0.15)
				(type solid)
			)
			(layer "F.SilkS")
		)
		(fp_line
			(start -5.62 -11.12)
			(end -10 -11.12)
			(stroke
				(width 0.15)
				(type solid)
			)
			(layer "F.SilkS")
		)
		(fp_line
			(start -10 -11.12)
			(end -11.12 -10)
			(stroke
				(width 0.15)
				(type solid)
			)
			(layer "F.SilkS")
		)
		(fp_line
			(start -11.12 11.12)
			(end -11.12 5.62)
			(stroke
				(width 0.15)
				(type solid)
			)
			(layer "F.SilkS")
		)
		(fp_line
			(start -11.12 -10)
			(end -11.12 -5.62)
			(stroke
				(width 0.15)
				(type solid)
			)
			(layer "F.SilkS")
		)
		(fp_circle
			(center -11 -11)
			(end -11 -10.9)
			(stroke
				(width 0.15)
				(type solid)
			)
			(fill yes)
			(layer "F.SilkS")
		)
		(fp_rect
			(start -11.4 -11.4)
			(end 11.4 11.4)
			(stroke
				(width 0.05)
				(type solid)
			)
			(fill no)
			(layer "F.CrtYd")
		)
		(fp_line
			(start 11 11)
			(end 11 -11)
			(stroke
				(width 0.15)
				(type solid)
			)
			(layer "F.Fab")
		)
		(fp_line
			(start 11 -11)
			(end -10 -11)
			(stroke
				(width 0.15)
				(type solid)
			)
			(layer "F.Fab")
		)
		(fp_line
			(start -10 -11)
			(end -11 -10)
			(stroke
				(width 0.15)
				(type solid)
			)
			(layer "F.Fab")
		)
		(fp_line
			(start -11 11)
			(end 11 11)
			(stroke
				(width 0.15)
				(type solid)
			)
			(layer "F.Fab")
		)
		(fp_line
			(start -11 -10)
			(end -11 11)
			(stroke
				(width 0.15)
				(type solid)
			)
			(layer "F.Fab")
		)
		(pad "A3" smd circle
			(at -9.25 -9.95 180)
			(size 0.5 0.5)
			(layers "F.Cu" "F.Mask" "F.Paste")
			(net 28 "GND")
			(pinfunction "VSSA")
			(pintype "power_in")
		)
		(pad "A5" smd circle
			(at -8.25 -9.95 180)
			(size 0.5 0.5)
			(layers "F.Cu" "F.Mask" "F.Paste")
			(net 349 "unconnected-(U9B-SER1_RX_N-PadA5)")
			(pinfunction "SER1_RX_N")
			(pintype "input+no_connect")
		)
		(pad "A7" smd circle
			(at -7.25 -9.95 180)
			(size 0.5 0.5)
			(layers "F.Cu" "F.Mask" "F.Paste")
			(net 28 "GND")
			(pinfunction "VSSA")
			(pintype "passive")
		)
		(pad "A9" smd circle
			(at -6.25 -9.95 180)
			(size 0.5 0.5)
			(layers "F.Cu" "F.Mask" "F.Paste")
			(net 265 "unconnected-(U9B-SER1_TX_P-PadA9)")
			(pinfunction "SER1_TX_P")
			(pintype "output+no_connect")
		)
		(pad "A11" smd circle
			(at -5.25 -9.95 180)
			(size 0.5 0.5)
			(layers "F.Cu" "F.Mask" "F.Paste")
			(net 28 "GND")
			(pinfunction "VSSA")
			(pintype "passive")
		)
		(pad "A13" smd circle
			(at -4.25 -9.95 180)
			(size 0.5 0.5)
			(layers "F.Cu" "F.Mask" "F.Paste")
			(net 178 "unconnected-(U9B-SER0_RX_N-PadA13)")
			(pinfunction "SER0_RX_N")
			(pintype "input+no_connect")
		)
		(pad "A15" smd circle
			(at -3.25 -9.95 180)
			(size 0.5 0.5)
			(layers "F.Cu" "F.Mask" "F.Paste")
			(net 28 "GND")
			(pinfunction "VSSA")
			(pintype "passive")
		)
		(pad "A17" smd circle
			(at -2.25 -9.95 180)
			(size 0.5 0.5)
			(layers "F.Cu" "F.Mask" "F.Paste")
			(net 192 "unconnected-(U9B-SER0_TX_P-PadA17)")
			(pinfunction "SER0_TX_P")
			(pintype "output+no_connect")
		)
		(pad "A19" smd circle
			(at -1.25 -9.95 180)
			(size 0.5 0.5)
			(layers "F.Cu" "F.Mask" "F.Paste")
			(net 28 "GND")
			(pinfunction "VSSA")
			(pintype "passive")
		)
		(pad "A21" smd circle
			(at -0.25 -9.95 180)
			(size 0.5 0.5)
			(layers "F.Cu" "F.Mask" "F.Paste")
			(net 28 "GND")
			(pinfunction "AVSS")
			(pintype "power_in")
		)
		(pad "A23" smd circle
			(at 0.75 -9.95 180)
			(size 0.5 0.5)
			(layers "F.Cu" "F.Mask" "F.Paste")
			(net 69 "/2xRJ45/Ethernet_P1.D1+")
			(pinfunction "P1_A_P")
			(pintype "bidirectional")
		)
		(pad "A25" smd circle
			(at 1.75 -9.95 180)
			(size 0.5 0.5)
			(layers "F.Cu" "F.Mask" "F.Paste")
			(net 60 "/2xRJ45/Ethernet_P1.D2-")
			(pinfunction "P1_B_N")
			(pintype "bidirectional")
		)
		(pad "A27" smd circle
			(at 2.75 -9.95 180)
			(size 0.5 0.5)
			(layers "F.Cu" "F.Mask" "F.Paste")
			(net 63 "/2xRJ45/Ethernet_P1.D3+")
			(pinfunction "P1_C_P")
			(pintype "bidirectional")
		)
		(pad "A29" smd circle
			(at 3.75 -9.95 180)
			(size 0.5 0.5)
			(layers "F.Cu" "F.Mask" "F.Paste")
			(net 68 "/2xRJ45/Ethernet_P1.D4-")
			(pinfunction "P1_D_N")
			(pintype "bidirectional")
		)
		(pad "A31" smd circle
			(at 4.75 -9.95 180)
			(size 0.5 0.5)
			(layers "F.Cu" "F.Mask" "F.Paste")
			(net 28 "GND")
			(pinfunction "AVSS")
			(pintype "passive")
		)
		(pad "A33" smd circle
			(at 5.75 -9.95 180)
			(size 0.5 0.5)
			(layers "F.Cu" "F.Mask" "F.Paste")
			(net 55 "/2xRJ45/Ethernet_P0.D4+")
			(pinfunction "P0_D_P")
			(pintype "bidirectional")
		)
		(pad "A35" smd circle
			(at 6.75 -9.95 180)
			(size 0.5 0.5)
			(layers "F.Cu" "F.Mask" "F.Paste")
			(net 50 "/2xRJ45/Ethernet_P0.D3-")
			(pinfunction "P0_C_N")
			(pintype "bidirectional")
		)
		(pad "A37" smd circle
			(at 7.75 -9.95 180)
			(size 0.5 0.5)
			(layers "F.Cu" "F.Mask" "F.Paste")
			(net 51 "/2xRJ45/Ethernet_P0.D2+")
			(pinfunction "P0_B_P")
			(pintype "bidirectional")
		)
		(pad "A39" smd circle
			(at 8.75 -9.95 180)
			(size 0.5 0.5)
			(layers "F.Cu" "F.Mask" "F.Paste")
			(net 49 "/2xRJ45/Ethernet_P0.D1-")
			(pinfunction "P0_A_N")
			(pintype "bidirectional")
		)
		(pad "A41" smd circle
			(at 9.75 -9.95 180)
			(size 0.5 0.5)
			(layers "F.Cu" "F.Mask" "F.Paste")
			(net 175 "unconnected-(U9G-RSVDA41_NC-PadA41)")
			(pinfunction "RSVDA41_NC")
			(pintype "passive+no_connect")
		)
		(pad "AA1" smd circle
			(at -10.25 7.35 180)
			(size 0.5 0.5)
			(layers "F.Cu" "F.Mask" "F.Paste")
			(net 402 "/X710-AT2 PCIe/CLK+")
			(pinfunction "PE_CLK_P")
			(pintype "input")
		)
		(pad "AA3" smd circle
			(at -9.25 7.35 180)
			(size 0.5 0.5)
			(layers "F.Cu" "F.Mask" "F.Paste")
			(net 28 "GND")
			(pinfunction "VSSA")
			(pintype "passive")
		)
		(pad "AA5" smd circle
			(at -8.25 7.35 180)
			(size 0.5 0.5)
			(layers "F.Cu" "F.Mask" "F.Paste")
			(net 39 "/OCuLink/PCIe_{x4}.RX0+")
			(pinfunction "PER_0_P")
			(pintype "input")
		)
		(pad "AA7" smd circle
			(at -7.25 7.35 180)
			(size 0.5 0.5)
			(layers "F.Cu" "F.Mask" "F.Paste")
			(net 36 "/OCuLink/PCIe_{x4}.RX0-")
			(pinfunction "PER_0_N")
			(pintype "input")
		)
		(pad "AA9" smd circle
			(at -6.25 7.35 180)
			(size 0.5 0.5)
			(layers "F.Cu" "F.Mask" "F.Paste")
			(net 28 "GND")
			(pinfunction "VSSA")
			(pintype "passive")
		)
		(pad "AA11" smd circle
			(at -5.25 7.35 180)
			(size 0.5 0.5)
			(layers "F.Cu" "F.Mask" "F.Paste")
			(net 28 "GND")
			(pinfunction "VSSA")
			(pintype "passive")
		)
		(pad "AA13" smd circle
			(at -4.25 7.35 180)
			(size 0.5 0.5)
			(layers "F.Cu" "F.Mask" "F.Paste")
			(net 28 "GND")
			(pinfunction "VSSA")
			(pintype "passive")
		)
		(pad "AA15" smd circle
			(at -3.25 7.35 180)
			(size 0.5 0.5)
			(layers "F.Cu" "F.Mask" "F.Paste")
			(net 28 "GND")
			(pinfunction "VSSA")
			(pintype "passive")
		)
		(pad "AA17" smd circle
			(at -2.25 7.35 180)
			(size 0.5 0.5)
			(layers "F.Cu" "F.Mask" "F.Paste")
			(net 28 "GND")
			(pinfunction "VSSA")
			(pintype "passive")
		)
		(pad "AA19" smd circle
			(at -1.25 7.35 180)
			(size 0.5 0.5)
			(layers "F.Cu" "F.Mask" "F.Paste")
			(net 28 "GND")
			(pinfunction "VSSA")
			(pintype "passive")
		)
		(pad "AA21" smd circle
			(at -0.25 7.35 180)
			(size 0.5 0.5)
			(layers "F.Cu" "F.Mask" "F.Paste")
			(net 28 "GND")
			(pinfunction "VSSA")
			(pintype "passive")
		)
		(pad "AA23" smd circle
			(at 0.75 7.35 180)
			(size 0.5 0.5)
			(layers "F.Cu" "F.Mask" "F.Paste")
			(net 28 "GND")
			(pinfunction "VSSA")
			(pintype "passive")
		)
		(pad "AA25" smd circle
			(at 1.75 7.35 180)
			(size 0.5 0.5)
			(layers "F.Cu" "F.Mask" "F.Paste")
			(net 28 "GND")
			(pinfunction "VSSA")
			(pintype "passive")
		)
		(pad "AA27" smd circle
			(at 2.75 7.35 180)
			(size 0.5 0.5)
			(layers "F.Cu" "F.Mask" "F.Paste")
			(net 244 "unconnected-(U9A-PER_4_P-PadAA27)")
			(pinfunction "PER_4_P")
			(pintype "input+no_connect")
		)
		(pad "AA29" smd circle
			(at 3.75 7.35 180)
			(size 0.5 0.5)
			(layers "F.Cu" "F.Mask" "F.Paste")
			(net 28 "GND")
			(pinfunction "VSSA")
			(pintype "passive")
		)
		(pad "AA31" smd circle
			(at 4.75 7.35 180)
			(size 0.5 0.5)
			(layers "F.Cu" "F.Mask" "F.Paste")
			(net 267 "unconnected-(U9A-PER_5_N-PadAA31)")
			(pinfunction "PER_5_N")
			(pintype "input+no_connect")
		)
		(pad "AA33" smd circle
			(at 5.75 7.35 180)
			(size 0.5 0.5)
			(layers "F.Cu" "F.Mask" "F.Paste")
			(net 28 "GND")
			(pinfunction "VSSA")
			(pintype "passive")
		)
		(pad "AA35" smd circle
			(at 6.75 7.35 180)
			(size 0.5 0.5)
			(layers "F.Cu" "F.Mask" "F.Paste")
			(net 247 "unconnected-(U9A-PER_6_N-PadAA35)")
			(pinfunction "PER_6_N")
			(pintype "input+no_connect")
		)
		(pad "AA37" smd circle
			(at 7.75 7.35 180)
			(size 0.5 0.5)
			(layers "F.Cu" "F.Mask" "F.Paste")
			(net 28 "GND")
			(pinfunction "VSSA")
			(pintype "passive")
		)
		(pad "AA39" smd circle
			(at 8.75 7.35 180)
			(size 0.5 0.5)
			(layers "F.Cu" "F.Mask" "F.Paste")
			(net 202 "unconnected-(U9A-PER_7_N-PadAA39)")
			(pinfunction "PER_7_N")
			(pintype "input+no_connect")
		)
		(pad "AA41" smd circle
			(at 9.75 7.35 180)
			(size 0.5 0.5)
			(layers "F.Cu" "F.Mask" "F.Paste")
			(net 28 "GND")
			(pinfunction "VSSA")
			(pintype "passive")
		)
		(pad "AB2" smd circle
			(at -9.75 8.215 180)
			(size 0.5 0.5)
			(layers "F.Cu" "F.Mask" "F.Paste")
			(net 403 "/X710-AT2 PCIe/CLK-")
			(pinfunction "PE_CLK_N")
			(pintype "input")
		)
		(pad "AB4" smd circle
			(at -8.75 8.215 180)
			(size 0.5 0.5)
			(layers "F.Cu" "F.Mask" "F.Paste")
			(net 28 "GND")
			(pinfunction "VSSA")
			(pintype "passive")
		)
		(pad "AB6" smd circle
			(at -7.75 8.215 180)
			(size 0.5 0.5)
			(layers "F.Cu" "F.Mask" "F.Paste")
			(net 28 "GND")
			(pinfunction "VSSA")
			(pintype "passive")
		)
		(pad "AB8" smd circle
			(at -6.75 8.215 180)
			(size 0.5 0.5)
			(layers "F.Cu" "F.Mask" "F.Paste")
			(net 28 "GND")
			(pinfunction "VSSA")
			(pintype "passive")
		)
		(pad "AB10" smd circle
			(at -5.75 8.215 180)
			(size 0.5 0.5)
			(layers "F.Cu" "F.Mask" "F.Paste")
			(net 37 "/OCuLink/PCIe_{x4}.RX1+")
			(pinfunction "PER_1_P")
			(pintype "input")
		)
		(pad "AB12" smd circle
			(at -4.75 8.215 180)
			(size 0.5 0.5)
			(layers "F.Cu" "F.Mask" "F.Paste")
			(net 34 "/OCuLink/PCIe_{x4}.RX1-")
			(pinfunction "PER_1_N")
			(pintype "input")
		)
		(pad "AB14" smd circle
			(at -3.75 8.215 180)
			(size 0.5 0.5)
			(layers "F.Cu" "F.Mask" "F.Paste")
			(net 28 "GND")
			(pinfunction "VSSA")
			(pintype "passive")
		)
		(pad "AB16" smd circle
			(at -2.75 8.215 180)
			(size 0.5 0.5)
			(layers "F.Cu" "F.Mask" "F.Paste")
			(net 80 "/OCuLink/PCIe_{x4}.RX2+")
			(pinfunction "PER_2_P")
			(pintype "input")
		)
		(pad "AB18" smd circle
			(at -1.75 8.215 180)
			(size 0.5 0.5)
			(layers "F.Cu" "F.Mask" "F.Paste")
			(net 104 "/OCuLink/PCIe_{x4}.RX2-")
			(pinfunction "PER_2_N")
			(pintype "input")
		)
		(pad "AB20" smd circle
			(at -0.75 8.215 180)
			(size 0.5 0.5)
			(layers "F.Cu" "F.Mask" "F.Paste")
			(net 28 "GND")
			(pinfunction "VSSA")
			(pintype "passive")
		)
		(pad "AB22" smd circle
			(at 0.25 8.215 180)
			(size 0.5 0.5)
			(layers "F.Cu" "F.Mask" "F.Paste")
			(net 98 "/OCuLink/PCIe_{x4}.RX3+")
			(pinfunction "PER_3_P")
			(pintype "input")
		)
		(pad "AB24" smd circle
			(at 1.25 8.215 180)
			(size 0.5 0.5)
			(layers "F.Cu" "F.Mask" "F.Paste")
			(net 109 "/OCuLink/PCIe_{x4}.RX3-")
			(pinfunction "PER_3_N")
			(pintype "input")
		)
		(pad "AB26" smd circle
			(at 2.25 8.215 180)
			(size 0.5 0.5)
			(layers "F.Cu" "F.Mask" "F.Paste")
			(net 28 "GND")
			(pinfunction "VSSA")
			(pintype "passive")
		)
		(pad "AB28" smd circle
			(at 3.25 8.215 180)
			(size 0.5 0.5)
			(layers "F.Cu" "F.Mask" "F.Paste")
			(net 273 "unconnected-(U9A-PER_4_N-PadAB28)")
			(pinfunction "PER_4_N")
			(pintype "input+no_connect")
		)
		(pad "AB30" smd circle
			(at 4.25 8.215 180)
			(size 0.5 0.5)
			(layers "F.Cu" "F.Mask" "F.Paste")
			(net 28 "GND")
			(pinfunction "VSSA")
			(pintype "passive")
		)
		(pad "AB32" smd circle
			(at 5.25 8.215 180)
			(size 0.5 0.5)
			(layers "F.Cu" "F.Mask" "F.Paste")
			(net 28 "GND")
			(pinfunction "VSSA")
			(pintype "passive")
		)
		(pad "AB34" smd circle
			(at 6.25 8.215 180)
			(size 0.5 0.5)
			(layers "F.Cu" "F.Mask" "F.Paste")
			(net 28 "GND")
			(pinfunction "VSSA")
			(pintype "passive")
		)
		(pad "AB36" smd circle
			(at 7.25 8.215 180)
			(size 0.5 0.5)
			(layers "F.Cu" "F.Mask" "F.Paste")
			(net 28 "GND")
			(pinfunction "VSSA")
			(pintype "passive")
		)
		(pad "AB38" smd circle
			(at 8.25 8.215 180)
			(size 0.5 0.5)
			(layers "F.Cu" "F.Mask" "F.Paste")
			(net 28 "GND")
			(pinfunction "VSSA")
			(pintype "passive")
		)
		(pad "AB40" smd circle
			(at 9.25 8.215 180)
			(size 0.5 0.5)
			(layers "F.Cu" "F.Mask" "F.Paste")
			(net 28 "GND")
			(pinfunction "VSSA")
			(pintype "passive")
		)
		(pad "AB42" smd circle
			(at 10.25 8.215 180)
			(size 0.5 0.5)
			(layers "F.Cu" "F.Mask" "F.Paste")
			(net 99 "/X710-AT2 Misc/LAN_PWR_GOOD")
			(pinfunction "LAN_PWR_GOOD")
			(pintype "input")
		)
		(pad "AC1" smd circle
			(at -10.25 9.08 180)
			(size 0.5 0.5)
			(layers "F.Cu" "F.Mask" "F.Paste")
			(net 28 "GND")
			(pinfunction "VSSA")
			(pintype "passive")
		)
		(pad "AC3" smd circle
			(at -9.25 9.08 180)
			(size 0.5 0.5)
			(layers "F.Cu" "F.Mask" "F.Paste")
			(net 28 "GND")
			(pinfunction "VSSA")
			(pintype "passive")
		)
		(pad "AC5" smd circle
			(at -8.25 9.08 180)
			(size 0.5 0.5)
			(layers "F.Cu" "F.Mask" "F.Paste")
			(net 33 "/X710-AT2 PCIe/PCIe_{x4}_AC.TX0-")
			(pinfunction "PET_0_N")
			(pintype "output")
		)
		(pad "AC7" smd circle
			(at -7.25 9.08 180)
			(size 0.5 0.5)
			(layers "F.Cu" "F.Mask" "F.Paste")
			(net 28 "GND")
			(pinfunction "VSSA")
			(pintype "passive")
		)
		(pad "AC9" smd circle
			(at -6.25 9.08 180)
			(size 0.5 0.5)
			(layers "F.Cu" "F.Mask" "F.Paste")
			(net 28 "GND")
			(pinfunction "VSSA")
			(pintype "passive")
		)
		(pad "AC11" smd circle
			(at -5.25 9.08 180)
			(size 0.5 0.5)
			(layers "F.Cu" "F.Mask" "F.Paste")
			(net 28 "GND")
			(pinfunction "VSSA")
			(pintype "passive")
		)
		(pad "AC13" smd circle
			(at -4.25 9.08 180)
			(size 0.5 0.5)
			(layers "F.Cu" "F.Mask" "F.Paste")
			(net 28 "GND")
			(pinfunction "VSSA")
			(pintype "passive")
		)
		(pad "AC15" smd circle
			(at -3.25 9.08 180)
			(size 0.5 0.5)
			(layers "F.Cu" "F.Mask" "F.Paste")
			(net 28 "GND")
			(pinfunction "VSSA")
			(pintype "passive")
		)
		(pad "AC17" smd circle
			(at -2.25 9.08 180)
			(size 0.5 0.5)
			(layers "F.Cu" "F.Mask" "F.Paste")
			(net 28 "GND")
			(pinfunction "VSSA")
			(pintype "passive")
		)
		(pad "AC19" smd circle
			(at -1.25 9.08 180)
			(size 0.5 0.5)
			(layers "F.Cu" "F.Mask" "F.Paste")
			(net 28 "GND")
			(pinfunction "VSSA")
			(pintype "passive")
		)
		(pad "AC21" smd circle
			(at -0.25 9.08 180)
			(size 0.5 0.5)
			(layers "F.Cu" "F.Mask" "F.Paste")
			(net 28 "GND")
			(pinfunction "VSSA")
			(pintype "passive")
		)
		(pad "AC23" smd circle
			(at 0.75 9.08 180)
			(size 0.5 0.5)
			(layers "F.Cu" "F.Mask" "F.Paste")
			(net 28 "GND")
			(pinfunction "VSSA")
			(pintype "passive")
		)
		(pad "AC25" smd circle
			(at 1.75 9.08 180)
			(size 0.5 0.5)
			(layers "F.Cu" "F.Mask" "F.Paste")
			(net 28 "GND")
			(pinfunction "VSSA")
			(pintype "passive")
		)
		(pad "AC27" smd circle
			(at 2.75 9.08 180)
			(size 0.5 0.5)
			(layers "F.Cu" "F.Mask" "F.Paste")
			(net 28 "GND")
			(pinfunction "VSSA")
			(pintype "passive")
		)
		(pad "AC29" smd circle
			(at 3.75 9.08 180)
			(size 0.5 0.5)
			(layers "F.Cu" "F.Mask" "F.Paste")
			(net 28 "GND")
			(pinfunction "VSSA")
			(pintype "passive")
		)
		(pad "AC31" smd circle
			(at 4.75 9.08 180)
			(size 0.5 0.5)
			(layers "F.Cu" "F.Mask" "F.Paste")
			(net 252 "unconnected-(U9A-PET_5_P-PadAC31)")
			(pinfunction "PET_5_P")
			(pintype "output+no_connect")
		)
		(pad "AC33" smd circle
			(at 5.75 9.08 180)
			(size 0.5 0.5)
			(layers "F.Cu" "F.Mask" "F.Paste")
			(net 28 "GND")
			(pinfunction "VSSA")
			(pintype "passive")
		)
		(pad "AC35" smd circle
			(at 6.75 9.08 180)
			(size 0.5 0.5)
			(layers "F.Cu" "F.Mask" "F.Paste")
			(net 243 "unconnected-(U9A-PET_6_P-PadAC35)")
			(pinfunction "PET_6_P")
			(pintype "output+no_connect")
		)
		(pad "AC37" smd circle
			(at 7.75 9.08 180)
			(size 0.5 0.5)
			(layers "F.Cu" "F.Mask" "F.Paste")
			(net 28 "GND")
			(pinfunction "VSSA")
			(pintype "passive")
		)
		(pad "AC39" smd circle
			(at 8.75 9.08 180)
			(size 0.5 0.5)
			(layers "F.Cu" "F.Mask" "F.Paste")
			(net 307 "unconnected-(U9A-PET_7_P-PadAC39)")
			(pinfunction "PET_7_P")
			(pintype "output+no_connect")
		)
		(pad "AC41" smd circle
			(at 9.75 9.08 180)
			(size 0.5 0.5)
			(layers "F.Cu" "F.Mask" "F.Paste")
			(net 28 "GND")
			(pinfunction "VSSA")
			(pintype "passive")
		)
		(pad "AD2" smd circle
			(at -9.75 9.945 180)
			(size 0.5 0.5)
			(layers "F.Cu" "F.Mask" "F.Paste")
			(net 28 "GND")
			(pinfunction "VSSA")
			(pintype "passive")
		)
		(pad "AD4" smd circle
			(at -8.75 9.945 180)
			(size 0.5 0.5)
			(layers "F.Cu" "F.Mask" "F.Paste")
			(net 32 "/X710-AT2 PCIe/PCIe_{x4}_AC.TX0+")
			(pinfunction "PET_0_P")
			(pintype "output")
		)
		(pad "AD6" smd circle
			(at -7.75 9.945 180)
			(size 0.5 0.5)
			(layers "F.Cu" "F.Mask" "F.Paste")
			(net 28 "GND")
			(pinfunction "VSSA")
			(pintype "passive")
		)
		(pad "AD8" smd circle
			(at -6.75 9.945 180)
			(size 0.5 0.5)
			(layers "F.Cu" "F.Mask" "F.Paste")
			(net 35 "/X710-AT2 PCIe/PCIe_{x4}_AC.TX1+")
			(pinfunction "PET_1_P")
			(pintype "output")
		)
		(pad "AD10" smd circle
			(at -5.75 9.945 180)
			(size 0.5 0.5)
			(layers "F.Cu" "F.Mask" "F.Paste")
			(net 38 "/X710-AT2 PCIe/PCIe_{x4}_AC.TX1-")
			(pinfunction "PET_1_N")
			(pintype "output")
		)
		(pad "AD12" smd circle
			(at -4.75 9.945 180)
			(size 0.5 0.5)
			(layers "F.Cu" "F.Mask" "F.Paste")
			(net 28 "GND")
			(pinfunction "VSSA")
			(pintype "passive")
		)
		(pad "AD14" smd circle
			(at -3.75 9.945 180)
			(size 0.5 0.5)
			(layers "F.Cu" "F.Mask" "F.Paste")
			(net 40 "/X710-AT2 PCIe/PCIe_{x4}_AC.TX2+")
			(pinfunction "PET_2_P")
			(pintype "output")
		)
		(pad "AD16" smd circle
			(at -2.75 9.945 180)
			(size 0.5 0.5)
			(layers "F.Cu" "F.Mask" "F.Paste")
			(net 41 "/X710-AT2 PCIe/PCIe_{x4}_AC.TX2-")
			(pinfunction "PET_2_N")
			(pintype "output")
		)
		(pad "AD18" smd circle
			(at -1.75 9.945 180)
			(size 0.5 0.5)
			(layers "F.Cu" "F.Mask" "F.Paste")
			(net 28 "GND")
			(pinfunction "VSSA")
			(pintype "passive")
		)
		(pad "AD20" smd circle
			(at -0.75 9.945 180)
			(size 0.5 0.5)
			(layers "F.Cu" "F.Mask" "F.Paste")
			(net 44 "/X710-AT2 PCIe/PCIe_{x4}_AC.TX3+")
			(pinfunction "PET_3_P")
			(pintype "output")
		)
		(pad "AD22" smd circle
			(at 0.25 9.945 180)
			(size 0.5 0.5)
			(layers "F.Cu" "F.Mask" "F.Paste")
			(net 46 "/X710-AT2 PCIe/PCIe_{x4}_AC.TX3-")
			(pinfunction "PET_3_N")
			(pintype "output")
		)
		(pad "AD24" smd circle
			(at 1.25 9.945 180)
			(size 0.5 0.5)
			(layers "F.Cu" "F.Mask" "F.Paste")
			(net 28 "GND")
			(pinfunction "VSSA")
			(pintype "passive")
		)
		(pad "AD26" smd circle
			(at 2.25 9.945 180)
			(size 0.5 0.5)
			(layers "F.Cu" "F.Mask" "F.Paste")
			(net 214 "unconnected-(U9A-PET_4_P-PadAD26)")
			(pinfunction "PET_4_P")
			(pintype "output+no_connect")
		)
		(pad "AD28" smd circle
			(at 3.25 9.945 180)
			(size 0.5 0.5)
			(layers "F.Cu" "F.Mask" "F.Paste")
			(net 275 "unconnected-(U9A-PET_4_N-PadAD28)")
			(pinfunction "PET_4_N")
			(pintype "output+no_connect")
		)
		(pad "AD30" smd circle
			(at 4.25 9.945 180)
			(size 0.5 0.5)
			(layers "F.Cu" "F.Mask" "F.Paste")
			(net 28 "GND")
			(pinfunction "VSSA")
			(pintype "passive")
		)
		(pad "AD32" smd circle
			(at 5.25 9.945 180)
			(size 0.5 0.5)
			(layers "F.Cu" "F.Mask" "F.Paste")
			(net 348 "unconnected-(U9A-PET_5_N-PadAD32)")
			(pinfunction "PET_5_N")
			(pintype "output+no_connect")
		)
		(pad "AD34" smd circle
			(at 6.25 9.945 180)
			(size 0.5 0.5)
			(layers "F.Cu" "F.Mask" "F.Paste")
			(net 28 "GND")
			(pinfunction "VSSA")
			(pintype "passive")
		)
		(pad "AD36" smd circle
			(at 7.25 9.945 180)
			(size 0.5 0.5)
			(layers "F.Cu" "F.Mask" "F.Paste")
			(net 245 "unconnected-(U9A-PET_6_N-PadAD36)")
			(pinfunction "PET_6_N")
			(pintype "output+no_connect")
		)
		(pad "AD38" smd circle
			(at 8.25 9.945 180)
			(size 0.5 0.5)
			(layers "F.Cu" "F.Mask" "F.Paste")
			(net 28 "GND")
			(pinfunction "VSSA")
			(pintype "passive")
		)
		(pad "AD40" smd circle
			(at 9.25 9.945 180)
			(size 0.5 0.5)
			(layers "F.Cu" "F.Mask" "F.Paste")
			(net 164 "unconnected-(U9A-PET_7_N-PadAD40)")
			(pinfunction "PET_7_N")
			(pintype "output+no_connect")
		)
		(pad "AD42" smd circle
			(at 10.25 9.945 180)
			(size 0.5 0.5)
			(layers "F.Cu" "F.Mask" "F.Paste")
			(net 28 "GND")
			(pinfunction "VSSA")
			(pintype "passive")
		)
		(pad "B2" smd circle
			(at -9.75 -9.085 180)
			(size 0.5 0.5)
			(layers "F.Cu" "F.Mask" "F.Paste")
			(net 28 "GND")
			(pinfunction "VSSA")
			(pintype "passive")
		)
		(pad "B4" smd circle
			(at -8.75 -9.085 180)
			(size 0.5 0.5)
			(layers "F.Cu" "F.Mask" "F.Paste")
			(net 28 "GND")
			(pinfunction "VSSA")
			(pintype "passive")
		)
		(pad "B6" smd circle
			(at -7.75 -9.085 180)
			(size 0.5 0.5)
			(layers "F.Cu" "F.Mask" "F.Paste")
			(net 282 "unconnected-(U9B-SER1_RX_P-PadB6)")
			(pinfunction "SER1_RX_P")
			(pintype "input+no_connect")
		)
		(pad "B8" smd circle
			(at -6.75 -9.085 180)
			(size 0.5 0.5)
			(layers "F.Cu" "F.Mask" "F.Paste")
			(net 28 "GND")
			(pinfunction "VSSA")
			(pintype "passive")
		)
		(pad "B10" smd circle
			(at -5.75 -9.085 180)
			(size 0.5 0.5)
			(layers "F.Cu" "F.Mask" "F.Paste")
			(net 235 "unconnected-(U9B-SER1_TX_N-PadB10)")
			(pinfunction "SER1_TX_N")
			(pintype "output+no_connect")
		)
		(pad "B12" smd circle
			(at -4.75 -9.085 180)
			(size 0.5 0.5)
			(layers "F.Cu" "F.Mask" "F.Paste")
			(net 28 "GND")
			(pinfunction "VSSA")
			(pintype "passive")
		)
		(pad "B14" smd circle
			(at -3.75 -9.085 180)
			(size 0.5 0.5)
			(layers "F.Cu" "F.Mask" "F.Paste")
			(net 170 "unconnected-(U9B-SER0_RX_P-PadB14)")
			(pinfunction "SER0_RX_P")
			(pintype "input+no_connect")
		)
		(pad "B16" smd circle
			(at -2.75 -9.085 180)
			(size 0.5 0.5)
			(layers "F.Cu" "F.Mask" "F.Paste")
			(net 28 "GND")
			(pinfunction "VSSA")
			(pintype "passive")
		)
		(pad "B18" smd circle
			(at -1.75 -9.085 180)
			(size 0.5 0.5)
			(layers "F.Cu" "F.Mask" "F.Paste")
			(net 272 "unconnected-(U9B-SER0_TX_N-PadB18)")
			(pinfunction "SER0_TX_N")
			(pintype "output+no_connect")
		)
		(pad "B20" smd circle
			(at -0.75 -9.085 180)
			(size 0.5 0.5)
			(layers "F.Cu" "F.Mask" "F.Paste")
			(net 28 "GND")
			(pinfunction "VSSA")
			(pintype "passive")
		)
		(pad "B22" smd circle
			(at 0.25 -9.085 180)
			(size 0.5 0.5)
			(layers "F.Cu" "F.Mask" "F.Paste")
			(net 28 "GND")
			(pinfunction "AVSS")
			(pintype "passive")
		)
		(pad "B24" smd circle
			(at 1.25 -9.085 180)
			(size 0.5 0.5)
			(layers "F.Cu" "F.Mask" "F.Paste")
			(net 59 "/2xRJ45/Ethernet_P1.D1-")
			(pinfunction "P1_A_N")
			(pintype "bidirectional")
		)
		(pad "B26" smd circle
			(at 2.25 -9.085 180)
			(size 0.5 0.5)
			(layers "F.Cu" "F.Mask" "F.Paste")
			(net 62 "/2xRJ45/Ethernet_P1.D2+")
			(pinfunction "P1_B_P")
			(pintype "bidirectional")
		)
		(pad "B28" smd circle
			(at 3.25 -9.085 180)
			(size 0.5 0.5)
			(layers "F.Cu" "F.Mask" "F.Paste")
			(net 65 "/2xRJ45/Ethernet_P1.D3-")
			(pinfunction "P1_C_N")
			(pintype "bidirectional")
		)
		(pad "B30" smd circle
			(at 4.25 -9.085 180)
			(size 0.5 0.5)
			(layers "F.Cu" "F.Mask" "F.Paste")
			(net 67 "/2xRJ45/Ethernet_P1.D4+")
			(pinfunction "P1_D_P")
			(pintype "bidirectional")
		)
		(pad "B32" smd circle
			(at 5.25 -9.085 180)
			(size 0.5 0.5)
			(layers "F.Cu" "F.Mask" "F.Paste")
			(net 28 "GND")
			(pinfunction "AVSS")
			(pintype "passive")
		)
		(pad "B34" smd circle
			(at 6.25 -9.085 180)
			(size 0.5 0.5)
			(layers "F.Cu" "F.Mask" "F.Paste")
			(net 57 "/2xRJ45/Ethernet_P0.D4-")
			(pinfunction "P0_D_N")
			(pintype "bidirectional")
		)
		(pad "B36" smd circle
			(at 7.25 -9.085 180)
			(size 0.5 0.5)
			(layers "F.Cu" "F.Mask" "F.Paste")
			(net 58 "/2xRJ45/Ethernet_P0.D3+")
			(pinfunction "P0_C_P")
			(pintype "bidirectional")
		)
		(pad "B38" smd circle
			(at 8.25 -9.085 180)
			(size 0.5 0.5)
			(layers "F.Cu" "F.Mask" "F.Paste")
			(net 48 "/2xRJ45/Ethernet_P0.D2-")
			(pinfunction "P0_B_N")
			(pintype "bidirectional")
		)
		(pad "B40" smd circle
			(at 9.25 -9.085 180)
			(size 0.5 0.5)
			(layers "F.Cu" "F.Mask" "F.Paste")
			(net 56 "/2xRJ45/Ethernet_P0.D1+")
			(pinfunction "P0_A_P")
			(pintype "bidirectional")
		)
		(pad "B42" smd circle
			(at 10.25 -9.085 180)
			(size 0.5 0.5)
			(layers "F.Cu" "F.Mask" "F.Paste")
			(net 253 "unconnected-(U9G-RSVDB42_NC-PadB42)")
			(pinfunction "RSVDB42_NC")
			(pintype "passive+no_connect")
		)
		(pad "C1" smd circle
			(at -10.25 -8.22 180)
			(size 0.5 0.5)
			(layers "F.Cu" "F.Mask" "F.Paste")
			(net 29 "/X710-AT2 10GbE/25MHZ_OSC.+")
			(pinfunction "REFCLKIN_P")
			(pintype "input")
		)
		(pad "C3" smd circle
			(at -9.25 -8.22 180)
			(size 0.5 0.5)
			(layers "F.Cu" "F.Mask" "F.Paste")
			(net 31 "/X710-AT2 10GbE/25MHZ_OSC.-")
			(pinfunction "REFCLKIN_N")
			(pintype "input")
		)
		(pad "C5" smd circle
			(at -8.25 -8.22 180)
			(size 0.5 0.5)
			(layers "F.Cu" "F.Mask" "F.Paste")
			(net 28 "GND")
			(pinfunction "VSSA")
			(pintype "passive")
		)
		(pad "C7" smd circle
			(at -7.25 -8.22 180)
			(size 0.5 0.5)
			(layers "F.Cu" "F.Mask" "F.Paste")
			(net 28 "GND")
			(pinfunction "VSSA")
			(pintype "passive")
		)
		(pad "C9" smd circle
			(at -6.25 -8.22 180)
			(size 0.5 0.5)
			(layers "F.Cu" "F.Mask" "F.Paste")
			(net 28 "GND")
			(pinfunction "VSSA")
			(pintype "passive")
		)
		(pad "C11" smd circle
			(at -5.25 -8.22 180)
			(size 0.5 0.5)
			(layers "F.Cu" "F.Mask" "F.Paste")
			(net 28 "GND")
			(pinfunction "VSSA")
			(pintype "passive")
		)
		(pad "C13" smd circle
			(at -4.25 -8.22 180)
			(size 0.5 0.5)
			(layers "F.Cu" "F.Mask" "F.Paste")
			(net 28 "GND")
			(pinfunction "VSSA")
			(pintype "passive")
		)
		(pad "C15" smd circle
			(at -3.25 -8.22 180)
			(size 0.5 0.5)
			(layers "F.Cu" "F.Mask" "F.Paste")
			(net 28 "GND")
			(pinfunction "VSSA")
			(pintype "passive")
		)
		(pad "C17" smd circle
			(at -2.25 -8.22 180)
			(size 0.5 0.5)
			(layers "F.Cu" "F.Mask" "F.Paste")
			(net 28 "GND")
			(pinfunction "VSSA")
			(pintype "passive")
		)
		(pad "C19" smd circle
			(at -1.25 -8.22 180)
			(size 0.5 0.5)
			(layers "F.Cu" "F.Mask" "F.Paste")
			(net 28 "GND")
			(pinfunction "VSSA")
			(pintype "passive")
		)
		(pad "C21" smd circle
			(at -0.25 -8.22 180)
			(size 0.5 0.5)
			(layers "F.Cu" "F.Mask" "F.Paste")
			(net 195 "unconnected-(U9G-RSVDC21_NC-PadC21)")
			(pinfunction "RSVDC21_NC")
			(pintype "passive+no_connect")
		)
		(pad "C23" smd circle
			(at 0.75 -8.22 180)
			(size 0.5 0.5)
			(layers "F.Cu" "F.Mask" "F.Paste")
			(net 14 "P1_AVDDL")
			(pinfunction "P1_AVDDL")
			(pintype "power_in")
		)
		(pad "C25" smd circle
			(at 1.75 -8.22 180)
			(size 0.5 0.5)
			(layers "F.Cu" "F.Mask" "F.Paste")
			(net 14 "P1_AVDDL")
			(pinfunction "P1_AVDDL")
			(pintype "passive")
		)
		(pad "C27" smd circle
			(at 2.75 -8.22 180)
			(size 0.5 0.5)
			(layers "F.Cu" "F.Mask" "F.Paste")
			(net 14 "P1_AVDDL")
			(pinfunction "P1_AVDDL")
			(pintype "passive")
		)
		(pad "C29" smd circle
			(at 3.75 -8.22 180)
			(size 0.5 0.5)
			(layers "F.Cu" "F.Mask" "F.Paste")
			(net 14 "P1_AVDDL")
			(pinfunction "P1_AVDDL")
			(pintype "passive")
		)
		(pad "C31" smd circle
			(at 4.75 -8.22 180)
			(size 0.5 0.5)
			(layers "F.Cu" "F.Mask" "F.Paste")
			(net 28 "GND")
			(pinfunction "AVSS")
			(pintype "passive")
		)
		(pad "C33" smd circle
			(at 5.75 -8.22 180)
			(size 0.5 0.5)
			(layers "F.Cu" "F.Mask" "F.Paste")
			(net 5 "P0_AVDDL")
			(pinfunction "P0_AVDDL")
			(pintype "power_in")
		)
		(pad "C35" smd circle
			(at 6.75 -8.22 180)
			(size 0.5 0.5)
			(layers "F.Cu" "F.Mask" "F.Paste")
			(net 5 "P0_AVDDL")
			(pinfunction "P0_AVDDL")
			(pintype "passive")
		)
		(pad "C37" smd circle
			(at 7.75 -8.22 180)
			(size 0.5 0.5)
			(layers "F.Cu" "F.Mask" "F.Paste")
			(net 5 "P0_AVDDL")
			(pinfunction "P0_AVDDL")
			(pintype "passive")
		)
		(pad "C39" smd circle
			(at 8.75 -8.22 180)
			(size 0.5 0.5)
			(layers "F.Cu" "F.Mask" "F.Paste")
			(net 5 "P0_AVDDL")
			(pinfunction "P0_AVDDL")
			(pintype "passive")
		)
		(pad "C41" smd circle
			(at 9.75 -8.22 180)
			(size 0.5 0.5)
			(layers "F.Cu" "F.Mask" "F.Paste")
			(net 28 "GND")
			(pinfunction "AVSS")
			(pintype "passive")
		)
		(pad "D2" smd circle
			(at -9.75 -7.355 180)
			(size 0.5 0.5)
			(layers "F.Cu" "F.Mask" "F.Paste")
			(net 290 "/X710-AT2 Misc/~{DEV_DIS}")
			(pinfunction "~{DEV_DIS}")
			(pintype "tri_state")
		)
		(pad "D4" smd circle
			(at -8.75 -7.355 180)
			(size 0.5 0.5)
			(layers "F.Cu" "F.Mask" "F.Paste")
			(net 383 "/X710-AT2 Misc/REFCLK_SEL")
			(pinfunction "REFCLK_SEL")
			(pintype "input")
		)
		(pad "D6" smd circle
			(at -7.75 -7.355 180)
			(size 0.5 0.5)
			(layers "F.Cu" "F.Mask" "F.Paste")
			(net 28 "GND")
			(pinfunction "RSVDD6_VSS")
			(pintype "passive")
		)
		(pad "D8" smd circle
			(at -6.75 -7.355 180)
			(size 0.5 0.5)
			(layers "F.Cu" "F.Mask" "F.Paste")
			(net 131 "/X710-AT2 RSVD/RSVDD8_1P88V")
			(pinfunction "RSVDD8_1P88V")
			(pintype "passive")
		)
		(pad "D10" smd circle
			(at -5.75 -7.355 180)
			(size 0.5 0.5)
			(layers "F.Cu" "F.Mask" "F.Paste")
			(net 295 "/X710-AT2 Misc/XTAL_BYPASS")
			(pinfunction "XTAL_BYPASS")
			(pintype "passive")
		)
		(pad "D12" smd circle
			(at -4.75 -7.355 180)
			(size 0.5 0.5)
			(layers "F.Cu" "F.Mask" "F.Paste")
			(net 384 "/X710-AT2 Misc/~{PHY_RESET}")
			(pinfunction "~{RESET}")
			(pintype "input")
		)
		(pad "D14" smd circle
			(at -3.75 -7.355 180)
			(size 0.5 0.5)
			(layers "F.Cu" "F.Mask" "F.Paste")
			(net 28 "GND")
			(pinfunction "RSVDD14")
			(pintype "input")
		)
		(pad "D16" smd circle
			(at -2.75 -7.355 180)
			(size 0.5 0.5)
			(layers "F.Cu" "F.Mask" "F.Paste")
			(net 135 "/X710-AT2 Misc/PHY_TMS")
			(pinfunction "PHY_TMS")
			(pintype "input")
		)
		(pad "D18" smd circle
			(at -1.75 -7.355 180)
			(size 0.5 0.5)
			(layers "F.Cu" "F.Mask" "F.Paste")
			(net 116 "/X710-AT2 Misc/~{PHY_TRST}")
			(pinfunction "~{PHY_TRST}")
			(pintype "input")
		)
		(pad "D20" smd circle
			(at -0.75 -7.355 180)
			(size 0.5 0.5)
			(layers "F.Cu" "F.Mask" "F.Paste")
			(net 250 "unconnected-(U9G-RSVDD20_NC-PadD20)")
			(pinfunction "RSVDD20_NC")
			(pintype "passive+no_connect")
		)
		(pad "D22" smd circle
			(at 0.25 -7.355 180)
			(size 0.5 0.5)
			(layers "F.Cu" "F.Mask" "F.Paste")
			(net 28 "GND")
			(pinfunction "RSVDD22_VSS")
			(pintype "passive")
		)
		(pad "D24" smd circle
			(at 1.25 -7.355 180)
			(size 0.5 0.5)
			(layers "F.Cu" "F.Mask" "F.Paste")
			(net 28 "GND")
			(pinfunction "AVSS")
			(pintype "passive")
		)
		(pad "D26" smd circle
			(at 2.25 -7.355 180)
			(size 0.5 0.5)
			(layers "F.Cu" "F.Mask" "F.Paste")
			(net 28 "GND")
			(pinfunction "AVSS")
			(pintype "passive")
		)
		(pad "D28" smd circle
			(at 3.25 -7.355 180)
			(size 0.5 0.5)
			(layers "F.Cu" "F.Mask" "F.Paste")
			(net 28 "GND")
			(pinfunction "AVSS")
			(pintype "passive")
		)
		(pad "D30" smd circle
			(at 4.25 -7.355 180)
			(size 0.5 0.5)
			(layers "F.Cu" "F.Mask" "F.Paste")
			(net 10 "AVDDH")
			(pinfunction "BIAS_AVDDH")
			(pintype "power_in")
		)
		(pad "D32" smd circle
			(at 5.25 -7.355 180)
			(size 0.5 0.5)
			(layers "F.Cu" "F.Mask" "F.Paste")
			(net 259 "unconnected-(U9G-RSVDD32_NC-PadD32)")
			(pinfunction "RSVDD32_NC")
			(pintype "passive+no_connect")
		)
		(pad "D34" smd circle
			(at 6.25 -7.355 180)
			(size 0.5 0.5)
			(layers "F.Cu" "F.Mask" "F.Paste")
			(net 23 "XGB_AVDDH")
			(pinfunction "XGB_AVDDH")
			(pintype "power_in")
		)
		(pad "D36" smd circle
			(at 7.25 -7.355 180)
			(size 0.5 0.5)
			(layers "F.Cu" "F.Mask" "F.Paste")
			(net 28 "GND")
			(pinfunction "AVSS")
			(pintype "passive")
		)
		(pad "D38" smd circle
			(at 8.25 -7.355 180)
			(size 0.5 0.5)
			(layers "F.Cu" "F.Mask" "F.Paste")
			(net 28 "GND")
			(pinfunction "AVSS")
			(pintype "passive")
		)
		(pad "D40" smd circle
			(at 9.25 -7.355 180)
			(size 0.5 0.5)
			(layers "F.Cu" "F.Mask" "F.Paste")
			(net 28 "GND")
			(pinfunction "AVSS")
			(pintype "passive")
		)
		(pad "D42" smd circle
			(at 10.25 -7.355 180)
			(size 0.5 0.5)
			(layers "F.Cu" "F.Mask" "F.Paste")
			(net 153 "/X710-AT2 Misc/50MHZ_XTAL.+")
			(pinfunction "XTAL_P")
			(pintype "input")
		)
		(pad "E1" smd circle
			(at -10.25 -6.49 180)
			(size 0.5 0.5)
			(layers "F.Cu" "F.Mask" "F.Paste")
			(net 100 "/X710-AT2 Misc/AUX_PWR")
			(pinfunction "AUX_PWR")
			(pintype "tri_state")
		)
		(pad "E3" smd circle
			(at -9.25 -6.49 180)
			(size 0.5 0.5)
			(layers "F.Cu" "F.Mask" "F.Paste")
			(net 133 "/X710-AT2 Misc/MAIN_PWR_OK")
			(pinfunction "MAIN_PWR_OK")
			(pintype "input")
		)
		(pad "E5" smd circle
			(at -8.25 -6.49 180)
			(size 0.5 0.5)
			(layers "F.Cu" "F.Mask" "F.Paste")
			(net 141 "/X710-AT2 10GbE/~{PHY_RESET_3V3_R}")
			(pinfunction "SDP0_0")
			(pintype "tri_state")
		)
		(pad "E7" smd circle
			(at -7.25 -6.49 180)
			(size 0.5 0.5)
			(layers "F.Cu" "F.Mask" "F.Paste")
			(net 256 "unconnected-(U9C-SDP2_2-PadE7)")
			(pinfunction "SDP2_2")
			(pintype "passive+no_connect")
		)
		(pad "E9" smd circle
			(at -6.25 -6.49 180)
			(size 0.5 0.5)
			(layers "F.Cu" "F.Mask" "F.Paste")
			(net 260 "unconnected-(U9F-SYNCE_LOCK_1-PadE9)")
			(pinfunction "SYNCE_LOCK_1")
			(pintype "output+no_connect")
		)
		(pad "E11" smd circle
			(at -5.25 -6.49 180)
			(size 0.5 0.5)
			(layers "F.Cu" "F.Mask" "F.Paste")
			(net 185 "unconnected-(U9F-SYNCE_LOCK_2-PadE11)")
			(pinfunction "SYNCE_LOCK_2")
			(pintype "output+no_connect")
		)
		(pad "E13" smd circle
			(at -4.25 -6.49 180)
			(size 0.5 0.5)
			(layers "F.Cu" "F.Mask" "F.Paste")
			(net 209 "unconnected-(U9F-SYNCE_CLKOUT_3-PadE13)")
			(pinfunction "SYNCE_CLKOUT_3")
			(pintype "output+no_connect")
		)
		(pad "E15" smd circle
			(at -3.25 -6.49 180)
			(size 0.5 0.5)
			(layers "F.Cu" "F.Mask" "F.Paste")
			(net 136 "/X710-AT2 Misc/PHY_TDI")
			(pinfunction "PHY_TDI")
			(pintype "input")
		)
		(pad "E17" smd circle
			(at -2.25 -6.49 180)
			(size 0.5 0.5)
			(layers "F.Cu" "F.Mask" "F.Paste")
			(net 134 "/X710-AT2 Misc/PHY_TCK")
			(pinfunction "PHY_TCK")
			(pintype "input")
		)
		(pad "E19" smd circle
			(at -1.25 -6.49 180)
			(size 0.5 0.5)
			(layers "F.Cu" "F.Mask" "F.Paste")
			(net 292 "/X710-AT2 RSVD/RSVDE19_1P88V")
			(pinfunction "RSVDE19_1P88V")
			(pintype "passive")
		)
		(pad "E21" smd circle
			(at -0.25 -6.49 180)
			(size 0.5 0.5)
			(layers "F.Cu" "F.Mask" "F.Paste")
			(net 28 "GND")
			(pinfunction "RSVDE21_VSS")
			(pintype "passive")
		)
		(pad "E23" smd circle
			(at 0.75 -6.49 180)
			(size 0.5 0.5)
			(layers "F.Cu" "F.Mask" "F.Paste")
			(net 28 "GND")
			(pinfunction "RSVDE23_VSS")
			(pintype "passive")
		)
		(pad "E25" smd circle
			(at 1.75 -6.49 180)
			(size 0.5 0.5)
			(layers "F.Cu" "F.Mask" "F.Paste")
			(net 28 "GND")
			(pinfunction "RSVDE25_VSS")
			(pintype "passive")
		)
		(pad "E27" smd circle
			(at 2.75 -6.49 180)
			(size 0.5 0.5)
			(layers "F.Cu" "F.Mask" "F.Paste")
			(net 10 "AVDDH")
			(pinfunction "P1_AVDDH")
			(pintype "power_in")
		)
		(pad "E29" smd circle
			(at 3.75 -6.49 180)
			(size 0.5 0.5)
			(layers "F.Cu" "F.Mask" "F.Paste")
			(net 10 "AVDDH")
			(pinfunction "P1_AVDDH")
			(pintype "passive")
		)
		(pad "E31" smd circle
			(at 4.75 -6.49 180)
			(size 0.5 0.5)
			(layers "F.Cu" "F.Mask" "F.Paste")
			(net 28 "GND")
			(pinfunction "AVSS")
			(pintype "passive")
		)
		(pad "E33" smd circle
			(at 5.75 -6.49 180)
			(size 0.5 0.5)
			(layers "F.Cu" "F.Mask" "F.Paste")
			(net 28 "GND")
			(pinfunction "AVSS")
			(pintype "passive")
		)
		(pad "E35" smd circle
			(at 6.75 -6.49 180)
			(size 0.5 0.5)
			(layers "F.Cu" "F.Mask" "F.Paste")
			(net 10 "AVDDH")
			(pinfunction "P0_AVDDH")
			(pintype "power_in")
		)
		(pad "E37" smd circle
			(at 7.75 -6.49 180)
			(size 0.5 0.5)
			(layers "F.Cu" "F.Mask" "F.Paste")
			(net 10 "AVDDH")
			(pinfunction "P0_AVDDH")
			(pintype "passive")
		)
		(pad "E39" smd circle
			(at 8.75 -6.49 180)
			(size 0.5 0.5)
			(layers "F.Cu" "F.Mask" "F.Paste")
			(net 84 "/X710-AT2 10GbE/BIAS_RDAC")
			(pinfunction "BIAS_RDAC")
			(pintype "passive")
		)
		(pad "E41" smd circle
			(at 9.75 -6.49 180)
			(size 0.5 0.5)
			(layers "F.Cu" "F.Mask" "F.Paste")
			(net 191 "/X710-AT2 Misc/50MHZ_XTAL.-")
			(pinfunction "XTAL_N")
			(pintype "input")
		)
		(pad "F2" smd circle
			(at -9.75 -5.625 180)
			(size 0.5 0.5)
			(layers "F.Cu" "F.Mask" "F.Paste")
			(net 363 "/X710-AT2 Misc/NCSI.TXD_0")
			(pinfunction "NCSI_TXD_0")
			(pintype "input")
		)
		(pad "F4" smd circle
			(at -8.75 -5.625 180)
			(size 0.5 0.5)
			(layers "F.Cu" "F.Mask" "F.Paste")
			(net 159 "Net-(U9D-NCSI_ARB_OUT)")
			(pinfunction "NCSI_ARB_OUT")
			(pintype "output")
		)
		(pad "F6" smd circle
			(at -7.75 -5.625 180)
			(size 0.5 0.5)
			(layers "F.Cu" "F.Mask" "F.Paste")
			(net 211 "unconnected-(U9C-SDP2_0-PadF6)")
			(pinfunction "SDP2_0")
			(pintype "passive+no_connect")
		)
		(pad "F8" smd circle
			(at -6.75 -5.625 180)
			(size 0.5 0.5)
			(layers "F.Cu" "F.Mask" "F.Paste")
			(net 238 "unconnected-(U9F-SYNCE_LOCK_0-PadF8)")
			(pinfunction "SYNCE_LOCK_0")
			(pintype "output+no_connect")
		)
		(pad "F10" smd circle
			(at -5.75 -5.625 180)
			(size 0.5 0.5)
			(layers "F.Cu" "F.Mask" "F.Paste")
			(net 258 "unconnected-(U9F-SYNCE_CLKOUT_1-PadF10)")
			(pinfunction "SYNCE_CLKOUT_1")
			(pintype "output+no_connect")
		)
		(pad "F12" smd circle
			(at -4.75 -5.625 180)
			(size 0.5 0.5)
			(layers "F.Cu" "F.Mask" "F.Paste")
			(net 218 "unconnected-(U9F-SYNCE_LOCK_3-PadF12)")
			(pinfunction "SYNCE_LOCK_3")
			(pintype "output+no_connect")
		)
		(pad "F14" smd circle
			(at -3.75 -5.625 180)
			(size 0.5 0.5)
			(layers "F.Cu" "F.Mask" "F.Paste")
			(net 287 "/X710-AT2 10GbE/~{P1_INT}")
			(pinfunction "P1_INT_MLC")
			(pintype "passive")
		)
		(pad "F16" smd circle
			(at -2.75 -5.625 180)
			(size 0.5 0.5)
			(layers "F.Cu" "F.Mask" "F.Paste")
			(net 137 "/X710-AT2 Misc/PHY_TDO")
			(pinfunction "PHY_TDO")
			(pintype "open_collector")
		)
		(pad "F18" smd circle
			(at -1.75 -5.625 180)
			(size 0.5 0.5)
			(layers "F.Cu" "F.Mask" "F.Paste")
			(net 28 "GND")
			(pinfunction "RSVDF18_VSS")
			(pintype "passive")
		)
		(pad "F20" smd circle
			(at -0.75 -5.625 180)
			(size 0.5 0.5)
			(layers "F.Cu" "F.Mask" "F.Paste")
			(net 28 "GND")
			(pinfunction "RSVDF20_VSS")
			(pintype "passive")
		)
		(pad "F22" smd circle
			(at 0.25 -5.625 180)
			(size 0.5 0.5)
			(layers "F.Cu" "F.Mask" "F.Paste")
			(net 28 "GND")
			(pinfunction "RSVDF22_VSS")
			(pintype "passive")
		)
		(pad "F24" smd circle
			(at 1.25 -5.625 180)
			(size 0.5 0.5)
			(layers "F.Cu" "F.Mask" "F.Paste")
			(net 28 "GND")
			(pinfunction "VSS")
			(pintype "power_in")
		)
		(pad "F26" smd circle
			(at 2.25 -5.625 180)
			(size 0.5 0.5)
			(layers "F.Cu" "F.Mask" "F.Paste")
			(net 28 "GND")
			(pinfunction "VSS")
			(pintype "passive")
		)
		(pad "F28" smd circle
			(at 3.25 -5.625 180)
			(size 0.5 0.5)
			(layers "F.Cu" "F.Mask" "F.Paste")
			(net 28 "GND")
			(pinfunction "VSS")
			(pintype "passive")
		)
		(pad "F30" smd circle
			(at 4.25 -5.625 180)
			(size 0.5 0.5)
			(layers "F.Cu" "F.Mask" "F.Paste")
			(net 28 "GND")
			(pinfunction "VSS")
			(pintype "passive")
		)
		(pad "F32" smd circle
			(at 5.25 -5.625 180)
			(size 0.5 0.5)
			(layers "F.Cu" "F.Mask" "F.Paste")
			(net 28 "GND")
			(pinfunction "VSS")
			(pintype "passive")
		)
		(pad "F34" smd circle
			(at 6.25 -5.625 180)
			(size 0.5 0.5)
			(layers "F.Cu" "F.Mask" "F.Paste")
			(net 28 "GND")
			(pinfunction "VSS")
			(pintype "passive")
		)
		(pad "F36" smd circle
			(at 7.25 -5.625 180)
			(size 0.5 0.5)
			(layers "F.Cu" "F.Mask" "F.Paste")
			(net 28 "GND")
			(pinfunction "VSS")
			(pintype "passive")
		)
		(pad "F38" smd circle
			(at 8.25 -5.625 180)
			(size 0.5 0.5)
			(layers "F.Cu" "F.Mask" "F.Paste")
			(net 28 "GND")
			(pinfunction "RSVDF38_VSS")
			(pintype "passive")
		)
		(pad "F40" smd circle
			(at 9.25 -5.625 180)
			(size 0.5 0.5)
			(layers "F.Cu" "F.Mask" "F.Paste")
			(net 28 "GND")
			(pinfunction "AVSS")
			(pintype "passive")
		)
		(pad "F42" smd circle
			(at 10.25 -5.625 180)
			(size 0.5 0.5)
			(layers "F.Cu" "F.Mask" "F.Paste")
			(net 28 "GND")
			(pinfunction "AVSS")
			(pintype "passive")
		)
		(pad "G1" smd circle
			(at -10.25 -4.76 180)
			(size 0.5 0.5)
			(layers "F.Cu" "F.Mask" "F.Paste")
			(net 361 "/X710-AT2 Misc/NCSI.TXD_1")
			(pinfunction "NCSI_TXD_1")
			(pintype "input")
		)
		(pad "G3" smd circle
			(at -9.25 -4.76 180)
			(size 0.5 0.5)
			(layers "F.Cu" "F.Mask" "F.Paste")
			(net 368 "/X710-AT2 Misc/NCSI.ARB_IN")
			(pinfunction "NCSI_ARB_IN")
			(pintype "input")
		)
		(pad "G5" smd circle
			(at -8.25 -4.76 180)
			(size 0.5 0.5)
			(layers "F.Cu" "F.Mask" "F.Paste")
			(net 198 "/X710-AT2 10GbE/~{P0_INT_R}")
			(pinfunction "SDP0_1")
			(pintype "tri_state")
		)
		(pad "G7" smd circle
			(at -7.25 -4.76 180)
			(size 0.5 0.5)
			(layers "F.Cu" "F.Mask" "F.Paste")
			(net 371 "unconnected-(U9C-SDP2_3-PadG7)")
			(pinfunction "SDP2_3")
			(pintype "passive+no_connect")
		)
		(pad "G9" smd circle
			(at -6.25 -4.76 180)
			(size 0.5 0.5)
			(layers "F.Cu" "F.Mask" "F.Paste")
			(net 207 "unconnected-(U9F-SYNCE_CLKOUT_0-PadG9)")
			(pinfunction "SYNCE_CLKOUT_0")
			(pintype "output+no_connect")
		)
		(pad "G11" smd circle
			(at -5.25 -4.76 180)
			(size 0.5 0.5)
			(layers "F.Cu" "F.Mask" "F.Paste")
			(net 254 "unconnected-(U9F-SYNCE_CLKOUT_2-PadG11)")
			(pinfunction "SYNCE_CLKOUT_2")
			(pintype "output+no_connect")
		)
		(pad "G13" smd circle
			(at -4.25 -4.76 180)
			(size 0.5 0.5)
			(layers "F.Cu" "F.Mask" "F.Paste")
			(net 223 "unconnected-(U9F-RSVDG13_NC-PadG13)")
			(pinfunction "RSVDG13_NC")
			(pintype "passive+no_connect")
		)
		(pad "G15" smd circle
			(at -3.25 -4.76 180)
			(size 0.5 0.5)
			(layers "F.Cu" "F.Mask" "F.Paste")
			(net 224 "unconnected-(U9F-RSVDG15_NC-PadG15)")
			(pinfunction "RSVDG15_NC")
			(pintype "passive+no_connect")
		)
		(pad "G17" smd circle
			(at -2.25 -4.76 180)
			(size 0.5 0.5)
			(layers "F.Cu" "F.Mask" "F.Paste")
			(net 294 "/X710-AT2 10GbE/TPIN_5")
			(pinfunction "TPIN_5")
			(pintype "passive")
		)
		(pad "G19" smd circle
			(at -1.25 -4.76 180)
			(size 0.5 0.5)
			(layers "F.Cu" "F.Mask" "F.Paste")
			(net 28 "GND")
			(pinfunction "RSVDG19_VSS")
			(pintype "passive")
		)
		(pad "G21" smd circle
			(at -0.25 -4.76 180)
			(size 0.5 0.5)
			(layers "F.Cu" "F.Mask" "F.Paste")
			(net 28 "GND")
			(pinfunction "RSVDG21_VSS")
			(pintype "passive")
		)
		(pad "G23" smd circle
			(at 0.75 -4.76 180)
			(size 0.5 0.5)
			(layers "F.Cu" "F.Mask" "F.Paste")
			(net 28 "GND")
			(pinfunction "RSVDG23_VSS")
			(pintype "passive")
		)
		(pad "G25" smd circle
			(at 1.75 -4.76 180)
			(size 0.5 0.5)
			(layers "F.Cu" "F.Mask" "F.Paste")
			(net 18 "+1V88")
			(pinfunction "VDDIO1")
			(pintype "power_in")
		)
		(pad "G27" smd circle
			(at 2.75 -4.76 180)
			(size 0.5 0.5)
			(layers "F.Cu" "F.Mask" "F.Paste")
			(net 6 "DVDD")
			(pinfunction "DVDD")
			(pintype "power_in")
		)
		(pad "G29" smd circle
			(at 3.75 -4.76 180)
			(size 0.5 0.5)
			(layers "F.Cu" "F.Mask" "F.Paste")
			(net 6 "DVDD")
			(pinfunction "DVDD")
			(pintype "passive")
		)
		(pad "G31" smd circle
			(at 4.75 -4.76 180)
			(size 0.5 0.5)
			(layers "F.Cu" "F.Mask" "F.Paste")
			(net 6 "DVDD")
			(pinfunction "DVDD")
			(pintype "passive")
		)
		(pad "G33" smd circle
			(at 5.75 -4.76 180)
			(size 0.5 0.5)
			(layers "F.Cu" "F.Mask" "F.Paste")
			(net 6 "DVDD")
			(pinfunction "DVDD")
			(pintype "passive")
		)
		(pad "G35" smd circle
			(at 6.75 -4.76 180)
			(size 0.5 0.5)
			(layers "F.Cu" "F.Mask" "F.Paste")
			(net 6 "DVDD")
			(pinfunction "DVDD")
			(pintype "passive")
		)
		(pad "G37" smd circle
			(at 7.75 -4.76 180)
			(size 0.5 0.5)
			(layers "F.Cu" "F.Mask" "F.Paste")
			(net 18 "+1V88")
			(pinfunction "VDDIO1")
			(pintype "passive")
		)
		(pad "G39" smd circle
			(at 8.75 -4.76 180)
			(size 0.5 0.5)
			(layers "F.Cu" "F.Mask" "F.Paste")
			(net 27 "PLL_VDD")
			(pinfunction "PLL_VDD")
			(pintype "power_in")
		)
		(pad "G41" smd circle
			(at 9.75 -4.76 180)
			(size 0.5 0.5)
			(layers "F.Cu" "F.Mask" "F.Paste")
			(net 28 "GND")
			(pinfunction "AVSS")
			(pintype "passive")
		)
		(pad "H2" smd circle
			(at -9.75 -3.895 180)
			(size 0.5 0.5)
			(layers "F.Cu" "F.Mask" "F.Paste")
			(net 367 "/X710-AT2 Misc/NCSI.REF_CLK")
			(pinfunction "NCSI_CLK_IN")
			(pintype "input")
		)
		(pad "H4" smd circle
			(at -8.75 -3.895 180)
			(size 0.5 0.5)
			(layers "F.Cu" "F.Mask" "F.Paste")
			(net 366 "/X710-AT2 Misc/NCSI.TX_EN")
			(pinfunction "NCSI_TX_EN")
			(pintype "input")
		)
		(pad "H6" smd circle
			(at -7.75 -3.895 180)
			(size 0.5 0.5)
			(layers "F.Cu" "F.Mask" "F.Paste")
			(net 296 "unconnected-(U9C-SDP1_3-PadH6)")
			(pinfunction "SDP1_3")
			(pintype "passive+no_connect")
		)
		(pad "H8" smd circle
			(at -6.75 -3.895 180)
			(size 0.5 0.5)
			(layers "F.Cu" "F.Mask" "F.Paste")
			(net 212 "unconnected-(U9D-GPIO_4-PadH8)")
			(pinfunction "GPIO_4")
			(pintype "passive+no_connect")
		)
		(pad "H10" smd circle
			(at -5.75 -3.895 180)
			(size 0.5 0.5)
			(layers "F.Cu" "F.Mask" "F.Paste")
			(net 189 "unconnected-(U9F-P1_PTP_SYNC0-PadH10)")
			(pinfunction "P1_PTP_SYNC0")
			(pintype "passive+no_connect")
		)
		(pad "H12" smd circle
			(at -4.75 -3.895 180)
			(size 0.5 0.5)
			(layers "F.Cu" "F.Mask" "F.Paste")
			(net 345 "unconnected-(U9F-P1_PTP_SYNC1-PadH12)")
			(pinfunction "P1_PTP_SYNC1")
			(pintype "passive+no_connect")
		)
		(pad "H14" smd circle
			(at -3.75 -3.895 180)
			(size 0.5 0.5)
			(layers "F.Cu" "F.Mask" "F.Paste")
			(net 227 "unconnected-(U9F-RSVDH14_NC-PadH14)")
			(pinfunction "RSVDH14_NC")
			(pintype "passive+no_connect")
		)
		(pad "H16" smd circle
			(at -2.75 -3.895 180)
			(size 0.5 0.5)
			(layers "F.Cu" "F.Mask" "F.Paste")
			(net 242 "unconnected-(U9F-RSVDH16_NC-PadH16)")
			(pinfunction "RSVDH16_NC")
			(pintype "passive+no_connect")
		)
		(pad "H18" smd circle
			(at -1.75 -3.895 180)
			(size 0.5 0.5)
			(layers "F.Cu" "F.Mask" "F.Paste")
			(net 28 "GND")
			(pinfunction "RSVH18_VSS")
			(pintype "passive")
		)
		(pad "H20" smd circle
			(at -0.75 -3.895 180)
			(size 0.5 0.5)
			(layers "F.Cu" "F.Mask" "F.Paste")
			(net 293 "/X710-AT2 10GbE/TPIN_3")
			(pinfunction "TPIN_3")
			(pintype "passive")
		)
		(pad "H22" smd circle
			(at 0.25 -3.895 180)
			(size 0.5 0.5)
			(layers "F.Cu" "F.Mask" "F.Paste")
			(net 28 "GND")
			(pinfunction "RSVDH22_VSS")
			(pintype "passive")
		)
		(pad "H24" smd circle
			(at 1.25 -3.895 180)
			(size 0.5 0.5)
			(layers "F.Cu" "F.Mask" "F.Paste")
			(net 28 "GND")
			(pinfunction "RSVDH24_VSS")
			(pintype "passive")
		)
		(pad "H26" smd circle
			(at 2.25 -3.895 180)
			(size 0.5 0.5)
			(layers "F.Cu" "F.Mask" "F.Paste")
			(net 28 "GND")
			(pinfunction "VSSA")
			(pintype "passive")
		)
		(pad "H28" smd circle
			(at 3.25 -3.895 180)
			(size 0.5 0.5)
			(layers "F.Cu" "F.Mask" "F.Paste")
			(net 28 "GND")
			(pinfunction "VSSA")
			(pintype "passive")
		)
		(pad "H30" smd circle
			(at 4.25 -3.895 180)
			(size 0.5 0.5)
			(layers "F.Cu" "F.Mask" "F.Paste")
			(net 28 "GND")
			(pinfunction "VSSA")
			(pintype "passive")
		)
		(pad "H32" smd circle
			(at 5.25 -3.895 180)
			(size 0.5 0.5)
			(layers "F.Cu" "F.Mask" "F.Paste")
			(net 28 "GND")
			(pinfunction "VSSA")
			(pintype "passive")
		)
		(pad "H34" smd circle
			(at 6.25 -3.895 180)
			(size 0.5 0.5)
			(layers "F.Cu" "F.Mask" "F.Paste")
			(net 28 "GND")
			(pinfunction "VSSA")
			(pintype "passive")
		)
		(pad "H36" smd circle
			(at 7.25 -3.895 180)
			(size 0.5 0.5)
			(layers "F.Cu" "F.Mask" "F.Paste")
			(net 28 "GND")
			(pinfunction "VSSA")
			(pintype "passive")
		)
		(pad "H38" smd circle
			(at 8.25 -3.895 180)
			(size 0.5 0.5)
			(layers "F.Cu" "F.Mask" "F.Paste")
			(net 28 "GND")
			(pinfunction "VSSA")
			(pintype "passive")
		)
		(pad "H40" smd circle
			(at 9.25 -3.895 180)
			(size 0.5 0.5)
			(layers "F.Cu" "F.Mask" "F.Paste")
			(net 28 "GND")
			(pinfunction "RSVDH40_VSS")
			(pintype "passive")
		)
		(pad "H42" smd circle
			(at 10.25 -3.895 180)
			(size 0.5 0.5)
			(layers "F.Cu" "F.Mask" "F.Paste")
			(net 346 "unconnected-(U9F-XTAL_PTP_XTAL_N-PadH42)")
			(pinfunction "XTAL_PTP_XTAL_N")
			(pintype "passive+no_connect")
		)
		(pad "J1" smd circle
			(at -10.25 -3.03 180)
			(size 0.5 0.5)
			(layers "F.Cu" "F.Mask" "F.Paste")
			(net 161 "Net-(U9D-NCSI_RXD_0)")
			(pinfunction "NCSI_RXD_0")
			(pintype "output")
		)
		(pad "J3" smd circle
			(at -9.25 -3.03 180)
			(size 0.5 0.5)
			(layers "F.Cu" "F.Mask" "F.Paste")
			(net 162 "Net-(U9D-NCSI_RXD_1)")
			(pinfunction "NCSI_RXD_1")
			(pintype "output")
		)
		(pad "J5" smd circle
			(at -8.25 -3.03 180)
			(size 0.5 0.5)
			(layers "F.Cu" "F.Mask" "F.Paste")
			(net 160 "Net-(U9D-NCSI_CRS_DV)")
			(pinfunction "NCSI_CRS_DV")
			(pintype "output")
		)
		(pad "J7" smd circle
			(at -7.25 -3.03 180)
			(size 0.5 0.5)
			(layers "F.Cu" "F.Mask" "F.Paste")
			(net 174 "unconnected-(U9C-SDP2_1-PadJ7)")
			(pinfunction "SDP2_1")
			(pintype "passive+no_connect")
		)
		(pad "J9" smd circle
			(at -6.25 -3.03 180)
			(size 0.5 0.5)
			(layers "F.Cu" "F.Mask" "F.Paste")
			(net 85 "/X710-AT2 10GbE/OSC_SEL")
			(pinfunction "OSC_SEL")
			(pintype "tri_state")
		)
		(pad "J11" smd circle
			(at -5.25 -3.03 180)
			(size 0.5 0.5)
			(layers "F.Cu" "F.Mask" "F.Paste")
			(net 115 "/X710-AT2 Misc/RSVD_J11_VSS")
			(pinfunction "RSVD_J11_VSS")
			(pintype "passive")
		)
		(pad "J13" smd circle
			(at -4.25 -3.03 180)
			(size 0.5 0.5)
			(layers "F.Cu" "F.Mask" "F.Paste")
			(net 28 "GND")
			(pinfunction "RSVDJ13_VSS")
			(pintype "passive")
		)
		(pad "J15" smd circle
			(at -3.25 -3.03 180)
			(size 0.5 0.5)
			(layers "F.Cu" "F.Mask" "F.Paste")
			(net 249 "unconnected-(U9F-RSVDJ15_NC-PadJ15)")
			(pinfunction "RSVDJ15_NC")
			(pintype "passive+no_connect")
		)
		(pad "J17" smd circle
			(at -2.25 -3.03 180)
			(size 0.5 0.5)
			(layers "F.Cu" "F.Mask" "F.Paste")
			(net 28 "GND")
			(pinfunction "RSVDJ17_VSS")
			(pintype "passive")
		)
		(pad "J19" smd circle
			(at -1.25 -3.03 180)
			(size 0.5 0.5)
			(layers "F.Cu" "F.Mask" "F.Paste")
			(net 28 "GND")
			(pinfunction "RSVDJ19_VSS")
			(pintype "passive")
		)
		(pad "J21" smd circle
			(at -0.25 -3.03 180)
			(size 0.5 0.5)
			(layers "F.Cu" "F.Mask" "F.Paste")
			(net 28 "GND")
			(pinfunction "RSVDJ21_VSS")
			(pintype "passive")
		)
		(pad "J23" smd circle
			(at 0.75 -3.03 180)
			(size 0.5 0.5)
			(layers "F.Cu" "F.Mask" "F.Paste")
			(net 239 "unconnected-(U9E-RSVDJ23_NC-PadJ23)")
			(pinfunction "RSVDJ23_NC")
			(pintype "passive+no_connect")
		)
		(pad "J25" smd circle
			(at 1.75 -3.03 180)
			(size 0.5 0.5)
			(layers "F.Cu" "F.Mask" "F.Paste")
			(net 236 "unconnected-(U9E-RSVDJ25_NC-PadJ25)")
			(pinfunction "RSVDJ25_NC")
			(pintype "passive+no_connect")
		)
		(pad "J27" smd circle
			(at 2.75 -3.03 180)
			(size 0.5 0.5)
			(layers "F.Cu" "F.Mask" "F.Paste")
			(net 12 "XFI_VDD")
			(pinfunction "XFI_VDD")
			(pintype "power_in")
		)
		(pad "J29" smd circle
			(at 3.75 -3.03 180)
			(size 0.5 0.5)
			(layers "F.Cu" "F.Mask" "F.Paste")
			(net 12 "XFI_VDD")
			(pinfunction "XFI_VDD")
			(pintype "passive")
		)
		(pad "J31" smd circle
			(at 4.75 -3.03 180)
			(size 0.5 0.5)
			(layers "F.Cu" "F.Mask" "F.Paste")
			(net 12 "XFI_VDD")
			(pinfunction "XFI_VDD")
			(pintype "passive")
		)
		(pad "J33" smd circle
			(at 5.75 -3.03 180)
			(size 0.5 0.5)
			(layers "F.Cu" "F.Mask" "F.Paste")
			(net 24 "XFI_PVDD")
			(pinfunction "XFI_PVDD")
			(pintype "power_in")
		)
		(pad "J35" smd circle
			(at 6.75 -3.03 180)
			(size 0.5 0.5)
			(layers "F.Cu" "F.Mask" "F.Paste")
			(net 12 "XFI_VDD")
			(pinfunction "XFI_VDD")
			(pintype "passive")
		)
		(pad "J37" smd circle
			(at 7.75 -3.03 180)
			(size 0.5 0.5)
			(layers "F.Cu" "F.Mask" "F.Paste")
			(net 83 "/X710-AT2 10GbE/RESCAL_RES_P")
			(pinfunction "RESCAL_RES_P")
			(pintype "passive")
		)
		(pad "J39" smd circle
			(at 8.75 -3.03 180)
			(size 0.5 0.5)
			(layers "F.Cu" "F.Mask" "F.Paste")
			(net 234 "unconnected-(U9G-RSVDJ39_NC-PadJ39)")
			(pinfunction "RSVDJ39_NC")
			(pintype "passive+no_connect")
		)
		(pad "J41" smd circle
			(at 9.75 -3.03 180)
			(size 0.5 0.5)
			(layers "F.Cu" "F.Mask" "F.Paste")
			(net 177 "unconnected-(U9F-XTAL_PTP_XTAL_P-PadJ41)")
			(pinfunction "XTAL_PTP_XTAL_P")
			(pintype "passive+no_connect")
		)
		(pad "K2" smd circle
			(at -9.75 -2.165 180)
			(size 0.5 0.5)
			(layers "F.Cu" "F.Mask" "F.Paste")
			(net 95 "/X710-AT2 10GbE/MDIO3_SDA3")
			(pinfunction "MDIO3_SDA3")
			(pintype "passive")
		)
		(pad "K4" smd circle
			(at -8.75 -2.165 180)
			(size 0.5 0.5)
			(layers "F.Cu" "F.Mask" "F.Paste")
			(net 94 "/X710-AT2 10GbE/MDC3_SCL3")
			(pinfunction "MDC3_SCL3")
			(pintype "passive")
		)
		(pad "K6" smd circle
			(at -7.75 -2.165 180)
			(size 0.5 0.5)
			(layers "F.Cu" "F.Mask" "F.Paste")
			(net 286 "/X710-AT2 10GbE/~{P1_INT_R}")
			(pinfunction "SDP0_2")
			(pintype "tri_state")
		)
		(pad "K8" smd circle
			(at -6.75 -2.165 180)
			(size 0.5 0.5)
			(layers "F.Cu" "F.Mask" "F.Paste")
			(net 28 "GND")
			(pinfunction "VSSA")
			(pintype "passive")
		)
		(pad "K10" smd circle
			(at -5.75 -2.165 180)
			(size 0.5 0.5)
			(layers "F.Cu" "F.Mask" "F.Paste")
			(net 28 "GND")
			(pinfunction "VSSA")
			(pintype "passive")
		)
		(pad "K12" smd circle
			(at -4.75 -2.165 180)
			(size 0.5 0.5)
			(layers "F.Cu" "F.Mask" "F.Paste")
			(net 28 "GND")
			(pinfunction "VSSA")
			(pintype "passive")
		)
		(pad "K14" smd circle
			(at -3.75 -2.165 180)
			(size 0.5 0.5)
			(layers "F.Cu" "F.Mask" "F.Paste")
			(net 28 "GND")
			(pinfunction "VSSA")
			(pintype "passive")
		)
		(pad "K16" smd circle
			(at -2.75 -2.165 180)
			(size 0.5 0.5)
			(layers "F.Cu" "F.Mask" "F.Paste")
			(net 28 "GND")
			(pinfunction "VSSA")
			(pintype "passive")
		)
		(pad "K18" smd circle
			(at -1.75 -2.165 180)
			(size 0.5 0.5)
			(layers "F.Cu" "F.Mask" "F.Paste")
			(net 28 "GND")
			(pinfunction "VSS")
			(pintype "passive")
		)
		(pad "K20" smd circle
			(at -0.75 -2.165 180)
			(size 0.5 0.5)
			(layers "F.Cu" "F.Mask" "F.Paste")
			(net 28 "GND")
			(pinfunction "VSS")
			(pintype "passive")
		)
		(pad "K22" smd circle
			(at 0.25 -2.165 180)
			(size 0.5 0.5)
			(layers "F.Cu" "F.Mask" "F.Paste")
			(net 313 "unconnected-(U9E-RSVDK22_NC-PadK22)")
			(pinfunction "RSVDK22_NC")
			(pintype "passive+no_connect")
		)
		(pad "K24" smd circle
			(at 1.25 -2.165 180)
			(size 0.5 0.5)
			(layers "F.Cu" "F.Mask" "F.Paste")
			(net 188 "unconnected-(U9E-RSVDK24_NC-PadK24)")
			(pinfunction "RSVDK24_NC")
			(pintype "passive+no_connect")
		)
		(pad "K26" smd circle
			(at 2.25 -2.165 180)
			(size 0.5 0.5)
			(layers "F.Cu" "F.Mask" "F.Paste")
			(net 305 "unconnected-(U9G-RSVDK26_NC-PadK26)")
			(pinfunction "RSVDK26_NC")
			(pintype "passive+no_connect")
		)
		(pad "K28" smd circle
			(at 3.25 -2.165 180)
			(size 0.5 0.5)
			(layers "F.Cu" "F.Mask" "F.Paste")
			(net 246 "unconnected-(U9G-RSVDK28_NC-PadK28)")
			(pinfunction "RSVDK28_NC")
			(pintype "passive+no_connect")
		)
		(pad "K30" smd circle
			(at 4.25 -2.165 180)
			(size 0.5 0.5)
			(layers "F.Cu" "F.Mask" "F.Paste")
			(net 230 "unconnected-(U9F-RSVDK30_NC-PadK30)")
			(pinfunction "RSVDK30_NC")
			(pintype "passive+no_connect")
		)
		(pad "K32" smd circle
			(at 5.25 -2.165 180)
			(size 0.5 0.5)
			(layers "F.Cu" "F.Mask" "F.Paste")
			(net 343 "unconnected-(U9F-RSVDK32_NC-PadK32)")
			(pinfunction "RSVDK32_NC")
			(pintype "passive+no_connect")
		)
		(pad "K34" smd circle
			(at 6.25 -2.165 180)
			(size 0.5 0.5)
			(layers "F.Cu" "F.Mask" "F.Paste")
			(net 200 "unconnected-(U9G-RSVDK34_NC-PadK34)")
			(pinfunction "RSVDK34_NC")
			(pintype "passive+no_connect")
		)
		(pad "K36" smd circle
			(at 7.25 -2.165 180)
			(size 0.5 0.5)
			(layers "F.Cu" "F.Mask" "F.Paste")
			(net 352 "unconnected-(U9G-RSVDK36_NC-PadK36)")
			(pinfunction "RSVDK36_NC")
			(pintype "passive+no_connect")
		)
		(pad "K38" smd circle
			(at 8.25 -2.165 180)
			(size 0.5 0.5)
			(layers "F.Cu" "F.Mask" "F.Paste")
			(net 28 "GND")
			(pinfunction "VSSA")
			(pintype "passive")
		)
		(pad "K40" smd circle
			(at 9.25 -2.165 180)
			(size 0.5 0.5)
			(layers "F.Cu" "F.Mask" "F.Paste")
			(net 113 "/X710-AT2 Misc/RSVDK40_1P88V")
			(pinfunction "RSVDK40_1P88V")
			(pintype "passive")
		)
		(pad "K42" smd circle
			(at 10.25 -2.165 180)
			(size 0.5 0.5)
			(layers "F.Cu" "F.Mask" "F.Paste")
			(net 28 "GND")
			(pinfunction "RSVDK42_VSS")
			(pintype "passive")
		)
		(pad "L1" smd circle
			(at -10.25 -1.3 180)
			(size 0.5 0.5)
			(layers "F.Cu" "F.Mask" "F.Paste")
			(net 101 "/X710-AT2 10GbE/MDIO2_SDA2")
			(pinfunction "MDIO2_SDA2")
			(pintype "passive")
		)
		(pad "L3" smd circle
			(at -9.25 -1.3 180)
			(size 0.5 0.5)
			(layers "F.Cu" "F.Mask" "F.Paste")
			(net 96 "/X710-AT2 10GbE/MDC2_SCL2")
			(pinfunction "MDC2_SCL2")
			(pintype "passive")
		)
		(pad "L5" smd circle
			(at -8.25 -1.3 180)
			(size 0.5 0.5)
			(layers "F.Cu" "F.Mask" "F.Paste")
			(net 213 "unconnected-(U9C-SDP0_3-PadL5)")
			(pinfunction "SDP0_3")
			(pintype "passive+no_connect")
		)
		(pad "L7" smd circle
			(at -7.25 -1.3 180)
			(size 0.5 0.5)
			(layers "F.Cu" "F.Mask" "F.Paste")
			(net 108 "/X710-AT2 Misc/GPIO5_POR_BYPASS")
			(pinfunction "GPIO_5")
			(pintype "tri_state")
		)
		(pad "L9" smd circle
			(at -6.25 -1.3 180)
			(size 0.5 0.5)
			(layers "F.Cu" "F.Mask" "F.Paste")
			(net 7 "+3V3")
			(pinfunction "VCC3P3_TX")
			(pintype "power_in")
		)
		(pad "L11" smd circle
			(at -5.25 -1.3 180)
			(size 0.5 0.5)
			(layers "F.Cu" "F.Mask" "F.Paste")
			(net 1 "VCCA")
			(pinfunction "VCCA")
			(pintype "power_in")
		)
		(pad "L13" smd circle
			(at -4.25 -1.3 180)
			(size 0.5 0.5)
			(layers "F.Cu" "F.Mask" "F.Paste")
			(net 1 "VCCA")
			(pinfunction "VCCA")
			(pintype "passive")
		)
		(pad "L15" smd circle
			(at -3.25 -1.3 180)
			(size 0.5 0.5)
			(layers "F.Cu" "F.Mask" "F.Paste")
			(net 1 "VCCA")
			(pinfunction "VCCA")
			(pintype "passive")
		)
		(pad "L17" smd circle
			(at -2.25 -1.3 180)
			(size 0.5 0.5)
			(layers "F.Cu" "F.Mask" "F.Paste")
			(net 1 "VCCA")
			(pinfunction "VCCA")
			(pintype "passive")
		)
		(pad "L19" smd circle
			(at -1.25 -1.3 180)
			(size 0.5 0.5)
			(layers "F.Cu" "F.Mask" "F.Paste")
			(net 9 "VCCD")
			(pinfunction "VCCD")
			(pintype "power_in")
		)
		(pad "L21" smd circle
			(at -0.25 -1.3 180)
			(size 0.5 0.5)
			(layers "F.Cu" "F.Mask" "F.Paste")
			(net 9 "VCCD")
			(pinfunction "VCCD")
			(pintype "passive")
		)
		(pad "L23" smd circle
			(at 0.75 -1.3 180)
			(size 0.5 0.5)
			(layers "F.Cu" "F.Mask" "F.Paste")
			(net 205 "unconnected-(U9E-RSVDL23_NC-PadL23)")
			(pinfunction "RSVDL23_NC")
			(pintype "passive+no_connect")
		)
		(pad "L25" smd circle
			(at 1.75 -1.3 180)
			(size 0.5 0.5)
			(layers "F.Cu" "F.Mask" "F.Paste")
			(net 221 "unconnected-(U9E-RSVDL25_NC-PadL25)")
			(pinfunction "RSVDL25_NC")
			(pintype "passive+no_connect")
		)
		(pad "L27" smd circle
			(at 2.75 -1.3 180)
			(size 0.5 0.5)
			(layers "F.Cu" "F.Mask" "F.Paste")
			(net 281 "unconnected-(U9E-RSVDL27_NC-PadL27)")
			(pinfunction "RSVDL27_NC")
			(pintype "passive+no_connect")
		)
		(pad "L29" smd circle
			(at 3.75 -1.3 180)
			(size 0.5 0.5)
			(layers "F.Cu" "F.Mask" "F.Paste")
			(net 169 "unconnected-(U9G-RSVDL29_NC-PadL29)")
			(pinfunction "RSVDL29_NC")
			(pintype "passive+no_connect")
		)
		(pad "L31" smd circle
			(at 4.75 -1.3 180)
			(size 0.5 0.5)
			(layers "F.Cu" "F.Mask" "F.Paste")
			(net 28 "GND")
			(pinfunction "RSVDL31_VSS")
			(pintype "passive")
		)
		(pad "L33" smd circle
			(at 5.75 -1.3 180)
			(size 0.5 0.5)
			(layers "F.Cu" "F.Mask" "F.Paste")
			(net 112 "/X710-AT2 Misc/RSVDL33")
			(pinfunction "RSVDL33")
			(pintype "passive")
		)
		(pad "L35" smd circle
			(at 6.75 -1.3 180)
			(size 0.5 0.5)
			(layers "F.Cu" "F.Mask" "F.Paste")
			(net 168 "unconnected-(U9F-RSVDL35_NC-PadL35)")
			(pinfunction "RSVDL35_NC")
			(pintype "passive+no_connect")
		)
		(pad "L37" smd circle
			(at 7.75 -1.3 180)
			(size 0.5 0.5)
			(layers "F.Cu" "F.Mask" "F.Paste")
			(net 28 "GND")
			(pinfunction "RSVDL37_VSS")
			(pintype "passive")
		)
		(pad "L39" smd circle
			(at 8.75 -1.3 180)
			(size 0.5 0.5)
			(layers "F.Cu" "F.Mask" "F.Paste")
			(net 18 "+1V88")
			(pinfunction "VDDIO2")
			(pintype "power_in")
		)
		(pad "L41" smd circle
			(at 9.75 -1.3 180)
			(size 0.5 0.5)
			(layers "F.Cu" "F.Mask" "F.Paste")
			(net 382 "/X710-AT2 Misc/MDIO.MDC")
			(pinfunction "MDC")
			(pintype "input")
		)
		(pad "M2" smd circle
			(at -9.75 -0.435 180)
			(size 0.5 0.5)
			(layers "F.Cu" "F.Mask" "F.Paste")
			(net 103 "/X710-AT2 10GbE/MDIO1_SDA1")
			(pinfunction "MDIO1_SDA1")
			(pintype "passive")
		)
		(pad "M4" smd circle
			(at -8.75 -0.435 180)
			(size 0.5 0.5)
			(layers "F.Cu" "F.Mask" "F.Paste")
			(net 102 "/X710-AT2 10GbE/MDC1_SCL1")
			(pinfunction "MDC1_SCL1")
			(pintype "passive")
		)
		(pad "M6" smd circle
			(at -7.75 -0.435 180)
			(size 0.5 0.5)
			(layers "F.Cu" "F.Mask" "F.Paste")
			(net 176 "unconnected-(U9C-SDP3_2-PadM6)")
			(pinfunction "SDP3_2")
			(pintype "passive+no_connect")
		)
		(pad "M8" smd circle
			(at -6.75 -0.435 180)
			(size 0.5 0.5)
			(layers "F.Cu" "F.Mask" "F.Paste")
			(net 199 "unconnected-(U9C-SDP3_3-PadM8)")
			(pinfunction "SDP3_3")
			(pintype "passive+no_connect")
		)
		(pad "M10" smd circle
			(at -5.75 -0.435 180)
			(size 0.5 0.5)
			(layers "F.Cu" "F.Mask" "F.Paste")
			(net 28 "GND")
			(pinfunction "VSSA")
			(pintype "passive")
		)
		(pad "M12" smd circle
			(at -4.75 -0.435 180)
			(size 0.5 0.5)
			(layers "F.Cu" "F.Mask" "F.Paste")
			(net 28 "GND")
			(pinfunction "VSSA")
			(pintype "passive")
		)
		(pad "M14" smd circle
			(at -3.75 -0.435 180)
			(size 0.5 0.5)
			(layers "F.Cu" "F.Mask" "F.Paste")
			(net 28 "GND")
			(pinfunction "VSSA")
			(pintype "passive")
		)
		(pad "M16" smd circle
			(at -2.75 -0.435 180)
			(size 0.5 0.5)
			(layers "F.Cu" "F.Mask" "F.Paste")
			(net 28 "GND")
			(pinfunction "VSSA")
			(pintype "passive")
		)
		(pad "M18" smd circle
			(at -1.75 -0.435 180)
			(size 0.5 0.5)
			(layers "F.Cu" "F.Mask" "F.Paste")
			(net 28 "GND")
			(pinfunction "VSS")
			(pintype "passive")
		)
		(pad "M20" smd circle
			(at -0.75 -0.435 180)
			(size 0.5 0.5)
			(layers "F.Cu" "F.Mask" "F.Paste")
			(net 28 "GND")
			(pinfunction "VSS")
			(pintype "passive")
		)
		(pad "M22" smd circle
			(at 0.25 -0.435 180)
			(size 0.5 0.5)
			(layers "F.Cu" "F.Mask" "F.Paste")
			(net 264 "unconnected-(U9E-RSVDM22_NC-PadM22)")
			(pinfunction "RSVDM22_NC")
			(pintype "passive+no_connect")
		)
		(pad "M24" smd circle
			(at 1.25 -0.435 180)
			(size 0.5 0.5)
			(layers "F.Cu" "F.Mask" "F.Paste")
			(net 279 "unconnected-(U9E-RSVDM24_NC-PadM24)")
			(pinfunction "RSVDM24_NC")
			(pintype "passive+no_connect")
		)
		(pad "M26" smd circle
			(at 2.25 -0.435 180)
			(size 0.5 0.5)
			(layers "F.Cu" "F.Mask" "F.Paste")
			(net 229 "unconnected-(U9E-RSVDM26_NC-PadM26)")
			(pinfunction "RSVDM26_NC")
			(pintype "passive+no_connect")
		)
		(pad "M28" smd circle
			(at 3.25 -0.435 180)
			(size 0.5 0.5)
			(layers "F.Cu" "F.Mask" "F.Paste")
			(net 355 "unconnected-(U9E-RSVDM28_NC-PadM28)")
			(pinfunction "RSVDM28_NC")
			(pintype "passive+no_connect")
		)
		(pad "M30" smd circle
			(at 4.25 -0.435 180)
			(size 0.5 0.5)
			(layers "F.Cu" "F.Mask" "F.Paste")
			(net 268 "unconnected-(U9G-RSVDM30_NC-PadM30)")
			(pinfunction "RSVDM30_NC")
			(pintype "passive+no_connect")
		)
		(pad "M32" smd circle
			(at 5.25 -0.435 180)
			(size 0.5 0.5)
			(layers "F.Cu" "F.Mask" "F.Paste")
			(net 219 "unconnected-(U9G-RSVDM32_NC-PadM32)")
			(pinfunction "RSVDM32_NC")
			(pintype "passive+no_connect")
		)
		(pad "M34" smd circle
			(at 6.25 -0.435 180)
			(size 0.5 0.5)
			(layers "F.Cu" "F.Mask" "F.Paste")
			(net 208 "unconnected-(U9F-RSVDM34_NC-PadM34)")
			(pinfunction "RSVDM34_NC")
			(pintype "passive+no_connect")
		)
		(pad "M36" smd circle
			(at 7.25 -0.435 180)
			(size 0.5 0.5)
			(layers "F.Cu" "F.Mask" "F.Paste")
			(net 196 "unconnected-(U9F-RSVDM36_NC-PadM36)")
			(pinfunction "RSVDM36_NC")
			(pintype "passive+no_connect")
		)
		(pad "M38" smd circle
			(at 8.25 -0.435 180)
			(size 0.5 0.5)
			(layers "F.Cu" "F.Mask" "F.Paste")
			(net 18 "+1V88")
			(pinfunction "VDDP2")
			(pintype "power_in")
		)
		(pad "M40" smd circle
			(at 9.25 -0.435 180)
			(size 0.5 0.5)
			(layers "F.Cu" "F.Mask" "F.Paste")
			(net 142 "/X710-AT2 10GbE/~{P0_INT}")
			(pinfunction "P0_INT_MLC")
			(pintype "passive")
		)
		(pad "M42" smd circle
			(at 10.25 -0.435 180)
			(size 0.5 0.5)
			(layers "F.Cu" "F.Mask" "F.Paste")
			(net 381 "/X710-AT2 Misc/MDIO.MDIO")
			(pinfunction "MDIO")
			(pintype "bidirectional")
		)
		(pad "N1" smd circle
			(at -10.25 0.43 180)
			(size 0.5 0.5)
			(layers "F.Cu" "F.Mask" "F.Paste")
			(net 132 "/X710-AT2 10GbE/MDIO0_SDA0")
			(pinfunction "MDIO0_SDA0")
			(pintype "bidirectional")
		)
		(pad "N3" smd circle
			(at -9.25 0.43 180)
			(size 0.5 0.5)
			(layers "F.Cu" "F.Mask" "F.Paste")
			(net 130 "/X710-AT2 10GbE/MDC0_SCL0")
			(pinfunction "MDC0_SCL0")
			(pintype "output")
		)
		(pad "N5" smd circle
			(at -8.25 0.43 180)
			(size 0.5 0.5)
			(layers "F.Cu" "F.Mask" "F.Paste")
			(net 172 "unconnected-(U9C-SDP3_0-PadN5)")
			(pinfunction "SDP3_0")
			(pintype "passive+no_connect")
		)
		(pad "N7" smd circle
			(at -7.25 0.43 180)
			(size 0.5 0.5)
			(layers "F.Cu" "F.Mask" "F.Paste")
			(net 165 "unconnected-(U9C-SDP3_1-PadN7)")
			(pinfunction "SDP3_1")
			(pintype "passive+no_connect")
		)
		(pad "N9" smd circle
			(at -6.25 0.43 180)
			(size 0.5 0.5)
			(layers "F.Cu" "F.Mask" "F.Paste")
			(net 125 "/X710-AT2 RSVD/RSVDN9_VSS")
			(pinfunction "RSVDN9_VSS")
			(pintype "passive")
		)
		(pad "N11" smd circle
			(at -5.25 0.43 180)
			(size 0.5 0.5)
			(layers "F.Cu" "F.Mask" "F.Paste")
			(net 1 "VCCA")
			(pinfunction "VCCA")
			(pintype "passive")
		)
		(pad "N13" smd circle
			(at -4.25 0.43 180)
			(size 0.5 0.5)
			(layers "F.Cu" "F.Mask" "F.Paste")
			(net 1 "VCCA")
			(pinfunction "VCCA")
			(pintype "passive")
		)
		(pad "N15" smd circle
			(at -3.25 0.43 180)
			(size 0.5 0.5)
			(layers "F.Cu" "F.Mask" "F.Paste")
			(net 1 "VCCA")
			(pinfunction "VCCA")
			(pintype "passive")
		)
		(pad "N17" smd circle
			(at -2.25 0.43 180)
			(size 0.5 0.5)
			(layers "F.Cu" "F.Mask" "F.Paste")
			(net 9 "VCCD")
			(pinfunction "VCCD")
			(pintype "passive")
		)
		(pad "N19" smd circle
			(at -1.25 0.43 180)
			(size 0.5 0.5)
			(layers "F.Cu" "F.Mask" "F.Paste")
			(net 9 "VCCD")
			(pinfunction "VCCD")
			(pintype "passive")
		)
		(pad "N21" smd circle
			(at -0.25 0.43 180)
			(size 0.5 0.5)
			(layers "F.Cu" "F.Mask" "F.Paste")
			(net 9 "VCCD")
			(pinfunction "VCCD")
			(pintype "passive")
		)
		(pad "N23" smd circle
			(at 0.75 0.43 180)
			(size 0.5 0.5)
			(layers "F.Cu" "F.Mask" "F.Paste")
			(net 276 "unconnected-(U9E-RSVDN23_NC-PadN23)")
			(pinfunction "RSVDN23_NC")
			(pintype "passive+no_connect")
		)
		(pad "N25" smd circle
			(at 1.75 0.43 180)
			(size 0.5 0.5)
			(layers "F.Cu" "F.Mask" "F.Paste")
			(net 251 "unconnected-(U9E-RSVDN25_NC-PadN25)")
			(pinfunction "RSVDN25_NC")
			(pintype "passive+no_connect")
		)
		(pad "N27" smd circle
			(at 2.75 0.43 180)
			(size 0.5 0.5)
			(layers "F.Cu" "F.Mask" "F.Paste")
			(net 266 "unconnected-(U9E-RSVDN27_NC-PadN27)")
			(pinfunction "RSVDN27_NC")
			(pintype "passive+no_connect")
		)
		(pad "N29" smd circle
			(at 3.75 0.43 180)
			(size 0.5 0.5)
			(layers "F.Cu" "F.Mask" "F.Paste")
			(net 248 "unconnected-(U9G-RSVDN29_NC-PadN29)")
			(pinfunction "RSVDN29_NC")
			(pintype "passive+no_connect")
		)
		(pad "N31" smd circle
			(at 4.75 0.43 180)
			(size 0.5 0.5)
			(layers "F.Cu" "F.Mask" "F.Paste")
			(net 372 "unconnected-(U9G-RSVDN31_NC-PadN31)")
			(pinfunction "RSVDN31_NC")
			(pintype "passive+no_connect")
		)
		(pad "N33" smd circle
			(at 5.75 0.43 180)
			(size 0.5 0.5)
			(layers "F.Cu" "F.Mask" "F.Paste")
			(net 270 "unconnected-(U9F-RSVDN33_NC-PadN33)")
			(pinfunction "RSVDN33_NC")
			(pintype "passive+no_connect")
		)
		(pad "N35" smd circle
			(at 6.75 0.43 180)
			(size 0.5 0.5)
			(layers "F.Cu" "F.Mask" "F.Paste")
			(net 203 "unconnected-(U9F-RSVDN35_NC-PadN35)")
			(pinfunction "RSVDN35_NC")
			(pintype "passive+no_connect")
		)
		(pad "N37" smd circle
			(at 7.75 0.43 180)
			(size 0.5 0.5)
			(layers "F.Cu" "F.Mask" "F.Paste")
			(net 28 "GND")
			(pinfunction "RSVDN37_VSS")
			(pintype "passive")
		)
		(pad "N39" smd circle
			(at 8.75 0.43 180)
			(size 0.5 0.5)
			(layers "F.Cu" "F.Mask" "F.Paste")
			(net 166 "unconnected-(U9F-P0_PTP_SYNC0-PadN39)")
			(pinfunction "P0_PTP_SYNC0")
			(pintype "passive+no_connect")
		)
		(pad "N41" smd circle
			(at 9.75 0.43 180)
			(size 0.5 0.5)
			(layers "F.Cu" "F.Mask" "F.Paste")
			(net 182 "unconnected-(U9F-P0_PTP_SYNC1-PadN41)")
			(pinfunction "P0_PTP_SYNC1")
			(pintype "passive+no_connect")
		)
		(pad "P2" smd circle
			(at -9.75 1.295 180)
			(size 0.5 0.5)
			(layers "F.Cu" "F.Mask" "F.Paste")
			(net 309 "/OCuLink/~{PE_WAKE}")
			(pinfunction "~{PE_WAKE}")
			(pintype "open_collector")
		)
		(pad "P4" smd circle
			(at -8.75 1.295 180)
			(size 0.5 0.5)
			(layers "F.Cu" "F.Mask" "F.Paste")
			(net 354 "unconnected-(U9C-SDP1_1-PadP4)")
			(pinfunction "SDP1_1")
			(pintype "passive+no_connect")
		)
		(pad "P6" smd circle
			(at -7.75 1.295 180)
			(size 0.5 0.5)
			(layers "F.Cu" "F.Mask" "F.Paste")
			(net 225 "unconnected-(U9C-SDP1_2-PadP6)")
			(pinfunction "SDP1_2")
			(pintype "passive+no_connect")
		)
		(pad "P8" smd circle
			(at -6.75 1.295 180)
			(size 0.5 0.5)
			(layers "F.Cu" "F.Mask" "F.Paste")
			(net 129 "/X710-AT2 RSVD/RSVDP8_VSS")
			(pinfunction "RSVDP8_VSS")
			(pintype "passive")
		)
		(pad "P10" smd circle
			(at -5.75 1.295 180)
			(size 0.5 0.5)
			(layers "F.Cu" "F.Mask" "F.Paste")
			(net 28 "GND")
			(pinfunction "VSS")
			(pintype "passive")
		)
		(pad "P12" smd circle
			(at -4.75 1.295 180)
			(size 0.5 0.5)
			(layers "F.Cu" "F.Mask" "F.Paste")
			(net 28 "GND")
			(pinfunction "VSS")
			(pintype "passive")
		)
		(pad "P14" smd circle
			(at -3.75 1.295 180)
			(size 0.5 0.5)
			(layers "F.Cu" "F.Mask" "F.Paste")
			(net 28 "GND")
			(pinfunction "VSS")
			(pintype "passive")
		)
		(pad "P16" smd circle
			(at -2.75 1.295 180)
			(size 0.5 0.5)
			(layers "F.Cu" "F.Mask" "F.Paste")
			(net 28 "GND")
			(pinfunction "VSS")
			(pintype "passive")
		)
		(pad "P18" smd circle
			(at -1.75 1.295 180)
			(size 0.5 0.5)
			(layers "F.Cu" "F.Mask" "F.Paste")
			(net 28 "GND")
			(pinfunction "VSS")
			(pintype "passive")
		)
		(pad "P20" smd circle
			(at -0.75 1.295 180)
			(size 0.5 0.5)
			(layers "F.Cu" "F.Mask" "F.Paste")
			(net 28 "GND")
			(pinfunction "VSS")
			(pintype "passive")
		)
		(pad "P22" smd circle
			(at 0.25 1.295 180)
			(size 0.5 0.5)
			(layers "F.Cu" "F.Mask" "F.Paste")
			(net 127 "/X710-AT2 RSVD/RSVDP22_VSS")
			(pinfunction "RSVDP22_VSS")
			(pintype "passive")
		)
		(pad "P24" smd circle
			(at 1.25 1.295 180)
			(size 0.5 0.5)
			(layers "F.Cu" "F.Mask" "F.Paste")
			(net 339 "unconnected-(U9E-RSVDP24_NC-PadP24)")
			(pinfunction "RSVDP24_NC")
			(pintype "passive+no_connect")
		)
		(pad "P26" smd circle
			(at 2.25 1.295 180)
			(size 0.5 0.5)
			(layers "F.Cu" "F.Mask" "F.Paste")
			(net 216 "unconnected-(U9E-RSVDP26_NC-PadP26)")
			(pinfunction "RSVDP26_NC")
			(pintype "passive+no_connect")
		)
		(pad "P28" smd circle
			(at 3.25 1.295 180)
			(size 0.5 0.5)
			(layers "F.Cu" "F.Mask" "F.Paste")
			(net 370 "unconnected-(U9E-RSVDP28_NC-PadP28)")
			(pinfunction "RSVDP28_NC")
			(pintype "passive+no_connect")
		)
		(pad "P30" smd circle
			(at 4.25 1.295 180)
			(size 0.5 0.5)
			(layers "F.Cu" "F.Mask" "F.Paste")
			(net 228 "unconnected-(U9G-RSVDP30_NC-PadP30)")
			(pinfunction "RSVDP30_NC")
			(pintype "passive+no_connect")
		)
		(pad "P32" smd circle
			(at 5.25 1.295 180)
			(size 0.5 0.5)
			(layers "F.Cu" "F.Mask" "F.Paste")
			(net 262 "unconnected-(U9G-RSVDP32_NC-PadP32)")
			(pinfunction "RSVDP32_NC")
			(pintype "passive+no_connect")
		)
		(pad "P34" smd circle
			(at 6.25 1.295 180)
			(size 0.5 0.5)
			(layers "F.Cu" "F.Mask" "F.Paste")
			(net 284 "unconnected-(U9F-RSVDP34_NC-PadP34)")
			(pinfunction "RSVDP34_NC")
			(pintype "passive+no_connect")
		)
		(pad "P36" smd circle
			(at 7.25 1.295 180)
			(size 0.5 0.5)
			(layers "F.Cu" "F.Mask" "F.Paste")
			(net 237 "unconnected-(U9F-RSVDP36_NC-PadP36)")
			(pinfunction "RSVDP36_NC")
			(pintype "passive+no_connect")
		)
		(pad "P38" smd circle
			(at 8.25 1.295 180)
			(size 0.5 0.5)
			(layers "F.Cu" "F.Mask" "F.Paste")
			(net 28 "GND")
			(pinfunction "RSVDP38_VSS")
			(pintype "passive")
		)
		(pad "P40" smd circle
			(at 9.25 1.295 180)
			(size 0.5 0.5)
			(layers "F.Cu" "F.Mask" "F.Paste")
			(net 107 "/X710-AT2 Misc/FLSH_SCK")
			(pinfunction "FLSH_SCK")
			(pintype "tri_state")
		)
		(pad "P42" smd circle
			(at 10.25 1.295 180)
			(size 0.5 0.5)
			(layers "F.Cu" "F.Mask" "F.Paste")
			(net 139 "/Flash memory/FLASH.MOSI")
			(pinfunction "FLSH_SI")
			(pintype "tri_state")
		)
		(pad "R1" smd circle
			(at -10.25 2.16 180)
			(size 0.5 0.5)
			(layers "F.Cu" "F.Mask" "F.Paste")
			(net 308 "/OCuLink/~{PE_RST}")
			(pinfunction "~{PE_RST}")
			(pintype "input")
		)
		(pad "R3" smd circle
			(at -9.25 2.16 180)
			(size 0.5 0.5)
			(layers "F.Cu" "F.Mask" "F.Paste")
			(net 231 "unconnected-(U9C-LED3_0-PadR3)")
			(pinfunction "LED3_0")
			(pintype "passive+no_connect")
		)
		(pad "R5" smd circle
			(at -8.25 2.16 180)
			(size 0.5 0.5)
			(layers "F.Cu" "F.Mask" "F.Paste")
			(net 358 "unconnected-(U9C-LED3_1-PadR5)")
			(pinfunction "LED3_1")
			(pintype "passive+no_connect")
		)
		(pad "R7" smd circle
			(at -7.25 2.16 180)
			(size 0.5 0.5)
			(layers "F.Cu" "F.Mask" "F.Paste")
			(net 347 "unconnected-(U9C-SDP1_0-PadR7)")
			(pinfunction "SDP1_0")
			(pintype "passive+no_connect")
		)
		(pad "R9" smd circle
			(at -6.25 2.16 180)
			(size 0.5 0.5)
			(layers "F.Cu" "F.Mask" "F.Paste")
			(net 180 "unconnected-(U9E-RSVDR9_NC-PadR9)")
			(pinfunction "RSVDR9_NC")
			(pintype "passive+no_connect")
		)
		(pad "R11" smd circle
			(at -5.25 2.16 180)
			(size 0.5 0.5)
			(layers "F.Cu" "F.Mask" "F.Paste")
			(net 7 "+3V3")
			(pinfunction "VCC3P3")
			(pintype "passive")
		)
		(pad "R13" smd circle
			(at -4.25 2.16 180)
			(size 0.5 0.5)
			(layers "F.Cu" "F.Mask" "F.Paste")
			(net 9 "VCCD")
			(pinfunction "VCCD")
			(pintype "passive")
		)
		(pad "R15" smd circle
			(at -3.25 2.16 180)
			(size 0.5 0.5)
			(layers "F.Cu" "F.Mask" "F.Paste")
			(net 9 "VCCD")
			(pinfunction "VCCD")
			(pintype "passive")
		)
		(pad "R17" smd circle
			(at -2.25 2.16 180)
			(size 0.5 0.5)
			(layers "F.Cu" "F.Mask" "F.Paste")
			(net 9 "VCCD")
			(pinfunction "VCCD")
			(pintype "passive")
		)
		(pad "R19" smd circle
			(at -1.25 2.16 180)
			(size 0.5 0.5)
			(layers "F.Cu" "F.Mask" "F.Paste")
			(net 9 "VCCD")
			(pinfunction "VCCD")
			(pintype "passive")
		)
		(pad "R21" smd circle
			(at -0.25 2.16 180)
			(size 0.5 0.5)
			(layers "F.Cu" "F.Mask" "F.Paste")
			(net 9 "VCCD")
			(pinfunction "VCCD")
			(pintype "passive")
		)
		(pad "R23" smd circle
			(at 0.75 2.16 180)
			(size 0.5 0.5)
			(layers "F.Cu" "F.Mask" "F.Paste")
			(net 298 "unconnected-(U9E-RSVDR23_NC-PadR23)")
			(pinfunction "RSVDR23_NC")
			(pintype "passive+no_connect")
		)
		(pad "R25" smd circle
			(at 1.75 2.16 180)
			(size 0.5 0.5)
			(layers "F.Cu" "F.Mask" "F.Paste")
			(net 278 "unconnected-(U9E-RSVDR25_NC-PadR25)")
			(pinfunction "RSVDR25_NC")
			(pintype "passive+no_connect")
		)
		(pad "R27" smd circle
			(at 2.75 2.16 180)
			(size 0.5 0.5)
			(layers "F.Cu" "F.Mask" "F.Paste")
			(net 186 "unconnected-(U9E-RSVDR27_NC-PadR27)")
			(pinfunction "RSVDR27_NC")
			(pintype "passive+no_connect")
		)
		(pad "R29" smd circle
			(at 3.75 2.16 180)
			(size 0.5 0.5)
			(layers "F.Cu" "F.Mask" "F.Paste")
			(net 271 "unconnected-(U9G-RSVDR29_NC-PadR29)")
			(pinfunction "RSVDR29_NC")
			(pintype "passive+no_connect")
		)
		(pad "R31" smd circle
			(at 4.75 2.16 180)
			(size 0.5 0.5)
			(layers "F.Cu" "F.Mask" "F.Paste")
			(net 283 "unconnected-(U9G-RSVDR31_NC-PadR31)")
			(pinfunction "RSVDR31_NC")
			(pintype "passive+no_connect")
		)
		(pad "R33" smd circle
			(at 5.75 2.16 180)
			(size 0.5 0.5)
			(layers "F.Cu" "F.Mask" "F.Paste")
			(net 220 "unconnected-(U9F-RSVDR33_NC-PadR33)")
			(pinfunction "RSVDR33_NC")
			(pintype "passive+no_connect")
		)
		(pad "R35" smd circle
			(at 6.75 2.16 180)
			(size 0.5 0.5)
			(layers "F.Cu" "F.Mask" "F.Paste")
			(net 28 "GND")
			(pinfunction "VSS")
			(pintype "passive")
		)
		(pad "R37" smd circle
			(at 7.75 2.16 180)
			(size 0.5 0.5)
			(layers "F.Cu" "F.Mask" "F.Paste")
			(net 187 "unconnected-(U9F-RSVDR37_NC-PadR37)")
			(pinfunction "RSVDR37_NC")
			(pintype "passive+no_connect")
		)
		(pad "R39" smd circle
			(at 8.75 2.16 180)
			(size 0.5 0.5)
			(layers "F.Cu" "F.Mask" "F.Paste")
			(net 394 "/OCuLink/SMBus.SCL")
			(pinfunction "SMBCLK")
			(pintype "open_collector")
		)
		(pad "R41" smd circle
			(at 9.75 2.16 180)
			(size 0.5 0.5)
			(layers "F.Cu" "F.Mask" "F.Paste")
			(net 105 "/Flash memory/FLASH.~{CE}")
			(pinfunction "~{FLSH_CE}")
			(pintype "tri_state")
		)
		(pad "T2" smd circle
			(at -9.75 3.025 180)
			(size 0.5 0.5)
			(layers "F.Cu" "F.Mask" "F.Paste")
			(net 7 "+3V3")
			(pinfunction "VCC3P3_SVR")
			(pintype "power_in")
		)
		(pad "T4" smd circle
			(at -8.75 3.025 180)
			(size 0.5 0.5)
			(layers "F.Cu" "F.Mask" "F.Paste")
			(net 88 "/2xRJ45/~{P1_LED_ACT}")
			(pinfunction "LED2_0")
			(pintype "output")
		)
		(pad "T6" smd circle
			(at -7.75 3.025 180)
			(size 0.5 0.5)
			(layers "F.Cu" "F.Mask" "F.Paste")
			(net 87 "/2xRJ45/~{P1_LED_LINK_10G}")
			(pinfunction "LED2_1")
			(pintype "output")
		)
		(pad "T8" smd circle
			(at -6.75 3.025 180)
			(size 0.5 0.5)
			(layers "F.Cu" "F.Mask" "F.Paste")
			(net 9 "VCCD")
			(pinfunction "RSVDT8_VCCD")
			(pintype "passive")
		)
		(pad "T10" smd circle
			(at -5.75 3.025 180)
			(size 0.5 0.5)
			(layers "F.Cu" "F.Mask" "F.Paste")
			(net 28 "GND")
			(pinfunction "VSS")
			(pintype "passive")
		)
		(pad "T12" smd circle
			(at -4.75 3.025 180)
			(size 0.5 0.5)
			(layers "F.Cu" "F.Mask" "F.Paste")
			(net 28 "GND")
			(pinfunction "VSS")
			(pintype "passive")
		)
		(pad "T14" smd circle
			(at -3.75 3.025 180)
			(size 0.5 0.5)
			(layers "F.Cu" "F.Mask" "F.Paste")
			(net 28 "GND")
			(pinfunction "VSS")
			(pintype "passive")
		)
		(pad "T16" smd circle
			(at -2.75 3.025 180)
			(size 0.5 0.5)
			(layers "F.Cu" "F.Mask" "F.Paste")
			(net 28 "GND")
			(pinfunction "VSS")
			(pintype "passive")
		)
		(pad "T18" smd circle
			(at -1.75 3.025 180)
			(size 0.5 0.5)
			(layers "F.Cu" "F.Mask" "F.Paste")
			(net 28 "GND")
			(pinfunction "VSS")
			(pintype "passive")
		)
		(pad "T20" smd circle
			(at -0.75 3.025 180)
			(size 0.5 0.5)
			(layers "F.Cu" "F.Mask" "F.Paste")
			(net 28 "GND")
			(pinfunction "VSS")
			(pintype "passive")
		)
		(pad "T22" smd circle
			(at 0.25 3.025 180)
			(size 0.5 0.5)
			(layers "F.Cu" "F.Mask" "F.Paste")
			(net 171 "unconnected-(U9E-RSVDT22_NC-PadT22)")
			(pinfunction "RSVDT22_NC")
			(pintype "passive+no_connect")
		)
		(pad "T24" smd circle
			(at 1.25 3.025 180)
			(size 0.5 0.5)
			(layers "F.Cu" "F.Mask" "F.Paste")
			(net 204 "unconnected-(U9E-RSVDT24_NC-PadT24)")
			(pinfunction "RSVDT24_NC")
			(pintype "passive+no_connect")
		)
		(pad "T26" smd circle
			(at 2.25 3.025 180)
			(size 0.5 0.5)
			(layers "F.Cu" "F.Mask" "F.Paste")
			(net 201 "unconnected-(U9E-RSVDT26_NC-PadT26)")
			(pinfunction "RSVDT26_NC")
			(pintype "passive+no_connect")
		)
		(pad "T28" smd circle
			(at 3.25 3.025 180)
			(size 0.5 0.5)
			(layers "F.Cu" "F.Mask" "F.Paste")
			(net 163 "unconnected-(U9E-RSVDT28_NC-PadT28)")
			(pinfunction "RSVDT28_NC")
			(pintype "passive+no_connect")
		)
		(pad "T30" smd circle
			(at 4.25 3.025 180)
			(size 0.5 0.5)
			(layers "F.Cu" "F.Mask" "F.Paste")
			(net 190 "unconnected-(U9G-RSVDT30_NC-PadT30)")
			(pinfunction "RSVDT30_NC")
			(pintype "passive+no_connect")
		)
		(pad "T32" smd circle
			(at 5.25 3.025 180)
			(size 0.5 0.5)
			(layers "F.Cu" "F.Mask" "F.Paste")
			(net 297 "unconnected-(U9G-RSVDT32_NC-PadT32)")
			(pinfunction "RSVDT32_NC")
			(pintype "passive+no_connect")
		)
		(pad "T34" smd circle
			(at 6.25 3.025 180)
			(size 0.5 0.5)
			(layers "F.Cu" "F.Mask" "F.Paste")
			(net 7 "+3V3")
			(pinfunction "VCC3P3")
			(pintype "passive")
		)
		(pad "T36" smd circle
			(at 7.25 3.025 180)
			(size 0.5 0.5)
			(layers "F.Cu" "F.Mask" "F.Paste")
			(net 11 "/X710-AT2 PCIe/PCIe_JTAG.JTDI")
			(pinfunction "JTDI")
			(pintype "input")
		)
		(pad "T38" smd circle
			(at 8.25 3.025 180)
			(size 0.5 0.5)
			(layers "F.Cu" "F.Mask" "F.Paste")
			(net 8 "/X710-AT2 PCIe/PCIe_JTAG.JTDO")
			(pinfunction "JTDO")
			(pintype "open_collector")
		)
		(pad "T40" smd circle
			(at 9.25 3.025 180)
			(size 0.5 0.5)
			(layers "F.Cu" "F.Mask" "F.Paste")
			(net 395 "/OCuLink/SMBus.SDA")
			(pinfunction "SMBD")
			(pintype "open_collector")
		)
		(pad "T42" smd circle
			(at 10.25 3.025 180)
			(size 0.5 0.5)
			(layers "F.Cu" "F.Mask" "F.Paste")
			(net 140 "/Flash memory/FLASH.MISO")
			(pinfunction "FLSH_SO")
			(pintype "input")
		)
		(pad "U1" smd circle
			(at -10.25 3.89 180)
			(size 0.5 0.5)
			(layers "F.Cu" "F.Mask" "F.Paste")
			(net 28 "GND")
			(pinfunction "VSS_SVR")
			(pintype "power_in")
		)
		(pad "U3" smd circle
			(at -9.25 3.89 180)
			(size 0.5 0.5)
			(layers "F.Cu" "F.Mask" "F.Paste")
			(net 289 "/X710-AT2 Misc/~{PCI_DIS}")
			(pinfunction "~{PCI_DIS}")
			(pintype "tri_state")
		)
		(pad "U5" smd circle
			(at -8.25 3.89 180)
			(size 0.5 0.5)
			(layers "F.Cu" "F.Mask" "F.Paste")
			(net 241 "unconnected-(U9C-LED1_0-PadU5)")
			(pinfunction "LED1_0")
			(pintype "passive+no_connect")
		)
		(pad "U7" smd circle
			(at -7.25 3.89 180)
			(size 0.5 0.5)
			(layers "F.Cu" "F.Mask" "F.Paste")
			(net 269 "unconnected-(U9C-LED1_1-PadU7)")
			(pinfunction "LED1_1")
			(pintype "passive+no_connect")
		)
		(pad "U9" smd circle
			(at -6.25 3.89 180)
			(size 0.5 0.5)
			(layers "F.Cu" "F.Mask" "F.Paste")
			(net 193 "unconnected-(U9E-RSVDU9_NC-PadU9)")
			(pinfunction "RSVDU9_NC")
			(pintype "passive+no_connect")
		)
		(pad "U11" smd circle
			(at -5.25 3.89 180)
			(size 0.5 0.5)
			(layers "F.Cu" "F.Mask" "F.Paste")
			(net 9 "VCCD")
			(pinfunction "VCCD")
			(pintype "passive")
		)
		(pad "U13" smd circle
			(at -4.25 3.89 180)
			(size 0.5 0.5)
			(layers "F.Cu" "F.Mask" "F.Paste")
			(net 9 "VCCD")
			(pinfunction "VCCD")
			(pintype "passive")
		)
		(pad "U15" smd circle
			(at -3.25 3.89 180)
			(size 0.5 0.5)
			(layers "F.Cu" "F.Mask" "F.Paste")
			(net 9 "VCCD")
			(pinfunction "VCCD")
			(pintype "passive")
		)
		(pad "U17" smd circle
			(at -2.25 3.89 180)
			(size 0.5 0.5)
			(layers "F.Cu" "F.Mask" "F.Paste")
			(net 9 "VCCD")
			(pinfunction "VCCD")
			(pintype "passive")
		)
		(pad "U19" smd circle
			(at -1.25 3.89 180)
			(size 0.5 0.5)
			(layers "F.Cu" "F.Mask" "F.Paste")
			(net 9 "VCCD")
			(pinfunction "VCCD")
			(pintype "passive")
		)
		(pad "U21" smd circle
			(at -0.25 3.89 180)
			(size 0.5 0.5)
			(layers "F.Cu" "F.Mask" "F.Paste")
			(net 7 "+3V3")
			(pinfunction "VCC3P3")
			(pintype "power_in")
		)
		(pad "U23" smd circle
			(at 0.75 3.89 180)
			(size 0.5 0.5)
			(layers "F.Cu" "F.Mask" "F.Paste")
			(net 222 "unconnected-(U9E-RSVDU23_NC-PadU23)")
			(pinfunction "RSVDU23_NC")
			(pintype "passive+no_connect")
		)
		(pad "U25" smd circle
			(at 1.75 3.89 180)
			(size 0.5 0.5)
			(layers "F.Cu" "F.Mask" "F.Paste")
			(net 280 "unconnected-(U9E-RSVDU25_NC-PadU25)")
			(pinfunction "RSVDU25_NC")
			(pintype "passive+no_connect")
		)
		(pad "U27" smd circle
			(at 2.75 3.89 180)
			(size 0.5 0.5)
			(layers "F.Cu" "F.Mask" "F.Paste")
			(net 261 "unconnected-(U9E-RSVDU27_NC-PadU27)")
			(pinfunction "RSVDU27_NC")
			(pintype "passive+no_connect")
		)
		(pad "U29" smd circle
			(at 3.75 3.89 180)
			(size 0.5 0.5)
			(layers "F.Cu" "F.Mask" "F.Paste")
			(net 184 "unconnected-(U9E-RSVDU29_NC-PadU29)")
			(pinfunction "RSVDU29_NC")
			(pintype "passive+no_connect")
		)
		(pad "U31" smd circle
			(at 4.75 3.89 180)
			(size 0.5 0.5)
			(layers "F.Cu" "F.Mask" "F.Paste")
			(net 173 "unconnected-(U9G-RSVDU31_NC-PadU31)")
			(pinfunction "RSVDU31_NC")
			(pintype "passive+no_connect")
		)
		(pad "U33" smd circle
			(at 5.75 3.89 180)
			(size 0.5 0.5)
			(layers "F.Cu" "F.Mask" "F.Paste")
			(net 232 "unconnected-(U9G-RSVDU33_NC-PadU33)")
			(pinfunction "RSVDU33_NC")
			(pintype "passive+no_connect")
		)
		(pad "U35" smd circle
			(at 6.75 3.89 180)
			(size 0.5 0.5)
			(layers "F.Cu" "F.Mask" "F.Paste")
			(net 167 "unconnected-(U9G-RSVDU35_NC-PadU35)")
			(pinfunction "RSVDU35_NC")
			(pintype "passive+no_connect")
		)
		(pad "U37" smd circle
			(at 7.75 3.89 180)
			(size 0.5 0.5)
			(layers "F.Cu" "F.Mask" "F.Paste")
			(net 16 "/X710-AT2 PCIe/PCIe_JTAG.JTCK")
			(pinfunction "JTCK")
			(pintype "input")
		)
		(pad "U39" smd circle
			(at 8.75 3.89 180)
			(size 0.5 0.5)
			(layers "F.Cu" "F.Mask" "F.Paste")
			(net 47 "/X710-AT2 Misc/POR_BYPASS")
			(pinfunction "POR_BYPASS")
			(pintype "input")
		)
		(pad "U41" smd circle
			(at 9.75 3.89 180)
			(size 0.5 0.5)
			(layers "F.Cu" "F.Mask" "F.Paste")
			(net 97 "/X710-AT2 Misc/~{SMBALRT}")
			(pinfunction "~{SMBALRT}")
			(pintype "open_collector")
		)
		(pad "V2" smd circle
			(at -9.75 4.755 180)
			(size 0.5 0.5)
			(layers "F.Cu" "F.Mask" "F.Paste")
			(net 155 "Net-(U9H-SVR_IND)")
			(pinfunction "SVR_IND")
			(pintype "passive")
		)
		(pad "V4" smd circle
			(at -8.75 4.755 180)
			(size 0.5 0.5)
			(layers "F.Cu" "F.Mask" "F.Paste")
			(net 82 "/2xRJ45/~{P0_LED_ACT}")
			(pinfunction "LED0_0")
			(pintype "output")
		)
		(pad "V6" smd circle
			(at -7.75 4.755 180)
			(size 0.5 0.5)
			(layers "F.Cu" "F.Mask" "F.Paste")
			(net 81 "/2xRJ45/~{P0_LED_LINK_10G}")
			(pinfunction "LED0_1")
			(pintype "output")
		)
		(pad "V8" smd circle
			(at -6.75 4.755 180)
			(size 0.5 0.5)
			(layers "F.Cu" "F.Mask" "F.Paste")
			(net 210 "unconnected-(U9H-RSVDV8_NC-PadV8)")
			(pinfunction "RSVDV8_NC")
			(pintype "passive+no_connect")
		)
		(pad "V10" smd circle
			(at -5.75 4.755 180)
			(size 0.5 0.5)
			(layers "F.Cu" "F.Mask" "F.Paste")
			(net 240 "unconnected-(U9H-RSVDV10_NC-PadV10)")
			(pinfunction "RSVDV10_NC")
			(pintype "passive+no_connect")
		)
		(pad "V12" smd circle
			(at -4.75 4.755 180)
			(size 0.5 0.5)
			(layers "F.Cu" "F.Mask" "F.Paste")
			(net 28 "GND")
			(pinfunction "VSSA")
			(pintype "passive")
		)
		(pad "V14" smd circle
			(at -3.75 4.755 180)
			(size 0.5 0.5)
			(layers "F.Cu" "F.Mask" "F.Paste")
			(net 28 "GND")
			(pinfunction "VSSA")
			(pintype "passive")
		)
		(pad "V16" smd circle
			(at -2.75 4.755 180)
			(size 0.5 0.5)
			(layers "F.Cu" "F.Mask" "F.Paste")
			(net 28 "GND")
			(pinfunction "VSSA")
			(pintype "passive")
		)
		(pad "V18" smd circle
			(at -1.75 4.755 180)
			(size 0.5 0.5)
			(layers "F.Cu" "F.Mask" "F.Paste")
			(net 28 "GND")
			(pinfunction "VSSA")
			(pintype "passive")
		)
		(pad "V20" smd circle
			(at -0.75 4.755 180)
			(size 0.5 0.5)
			(layers "F.Cu" "F.Mask" "F.Paste")
			(net 28 "GND")
			(pinfunction "VSSA")
			(pintype "passive")
		)
		(pad "V22" smd circle
			(at 0.25 4.755 180)
			(size 0.5 0.5)
			(layers "F.Cu" "F.Mask" "F.Paste")
			(net 181 "unconnected-(U9E-RSVDV22_NC-PadV22)")
			(pinfunction "RSVDV22_NC")
			(pintype "passive+no_connect")
		)
		(pad "V24" smd circle
			(at 1.25 4.755 180)
			(size 0.5 0.5)
			(layers "F.Cu" "F.Mask" "F.Paste")
			(net 233 "unconnected-(U9E-RSVDV24_NC-PadV24)")
			(pinfunction "RSVDV24_NC")
			(pintype "passive+no_connect")
		)
		(pad "V26" smd circle
			(at 2.25 4.755 180)
			(size 0.5 0.5)
			(layers "F.Cu" "F.Mask" "F.Paste")
			(net 344 "unconnected-(U9E-RSVDV26_NC-PadV26)")
			(pinfunction "RSVDV26_NC")
			(pintype "passive+no_connect")
		)
		(pad "V28" smd circle
			(at 3.25 4.755 180)
			(size 0.5 0.5)
			(layers "F.Cu" "F.Mask" "F.Paste")
			(net 217 "unconnected-(U9E-RSVDV28_NC-PadV28)")
			(pinfunction "RSVDV28_NC")
			(pintype "passive+no_connect")
		)
		(pad "V30" smd circle
			(at 4.25 4.755 180)
			(size 0.5 0.5)
			(layers "F.Cu" "F.Mask" "F.Paste")
			(net 306 "unconnected-(U9G-RSVDV30_NC-PadV30)")
			(pinfunction "RSVDV30_NC")
			(pintype "passive+no_connect")
		)
		(pad "V32" smd circle
			(at 5.25 4.755 180)
			(size 0.5 0.5)
			(layers "F.Cu" "F.Mask" "F.Paste")
			(net 183 "unconnected-(U9G-RSVDV32_NC-PadV32)")
			(pinfunction "RSVDV32_NC")
			(pintype "passive+no_connect")
		)
		(pad "V34" smd circle
			(at 6.25 4.755 180)
			(size 0.5 0.5)
			(layers "F.Cu" "F.Mask" "F.Paste")
			(net 257 "unconnected-(U9G-RSVDV34_NC-PadV34)")
			(pinfunction "RSVDV34_NC")
			(pintype "passive+no_connect")
		)
		(pad "V36" smd circle
			(at 7.25 4.755 180)
			(size 0.5 0.5)
			(layers "F.Cu" "F.Mask" "F.Paste")
			(net 15 "/X710-AT2 PCIe/PCIe_JTAG.~{JRST}")
			(pinfunction "~{JRST}")
			(pintype "input")
		)
		(pad "V38" smd circle
			(at 8.25 4.755 180)
			(size 0.5 0.5)
			(layers "F.Cu" "F.Mask" "F.Paste")
			(net 4 "/X710-AT2 PCIe/PCIe_JTAG.JTMS")
			(pinfunction "JTMS")
			(pintype "input")
		)
		(pad "V40" smd circle
			(at 9.25 4.755 180)
			(size 0.5 0.5)
			(layers "F.Cu" "F.Mask" "F.Paste")
			(net 291 "/2xRJ45/~{P0_LINK_LESS_THAN_10G}")
			(pinfunction "GPIO_0")
			(pintype "tri_state")
		)
		(pad "V42" smd circle
			(at 10.25 4.755 180)
			(size 0.5 0.5)
			(layers "F.Cu" "F.Mask" "F.Paste")
			(net 263 "unconnected-(U9D-GPIO_3-PadV42)")
			(pinfunction "GPIO_3")
			(pintype "passive+no_connect")
		)
		(pad "W1" smd circle
			(at -10.25 5.62 180)
			(size 0.5 0.5)
			(layers "F.Cu" "F.Mask" "F.Paste")
			(net 126 "/X710-AT2 RSVD/RSVDW1_VSS")
			(pinfunction "RSVDW1_VSS")
			(pintype "passive")
		)
		(pad "W3" smd circle
			(at -9.25 5.62 180)
			(size 0.5 0.5)
			(layers "F.Cu" "F.Mask" "F.Paste")
			(net 28 "GND")
			(pinfunction "RSVDW3_VSS")
			(pintype "power_in")
		)
		(pad "W5" smd circle
			(at -8.25 5.62 180)
			(size 0.5 0.5)
			(layers "F.Cu" "F.Mask" "F.Paste")
			(net 124 "/X710-AT2 RSVD/RSVDW5_VSS")
			(pinfunction "RSVDW5_VSS")
			(pintype "passive")
		)
		(pad "W7" smd circle
			(at -7.25 5.62 180)
			(size 0.5 0.5)
			(layers "F.Cu" "F.Mask" "F.Paste")
			(net 120 "/X710-AT2 RSVD/DEBUG_W7")
			(pinfunction "DEBUG_W7")
			(pintype "passive")
		)
		(pad "W9" smd circle
			(at -6.25 5.62 180)
			(size 0.5 0.5)
			(layers "F.Cu" "F.Mask" "F.Paste")
			(net 9 "VCCD")
			(pinfunction "VCCD_A")
			(pintype "power_in")
		)
		(pad "W11" smd circle
			(at -5.25 5.62 180)
			(size 0.5 0.5)
			(layers "F.Cu" "F.Mask" "F.Paste")
			(net 7 "+3V3")
			(pinfunction "VCC3P3_A")
			(pintype "power_in")
		)
		(pad "W13" smd circle
			(at -4.25 5.62 180)
			(size 0.5 0.5)
			(layers "F.Cu" "F.Mask" "F.Paste")
			(net 1 "VCCA")
			(pinfunction "VCCA")
			(pintype "passive")
		)
		(pad "W15" smd circle
			(at -3.25 5.62 180)
			(size 0.5 0.5)
			(layers "F.Cu" "F.Mask" "F.Paste")
			(net 1 "VCCA")
			(pinfunction "VCCA")
			(pintype "passive")
		)
		(pad "W17" smd circle
			(at -2.25 5.62 180)
			(size 0.5 0.5)
			(layers "F.Cu" "F.Mask" "F.Paste")
			(net 1 "VCCA")
			(pinfunction "VCCA")
			(pintype "passive")
		)
		(pad "W19" smd circle
			(at -1.25 5.62 180)
			(size 0.5 0.5)
			(layers "F.Cu" "F.Mask" "F.Paste")
			(net 1 "VCCA")
			(pinfunction "VCCA")
			(pintype "passive")
		)
		(pad "W21" smd circle
			(at -0.25 5.62 180)
			(size 0.5 0.5)
			(layers "F.Cu" "F.Mask" "F.Paste")
			(net 1 "VCCA")
			(pinfunction "VCCA")
			(pintype "passive")
		)
		(pad "W23" smd circle
			(at 0.75 5.62 180)
			(size 0.5 0.5)
			(layers "F.Cu" "F.Mask" "F.Paste")
			(net 206 "unconnected-(U9E-RSVDW23_NC-PadW23)")
			(pinfunction "RSVDW23_NC")
			(pintype "passive+no_connect")
		)
		(pad "W25" smd circle
			(at 1.75 5.62 180)
			(size 0.5 0.5)
			(layers "F.Cu" "F.Mask" "F.Paste")
			(net 194 "unconnected-(U9E-RSVDW25_NC-PadW25)")
			(pinfunction "RSVDW25_NC")
			(pintype "passive+no_connect")
		)
		(pad "W27" smd circle
			(at 2.75 5.62 180)
			(size 0.5 0.5)
			(layers "F.Cu" "F.Mask" "F.Paste")
			(net 179 "unconnected-(U9E-RSVDW27_NC-PadW27)")
			(pinfunction "RSVDW27_NC")
			(pintype "passive+no_connect")
		)
		(pad "W29" smd circle
			(at 3.75 5.62 180)
			(size 0.5 0.5)
			(layers "F.Cu" "F.Mask" "F.Paste")
			(net 28 "GND")
			(pinfunction "VSSA")
			(pintype "passive")
		)
		(pad "W31" smd circle
			(at 4.75 5.62 180)
			(size 0.5 0.5)
			(layers "F.Cu" "F.Mask" "F.Paste")
			(net 28 "GND")
			(pinfunction "VSSA")
			(pintype "passive")
		)
		(pad "W33" smd circle
			(at 5.75 5.62 180)
			(size 0.5 0.5)
			(layers "F.Cu" "F.Mask" "F.Paste")
			(net 28 "GND")
			(pinfunction "VSSA")
			(pintype "passive")
		)
		(pad "W35" smd circle
			(at 6.75 5.62 180)
			(size 0.5 0.5)
			(layers "F.Cu" "F.Mask" "F.Paste")
			(net 28 "GND")
			(pinfunction "VSSA")
			(pintype "passive")
		)
		(pad "W37" smd circle
			(at 7.75 5.62 180)
			(size 0.5 0.5)
			(layers "F.Cu" "F.Mask" "F.Paste")
			(net 28 "GND")
			(pinfunction "VSSA")
			(pintype "passive")
		)
		(pad "W39" smd circle
			(at 8.75 5.62 180)
			(size 0.5 0.5)
			(layers "F.Cu" "F.Mask" "F.Paste")
			(net 28 "GND")
			(pinfunction "VSSA")
			(pintype "passive")
		)
		(pad "W41" smd circle
			(at 9.75 5.62 180)
			(size 0.5 0.5)
			(layers "F.Cu" "F.Mask" "F.Paste")
			(net 197 "unconnected-(U9D-GPIO_1-PadW41)")
			(pinfunction "GPIO_1")
			(pintype "passive+no_connect")
		)
		(pad "Y2" smd circle
			(at -9.75 6.485 180)
			(size 0.5 0.5)
			(layers "F.Cu" "F.Mask" "F.Paste")
			(net 28 "GND")
			(pinfunction "VSS_S")
			(pintype "power_in")
		)
		(pad "Y4" smd circle
			(at -8.75 6.485 180)
			(size 0.5 0.5)
			(layers "F.Cu" "F.Mask" "F.Paste")
			(net 28 "GND")
			(pinfunction "VSSA")
			(pintype "passive")
		)
		(pad "Y6" smd circle
			(at -7.75 6.485 180)
			(size 0.5 0.5)
			(layers "F.Cu" "F.Mask" "F.Paste")
			(net 28 "GND")
			(pinfunction "VSSA")
			(pintype "passive")
		)
		(pad "Y8" smd circle
			(at -6.75 6.485 180)
			(size 0.5 0.5)
			(layers "F.Cu" "F.Mask" "F.Paste")
			(net 28 "GND")
			(pinfunction "VSSA")
			(pintype "passive")
		)
		(pad "Y10" smd circle
			(at -5.75 6.485 180)
			(size 0.5 0.5)
			(layers "F.Cu" "F.Mask" "F.Paste")
			(net 3 "/X710-AT2 PCIe/RBIAS")
			(pinfunction "RBIAS")
			(pintype "passive")
		)
		(pad "Y12" smd circle
			(at -4.75 6.485 180)
			(size 0.5 0.5)
			(layers "F.Cu" "F.Mask" "F.Paste")
			(net 2 "/X710-AT2 PCIe/RSENSE")
			(pinfunction "RSENSE")
			(pintype "passive")
		)
		(pad "Y14" smd circle
			(at -3.75 6.485 180)
			(size 0.5 0.5)
			(layers "F.Cu" "F.Mask" "F.Paste")
			(net 28 "GND")
			(pinfunction "VSSA")
			(pintype "passive")
		)
		(pad "Y16" smd circle
			(at -2.75 6.485 180)
			(size 0.5 0.5)
			(layers "F.Cu" "F.Mask" "F.Paste")
			(net 121 "/X710-AT2 RSVD/DEBUG_Y16")
			(pinfunction "DEBUG_Y16")
			(pintype "passive")
		)
		(pad "Y18" smd circle
			(at -1.75 6.485 180)
			(size 0.5 0.5)
			(layers "F.Cu" "F.Mask" "F.Paste")
			(net 128 "/X710-AT2 RSVD/RSVDY18_VSS")
			(pinfunction "RSVDY18_VSS")
			(pintype "passive")
		)
		(pad "Y20" smd circle
			(at -0.75 6.485 180)
			(size 0.5 0.5)
			(layers "F.Cu" "F.Mask" "F.Paste")
			(net 119 "/X710-AT2 RSVD/DEBUG_Y20")
			(pinfunction "DEBUG_Y20")
			(pintype "passive")
		)
		(pad "Y22" smd circle
			(at 0.25 6.485 180)
			(size 0.5 0.5)
			(layers "F.Cu" "F.Mask" "F.Paste")
			(net 123 "/X710-AT2 RSVD/RSVDY22_VSS")
			(pinfunction "RSVDY22_VSS")
			(pintype "passive")
		)
		(pad "Y24" smd circle
			(at 1.25 6.485 180)
			(size 0.5 0.5)
			(layers "F.Cu" "F.Mask" "F.Paste")
			(net 122 "/X710-AT2 RSVD/RSVDY24_VSS")
			(pinfunction "RSVDY24_VSS")
			(pintype "passive")
		)
		(pad "Y26" smd circle
			(at 2.25 6.485 180)
			(size 0.5 0.5)
			(layers "F.Cu" "F.Mask" "F.Paste")
			(net 28 "GND")
			(pinfunction "VSSA")
			(pintype "passive")
		)
		(pad "Y28" smd circle
			(at 3.25 6.485 180)
			(size 0.5 0.5)
			(layers "F.Cu" "F.Mask" "F.Paste")
			(net 28 "GND")
			(pinfunction "VSSA")
			(pintype "passive")
		)
		(pad "Y30" smd circle
			(at 4.25 6.485 180)
			(size 0.5 0.5)
			(layers "F.Cu" "F.Mask" "F.Paste")
			(net 274 "unconnected-(U9A-PER_5_P-PadY30)")
			(pinfunction "PER_5_P")
			(pintype "input+no_connect")
		)
		(pad "Y32" smd circle
			(at 5.25 6.485 180)
			(size 0.5 0.5)
			(layers "F.Cu" "F.Mask" "F.Paste")
			(net 28 "GND")
			(pinfunction "VSSA")
			(pintype "passive")
		)
		(pad "Y34" smd circle
			(at 6.25 6.485 180)
			(size 0.5 0.5)
			(layers "F.Cu" "F.Mask" "F.Paste")
			(net 277 "unconnected-(U9A-PER_6_P-PadY34)")
			(pinfunction "PER_6_P")
			(pintype "input+no_connect")
		)
		(pad "Y36" smd circle
			(at 7.25 6.485 180)
			(size 0.5 0.5)
			(layers "F.Cu" "F.Mask" "F.Paste")
			(net 28 "GND")
			(pinfunction "VSSA")
			(pintype "passive")
		)
		(pad "Y38" smd circle
			(at 8.25 6.485 180)
			(size 0.5 0.5)
			(layers "F.Cu" "F.Mask" "F.Paste")
			(net 359 "unconnected-(U9A-PER_7_P-PadY38)")
			(pinfunction "PER_7_P")
			(pintype "input+no_connect")
		)
		(pad "Y40" smd circle
			(at 9.25 6.485 180)
			(size 0.5 0.5)
			(layers "F.Cu" "F.Mask" "F.Paste")
			(net 28 "GND")
			(pinfunction "VSSA")
			(pintype "passive")
		)
		(pad "Y42" smd circle
			(at 10.25 6.485 180)
			(size 0.5 0.5)
			(layers "F.Cu" "F.Mask" "F.Paste")
			(net 86 "/2xRJ45/~{P1_LINK_LESS_THAN_10G}")
			(pinfunction "GPIO_2")
			(pintype "tri_state")
		)
	)
	(footprint "antmicro-footprints:R_0402_1005Metric"
		(layer "F.Cu")
		(at 54.099998 92.849999 -90)
		(descr "Resistor SMD 0402")
		(tags "resistor SMD 0402")
		(property "Reference" "R32"
			(at -1.059999 3.019998 90)
			(layer "F.SilkS")
			(effects
				(font
					(size 0.7 0.7)
					(thickness 0.15)
				)
				(justify right top)
			)
		)
		(property "Value" "R_30k_0402"
			(at -1.011843 1.772046 90)
			(layer "F.Fab")
			(hide yes)
			(effects
				(font
					(size 0.7 0.7)
					(thickness 0.15)
				)
				(justify right top)
			)
		)
		(property "Datasheet" "https://www.bourns.com/docs/product-datasheets/cr.pdf"
			(at 0 0 90)
			(layer "F.Fab")
			(hide yes)
			(effects
				(font
					(size 1.27 1.27)
					(thickness 0.15)
				)
			)
		)
		(property "Description" "SMD Chip Resistor, 30 kohm, ± 1%, 63 mW, 0402 [1005 Metric], Thick Film, General Purpose"
			(at 0 0 90)
			(layer "F.Fab")
			(hide yes)
			(effects
				(font
					(size 1.27 1.27)
					(thickness 0.15)
				)
			)
		)
		(property "MPN" "CR0402-FX-3002GLF"
			(at 0 0 270)
			(unlocked yes)
			(layer "F.Fab")
			(hide yes)
			(effects
				(font
					(size 1 1)
					(thickness 0.15)
				)
			)
		)
		(property "Manufacturer" "Bourns"
			(at 0 0 270)
			(unlocked yes)
			(layer "F.Fab")
			(hide yes)
			(effects
				(font
					(size 1 1)
					(thickness 0.15)
				)
			)
		)
		(property "License" "Apache-2.0"
			(at 0 0 270)
			(unlocked yes)
			(layer "F.Fab")
			(hide yes)
			(effects
				(font
					(size 1 1)
					(thickness 0.15)
				)
			)
		)
		(property "Author" "Antmicro"
			(at 0 0 270)
			(unlocked yes)
			(layer "F.Fab")
			(hide yes)
			(effects
				(font
					(size 1 1)
					(thickness 0.15)
				)
			)
		)
		(property "Val" "30k"
			(at 0 0 270)
			(unlocked yes)
			(layer "F.Fab")
			(hide yes)
			(effects
				(font
					(size 1 1)
					(thickness 0.15)
				)
			)
		)
		(property "Tolerance" "1%"
			(at 0 0 270)
			(unlocked yes)
			(layer "F.Fab")
			(hide yes)
			(effects
				(font
					(size 1 1)
					(thickness 0.15)
				)
			)
		)
		(sheetname "/Power/")
		(sheetfile "power.kicad_sch")
		(attr smd)
		(fp_rect
			(start -0.925 -0.47)
			(end 0.925 0.47)
			(stroke
				(width 0.05)
				(type default)
			)
			(fill no)
			(layer "F.CrtYd")
		)
		(fp_rect
			(start -0.5 -0.25)
			(end 0.5 0.25)
			(stroke
				(width 0.15)
				(type solid)
			)
			(fill no)
			(layer "F.Fab")
		)
		(pad "1" smd roundrect
			(at -0.48 0 270)
			(size 0.59 0.64)
			(layers "F.Cu" "F.Mask" "F.Paste")
			(roundrect_rratio 0.25)
			(net 28 "GND")
			(pintype "passive")
		)
		(pad "2" smd roundrect
			(at 0.48 0 270)
			(size 0.59 0.64)
			(layers "F.Cu" "F.Mask" "F.Paste")
			(roundrect_rratio 0.25)
			(net 331 "/Power/DVDD_FB")
			(pintype "passive")
		)
	)
	(footprint "antmicro-footprints:C_0603_1608Metric_EIA"
		(layer "F.Cu")
		(at 63.199999 100.850001 180)
		(descr "Capacitor SMD 0603, IPC-7351 Density Level A")
		(tags "Capacitor 0603")
		(property "Reference" "C26"
			(at -2.050001 -0.659999 0)
			(layer "F.SilkS")
			(effects
				(font
					(size 0.7 0.7)
					(thickness 0.15)
				)
				(justify right top)
			)
		)
		(property "Value" "C_22u_16V_0603"
			(at -1.42757 1.770288 0)
			(layer "F.Fab")
			(hide yes)
			(effects
				(font
					(size 0.7 0.7)
					(thickness 0.15)
				)
				(justify right top)
			)
		)
		(property "Datasheet" "https://product.samsungsem.com/mlcc/CL10A226MO7JZN.do"
			(at 0 0 0)
			(layer "F.Fab")
			(hide yes)
			(effects
				(font
					(size 1.27 1.27)
					(thickness 0.15)
				)
			)
		)
		(property "Description" "SMD Multilayer Ceramic Capacitor"
			(at 0 0 0)
			(layer "F.Fab")
			(hide yes)
			(effects
				(font
					(size 1.27 1.27)
					(thickness 0.15)
				)
			)
		)
		(property "MPN" "CL10A226MO7JZNC"
			(at 0 0 180)
			(unlocked yes)
			(layer "F.Fab")
			(hide yes)
			(effects
				(font
					(size 1 1)
					(thickness 0.15)
				)
			)
		)
		(property "Manufacturer" "Samsung Electro-Mechanics"
			(at 0 0 180)
			(unlocked yes)
			(layer "F.Fab")
			(hide yes)
			(effects
				(font
					(size 1 1)
					(thickness 0.15)
				)
			)
		)
		(property "License" "Apache-2.0"
			(at 0 0 180)
			(unlocked yes)
			(layer "F.Fab")
			(hide yes)
			(effects
				(font
					(size 1 1)
					(thickness 0.15)
				)
			)
		)
		(property "Author" "Antmicro"
			(at 0 0 180)
			(unlocked yes)
			(layer "F.Fab")
			(hide yes)
			(effects
				(font
					(size 1 1)
					(thickness 0.15)
				)
			)
		)
		(property "Val" "22u"
			(at 0 0 180)
			(unlocked yes)
			(layer "F.Fab")
			(hide yes)
			(effects
				(font
					(size 1 1)
					(thickness 0.15)
				)
			)
		)
		(property "Voltage" "16V"
			(at 0 0 180)
			(unlocked yes)
			(layer "F.Fab")
			(hide yes)
			(effects
				(font
					(size 1 1)
					(thickness 0.15)
				)
			)
		)
		(property "Dielectric" ""
			(at 0 0 180)
			(unlocked yes)
			(layer "F.Fab")
			(hide yes)
			(effects
				(font
					(size 1 1)
					(thickness 0.15)
				)
			)
		)
		(property "Public" "False"
			(at 0 0 180)
			(unlocked yes)
			(layer "F.Fab")
			(hide yes)
			(effects
				(font
					(size 1 1)
					(thickness 0.15)
				)
			)
		)
		(sheetname "/Power/")
		(sheetfile "power.kicad_sch")
		(attr smd)
		(fp_line
			(start -0.15 0.55)
			(end 0.15 0.55)
			(stroke
				(width 0.15)
				(type solid)
			)
			(layer "F.SilkS")
		)
		(fp_line
			(start -0.15 -0.55)
			(end 0.15 -0.55)
			(stroke
				(width 0.15)
				(type solid)
			)
			(layer "F.SilkS")
		)
		(fp_rect
			(start -1.25 -0.65)
			(end 1.25 0.65)
			(stroke
				(width 0.05)
				(type solid)
			)
			(fill no)
			(layer "F.CrtYd")
		)
		(fp_rect
			(start -0.8 -0.45)
			(end 0.8 0.45)
			(stroke
				(width 0.15)
				(type solid)
			)
			(fill no)
			(layer "F.Fab")
		)
		(pad "1" smd roundrect
			(at -0.7 0 180)
			(size 0.8 1.1)
			(layers "F.Cu" "F.Mask" "F.Paste")
			(roundrect_rratio 0.2)
			(net 28 "GND")
			(pintype "passive")
		)
		(pad "2" smd roundrect
			(at 0.7 0 180)
			(size 0.8 1.1)
			(layers "F.Cu" "F.Mask" "F.Paste")
			(roundrect_rratio 0.2)
			(net 310 "/Power/+1V88_OUT")
			(pintype "passive")
		)
	)
	(footprint "antmicro-footprints:C_0603_1608Metric_EIA"
		(layer "F.Cu")
		(at 63.199998 93.15 180)
		(descr "Capacitor SMD 0603, IPC-7351 Density Level A")
		(tags "Capacitor 0603")
		(property "Reference" "C208"
			(at -2.610002 -0.73 0)
			(layer "F.SilkS")
			(effects
				(font
					(size 0.7 0.7)
					(thickness 0.15)
				)
				(justify right top)
			)
		)
		(property "Value" "C_22u_16V_0603"
			(at -1.42757 1.770288 0)
			(layer "F.Fab")
			(hide yes)
			(effects
				(font
					(size 0.7 0.7)
					(thickness 0.15)
				)
				(justify right top)
			)
		)
		(property "Datasheet" "https://product.samsungsem.com/mlcc/CL10A226MO7JZN.do"
			(at 0 0 0)
			(layer "F.Fab")
			(hide yes)
			(effects
				(font
					(size 1.27 1.27)
					(thickness 0.15)
				)
			)
		)
		(property "Description" "SMD Multilayer Ceramic Capacitor"
			(at 0 0 0)
			(layer "F.Fab")
			(hide yes)
			(effects
				(font
					(size 1.27 1.27)
					(thickness 0.15)
				)
			)
		)
		(property "MPN" "CL10A226MO7JZNC"
			(at 0 0 180)
			(unlocked yes)
			(layer "F.Fab")
			(hide yes)
			(effects
				(font
					(size 1 1)
					(thickness 0.15)
				)
			)
		)
		(property "Manufacturer" "Samsung Electro-Mechanics"
			(at 0 0 180)
			(unlocked yes)
			(layer "F.Fab")
			(hide yes)
			(effects
				(font
					(size 1 1)
					(thickness 0.15)
				)
			)
		)
		(property "License" "Apache-2.0"
			(at 0 0 180)
			(unlocked yes)
			(layer "F.Fab")
			(hide yes)
			(effects
				(font
					(size 1 1)
					(thickness 0.15)
				)
			)
		)
		(property "Author" "Antmicro"
			(at 0 0 180)
			(unlocked yes)
			(layer "F.Fab")
			(hide yes)
			(effects
				(font
					(size 1 1)
					(thickness 0.15)
				)
			)
		)
		(property "Val" "22u"
			(at 0 0 180)
			(unlocked yes)
			(layer "F.Fab")
			(hide yes)
			(effects
				(font
					(size 1 1)
					(thickness 0.15)
				)
			)
		)
		(property "Voltage" "16V"
			(at 0 0 180)
			(unlocked yes)
			(layer "F.Fab")
			(hide yes)
			(effects
				(font
					(size 1 1)
					(thickness 0.15)
				)
			)
		)
		(property "Dielectric" ""
			(at 0 0 180)
			(unlocked yes)
			(layer "F.Fab")
			(hide yes)
			(effects
				(font
					(size 1 1)
					(thickness 0.15)
				)
			)
		)
		(property "Public" "False"
			(at 0 0 180)
			(unlocked yes)
			(layer "F.Fab")
			(hide yes)
			(effects
				(font
					(size 1 1)
					(thickness 0.15)
				)
			)
		)
		(sheetname "/Power/")
		(sheetfile "power.kicad_sch")
		(attr smd)
		(fp_line
			(start -0.15 0.55)
			(end 0.15 0.55)
			(stroke
				(width 0.15)
				(type solid)
			)
			(layer "F.SilkS")
		)
		(fp_line
			(start -0.15 -0.55)
			(end 0.15 -0.55)
			(stroke
				(width 0.15)
				(type solid)
			)
			(layer "F.SilkS")
		)
		(fp_rect
			(start -1.25 -0.65)
			(end 1.25 0.65)
			(stroke
				(width 0.05)
				(type solid)
			)
			(fill no)
			(layer "F.CrtYd")
		)
		(fp_rect
			(start -0.8 -0.45)
			(end 0.8 0.45)
			(stroke
				(width 0.15)
				(type solid)
			)
			(fill no)
			(layer "F.Fab")
		)
		(pad "1" smd roundrect
			(at -0.7 0 180)
			(size 0.8 1.1)
			(layers "F.Cu" "F.Mask" "F.Paste")
			(roundrect_rratio 0.2)
			(net 28 "GND")
			(pintype "passive")
		)
		(pad "2" smd roundrect
			(at 0.7 0 180)
			(size 0.8 1.1)
			(layers "F.Cu" "F.Mask" "F.Paste")
			(roundrect_rratio 0.2)
			(net 311 "/Power/+DVDD_OUT")
			(pintype "passive")
		)
	)
	(footprint "antmicro-footprints:USB-C_Receptacle_GCT_USB4105-GF-A"
		(layer "F.Cu")
		(at 82.9 52.704 180)
		(property "Reference" "J2"
			(at -5.24 -2.328 90)
			(layer "F.SilkS")
			(effects
				(font
					(size 0.7 0.7)
					(thickness 0.15)
				)
				(justify right top)
			)
		)
		(property "Value" "USB-C_GCT_USB4105-GF-A"
			(at 0 5 0)
			(layer "F.Fab")
			(hide yes)
			(effects
				(font
					(size 0.7 0.7)
					(thickness 0.15)
				)
				(justify right top)
			)
		)
		(property "Datasheet" "https://gct.co/files/drawings/usb4105.pdf"
			(at 0 0 0)
			(layer "F.Fab")
			(hide yes)
			(effects
				(font
					(size 1.27 1.27)
					(thickness 0.15)
				)
			)
		)
		(property "Description" "USB-C (USB TYPE-C) USB 2.0 Receptacle Connector 24 (16+8 Dummy) Position Surface Mount, Right Angle"
			(at 0 0 0)
			(layer "F.Fab")
			(hide yes)
			(effects
				(font
					(size 1.27 1.27)
					(thickness 0.15)
				)
			)
		)
		(property "Manufacturer" "GCT"
			(at 0 0 180)
			(unlocked yes)
			(layer "F.Fab")
			(hide yes)
			(effects
				(font
					(size 1 1)
					(thickness 0.15)
				)
			)
		)
		(property "MPN" "USB4105-GF-A"
			(at 0 0 180)
			(unlocked yes)
			(layer "F.Fab")
			(hide yes)
			(effects
				(font
					(size 1 1)
					(thickness 0.15)
				)
			)
		)
		(property "Author" "Antmicro"
			(at 0 0 180)
			(unlocked yes)
			(layer "F.Fab")
			(hide yes)
			(effects
				(font
					(size 1 1)
					(thickness 0.15)
				)
			)
		)
		(property "License" "Apache-2.0"
			(at 0 0 180)
			(unlocked yes)
			(layer "F.Fab")
			(hide yes)
			(effects
				(font
					(size 1 1)
					(thickness 0.15)
				)
			)
		)
		(sheetname "/Power/")
		(sheetfile "power.kicad_sch")
		(attr smd)
		(fp_line
			(start 4.788 3.854)
			(end 4.788 2.575)
			(stroke
				(width 0.15)
				(type solid)
			)
			(layer "F.SilkS")
		)
		(fp_line
			(start 4.788 -1.395)
			(end 4.788 -0.145)
			(stroke
				(width 0.15)
				(type solid)
			)
			(layer "F.SilkS")
		)
		(fp_line
			(start -4.79 3.854)
			(end 4.788 3.854)
			(stroke
				(width 0.15)
				(type solid)
			)
			(layer "F.SilkS")
		)
		(fp_line
			(start -4.79 2.575)
			(end -4.79 3.854)
			(stroke
				(width 0.15)
				(type solid)
			)
			(layer "F.SilkS")
		)
		(fp_line
			(start -4.79 -1.395)
			(end -4.79 -0.145)
			(stroke
				(width 0.15)
				(type solid)
			)
			(layer "F.SilkS")
		)
		(fp_circle
			(center -3.8 -4.27071)
			(end -3.75 -4.22071)
			(stroke
				(width 0.15)
				(type solid)
			)
			(fill yes)
			(layer "F.SilkS")
		)
		(fp_rect
			(start -5.1 -4.4)
			(end 5.1 3.9)
			(stroke
				(width 0.05)
				(type solid)
			)
			(fill no)
			(layer "F.CrtYd")
		)
		(fp_line
			(start 4.788 3.854)
			(end -4.79 3.854)
			(stroke
				(width 0.15)
				(type solid)
			)
			(layer "F.Fab")
		)
		(fp_line
			(start 4.788 -3.676)
			(end 4.788 3.854)
			(stroke
				(width 0.15)
				(type solid)
			)
			(layer "F.Fab")
		)
		(fp_line
			(start -4.702 3.854)
			(end 4.788 3.854)
			(stroke
				(width 0.15)
				(type solid)
			)
			(layer "F.Fab")
		)
		(fp_line
			(start -4.79 3.854)
			(end -4.79 -3.676)
			(stroke
				(width 0.15)
				(type solid)
			)
			(layer "F.Fab")
		)
		(fp_line
			(start -4.79 -3.676)
			(end 4.788 -3.676)
			(stroke
				(width 0.15)
				(type solid)
			)
			(layer "F.Fab")
		)
		(pad "" np_thru_hole circle
			(at -2.891 -2.426 180)
			(size 0.65 0.65)
			(drill 0.65)
			(layers "*.Cu" "*.Mask")
		)
		(pad "" np_thru_hole circle
			(at 2.89 -2.426 180)
			(size 0.65 0.65)
			(drill 0.65)
			(layers "*.Cu" "*.Mask")
		)
		(pad "A1" smd roundrect
			(at -3.202 -3.5 180)
			(size 0.6 1.15)
			(layers "F.Cu" "F.Mask" "F.Paste")
			(roundrect_rratio 0.25)
			(net 28 "GND")
			(pinfunction "GND")
			(pintype "power_in")
		)
		(pad "A4" smd roundrect
			(at -2.4 -3.5 180)
			(size 0.6 1.15)
			(layers "F.Cu" "F.Mask" "F.Paste")
			(roundrect_rratio 0.25)
			(net 351 "/Power/+5V_USB")
			(pinfunction "VBUS")
			(pintype "power_in")
		)
		(pad "A5" smd roundrect
			(at -1.25 -3.5 180)
			(size 0.3 1.15)
			(layers "F.Cu" "F.Mask" "F.Paste")
			(roundrect_rratio 0.25)
			(net 357 "/Power/CC1")
			(pinfunction "CC_{1}")
			(pintype "bidirectional")
		)
		(pad "A6" smd roundrect
			(at -0.25 -3.5 180)
			(size 0.3 1.15)
			(layers "F.Cu" "F.Mask" "F.Paste")
			(roundrect_rratio 0.25)
			(net 146 "unconnected-(J2-D_{A}+-PadA6)")
			(pinfunction "D_{A}+")
			(pintype "bidirectional+no_connect")
		)
		(pad "A7" smd roundrect
			(at 0.248 -3.5 180)
			(size 0.3 1.15)
			(layers "F.Cu" "F.Mask" "F.Paste")
			(roundrect_rratio 0.25)
			(net 144 "unconnected-(J2-D_{A}--PadA7)")
			(pinfunction "D_{A}-")
			(pintype "bidirectional+no_connect")
		)
		(pad "A8" smd roundrect
			(at 1.249 -3.5 180)
			(size 0.3 1.15)
			(layers "F.Cu" "F.Mask" "F.Paste")
			(roundrect_rratio 0.25)
			(net 93 "unconnected-(J2-SBU_{1}-PadA8)")
			(pinfunction "SBU_{1}")
			(pintype "bidirectional+no_connect")
		)
		(pad "A9" smd roundrect
			(at 2.398 -3.5 180)
			(size 0.6 1.15)
			(layers "F.Cu" "F.Mask" "F.Paste")
			(roundrect_rratio 0.25)
			(net 351 "/Power/+5V_USB")
			(pinfunction "VBUS")
			(pintype "passive")
		)
		(pad "A12" smd roundrect
			(at 3.2 -3.5 180)
			(size 0.6 1.15)
			(layers "F.Cu" "F.Mask" "F.Paste")
			(roundrect_rratio 0.25)
			(net 28 "GND")
			(pinfunction "GND")
			(pintype "passive")
		)
		(pad "B1" smd roundrect
			(at 3.2 -3.5 180)
			(size 0.6 1.15)
			(layers "F.Cu" "F.Mask" "F.Paste")
			(roundrect_rratio 0.25)
			(net 28 "GND")
			(pinfunction "GND")
			(pintype "passive")
		)
		(pad "B4" smd roundrect
			(at 2.398 -3.5 180)
			(size 0.6 1.15)
			(layers "F.Cu" "F.Mask" "F.Paste")
			(roundrect_rratio 0.25)
			(net 351 "/Power/+5V_USB")
			(pinfunction "VBUS")
			(pintype "passive")
		)
		(pad "B5" smd roundrect
			(at 1.749 -3.5 180)
			(size 0.3 1.15)
			(layers "F.Cu" "F.Mask" "F.Paste")
			(roundrect_rratio 0.25)
			(net 356 "/Power/CC2")
			(pinfunction "CC_{2}")
			(pintype "bidirectional")
		)
		(pad "B6" smd roundrect
			(at 0.748 -3.5 180)
			(size 0.3 1.15)
			(layers "F.Cu" "F.Mask" "F.Paste")
			(roundrect_rratio 0.25)
			(net 138 "unconnected-(J2-D_{B}+-PadB6)")
			(pinfunction "D_{B}+")
			(pintype "bidirectional+no_connect")
		)
		(pad "B7" smd roundrect
			(at -0.75 -3.5 180)
			(size 0.3 1.15)
			(layers "F.Cu" "F.Mask" "F.Paste")
			(roundrect_rratio 0.25)
			(net 92 "unconnected-(J2-D_{B}--PadB7)")
			(pinfunction "D_{B}-")
			(pintype "bidirectional+no_connect")
		)
		(pad "B8" smd roundrect
			(at -1.75 -3.5 180)
			(size 0.3 1.15)
			(layers "F.Cu" "F.Mask" "F.Paste")
			(roundrect_rratio 0.25)
			(net 145 "unconnected-(J2-SBU_{2}-PadB8)")
			(pinfunction "SBU_{2}")
			(pintype "bidirectional+no_connect")
		)
		(pad "B9" smd roundrect
			(at -2.4 -3.5 180)
			(size 0.6 1.15)
			(layers "F.Cu" "F.Mask" "F.Paste")
			(roundrect_rratio 0.25)
			(net 351 "/Power/+5V_USB")
			(pinfunction "VBUS")
			(pintype "passive")
		)
		(pad "B12" smd roundrect
			(at -3.202 -3.5 180)
			(size 0.6 1.15)
			(layers "F.Cu" "F.Mask" "F.Paste")
			(roundrect_rratio 0.25)
			(net 28 "GND")
			(pinfunction "GND")
			(pintype "passive")
		)
		(pad "SH" thru_hole oval
			(at -4.321 -2.926 180)
			(size 1.05 2.1)
			(drill oval 0.6 1.7)
			(layers "*.Cu" "*.Mask")
			(remove_unused_layers no)
			(net 43 "Net-(C37-Pad2)")
			(pinfunction "SH")
			(pintype "passive")
		)
		(pad "SH" thru_hole oval
			(at -4.321 1.255 180)
			(size 1 2)
			(drill oval 0.6 1.4)
			(layers "*.Cu" "*.Mask")
			(remove_unused_layers no)
			(net 43 "Net-(C37-Pad2)")
			(pinfunction "SH")
			(pintype "passive")
		)
		(pad "SH" thru_hole oval
			(at 4.32 -2.926 180)
			(size 1.05 2.1)
			(drill oval 0.6 1.7)
			(layers "*.Cu" "*.Mask")
			(remove_unused_layers no)
			(net 43 "Net-(C37-Pad2)")
			(pinfunction "SH")
			(pintype "passive")
		)
		(pad "SH" thru_hole oval
			(at 4.32 1.255 180)
			(size 1 2)
			(drill oval 0.6 1.4)
			(layers "*.Cu" "*.Mask")
			(remove_unused_layers no)
			(net 43 "Net-(C37-Pad2)")
			(pinfunction "SH")
			(pintype "passive")
		)
	)
	(footprint "antmicro-footprints:C_0603_1608Metric"
		(layer "F.Cu")
		(at 72.45 100.95 -90)
		(descr "Capacitor SMD 0603")
		(tags "capacitor 0603")
		(property "Reference" "C180"
			(at -1.39 -0.74 90)
			(layer "F.SilkS")
			(effects
				(font
					(size 0.7 0.7)
					(thickness 0.15)
				)
				(justify right top)
			)
		)
		(property "Value" "C_47u_0603"
			(at -1.42757 1.770288 90)
			(layer "F.Fab")
			(hide yes)
			(effects
				(font
					(size 0.7 0.7)
					(thickness 0.15)
				)
				(justify right top)
			)
		)
		(property "Datasheet" "https://www.murata.com/products/productdetail?partno=GRM188R60J476ME15%23"
			(at 0 0 90)
			(layer "F.Fab")
			(hide yes)
			(effects
				(font
					(size 1.27 1.27)
					(thickness 0.15)
				)
			)
		)
		(property "Description" "SMD Multilayer Ceramic Capacitor, 47 µF, 6.3 V, 0603 [1608 Metric], ± 20%, X5R, GRM Series"
			(at 0 0 90)
			(layer "F.Fab")
			(hide yes)
			(effects
				(font
					(size 1.27 1.27)
					(thickness 0.15)
				)
			)
		)
		(property "MPN" "GRM188R60J476ME15D"
			(at 0 0 270)
			(unlocked yes)
			(layer "F.Fab")
			(hide yes)
			(effects
				(font
					(size 1 1)
					(thickness 0.15)
				)
			)
		)
		(property "Manufacturer" "Murata"
			(at 0 0 270)
			(unlocked yes)
			(layer "F.Fab")
			(hide yes)
			(effects
				(font
					(size 1 1)
					(thickness 0.15)
				)
			)
		)
		(property "License" "Apache-2.0"
			(at 0 0 270)
			(unlocked yes)
			(layer "F.Fab")
			(hide yes)
			(effects
				(font
					(size 1 1)
					(thickness 0.15)
				)
			)
		)
		(property "Author" "Antmicro"
			(at 0 0 270)
			(unlocked yes)
			(layer "F.Fab")
			(hide yes)
			(effects
				(font
					(size 1 1)
					(thickness 0.15)
				)
			)
		)
		(property "Val" "47u"
			(at 0 0 270)
			(unlocked yes)
			(layer "F.Fab")
			(hide yes)
			(effects
				(font
					(size 1 1)
					(thickness 0.15)
				)
			)
		)
		(property "Voltage" ""
			(at 0 0 270)
			(unlocked yes)
			(layer "F.Fab")
			(hide yes)
			(effects
				(font
					(size 1 1)
					(thickness 0.15)
				)
			)
		)
		(property "Dielectric" ""
			(at 0 0 270)
			(unlocked yes)
			(layer "F.Fab")
			(hide yes)
			(effects
				(font
					(size 1 1)
					(thickness 0.15)
				)
			)
		)
		(sheetname "/X710-AT2 power/")
		(sheetfile "x710-at2-power.kicad_sch")
		(attr smd)
		(fp_line
			(start -0.15 0.4)
			(end 0.15 0.4)
			(stroke
				(width 0.15)
				(type solid)
			)
			(layer "F.SilkS")
		)
		(fp_line
			(start -0.15 -0.4)
			(end 0.15 -0.4)
			(stroke
				(width 0.15)
				(type solid)
			)
			(layer "F.SilkS")
		)
		(fp_rect
			(start -1.25 -0.65)
			(end 1.25 0.65)
			(stroke
				(width 0.05)
				(type solid)
			)
			(fill no)
			(layer "F.CrtYd")
		)
		(fp_rect
			(start -0.8 -0.4)
			(end 0.8 0.4)
			(stroke
				(width 0.15)
				(type solid)
			)
			(fill no)
			(layer "F.Fab")
		)
		(pad "1" smd roundrect
			(at -0.7 0 270)
			(size 0.8 1)
			(layers "F.Cu" "F.Mask" "F.Paste")
			(roundrect_rratio 0.2)
			(net 28 "GND")
			(pintype "passive")
		)
		(pad "2" smd roundrect
			(at 0.7 0 270)
			(size 0.8 1)
			(layers "F.Cu" "F.Mask" "F.Paste")
			(roundrect_rratio 0.2)
			(net 12 "XFI_VDD")
			(pintype "passive")
		)
	)
	(footprint "antmicro-footprints:C_0603_1608Metric"
		(layer "F.Cu")
		(at 72.45 98.3 90)
		(descr "Capacitor SMD 0603")
		(tags "capacitor 0603")
		(property "Reference" "C140"
			(at 1.08 0.32 90)
			(layer "F.SilkS")
			(effects
				(font
					(size 0.7 0.7)
					(thickness 0.15)
				)
				(justify left bottom)
			)
		)
		(property "Value" "C_10u_10V_X7R_0603"
			(at -1.42757 1.770288 90)
			(layer "F.Fab")
			(hide yes)
			(effects
				(font
					(size 0.7 0.7)
					(thickness 0.15)
				)
				(justify left bottom)
			)
		)
		(property "Datasheet" "https://www.murata.com/products/productdetail?partno=GRM188Z71A106KA73%23"
			(at 0 0 90)
			(layer "F.Fab")
			(hide yes)
			(effects
				(font
					(size 1.27 1.27)
					(thickness 0.15)
				)
			)
		)
		(property "Description" "SMD Multilayer Ceramic Capacitor,  10µF, 10V, 0603, ±10%, X7R"
			(at 0 0 90)
			(layer "F.Fab")
			(hide yes)
			(effects
				(font
					(size 1.27 1.27)
					(thickness 0.15)
				)
			)
		)
		(property "MPN" "GRM188Z71A106KA73D"
			(at 0 0 90)
			(unlocked yes)
			(layer "F.Fab")
			(hide yes)
			(effects
				(font
					(size 1 1)
					(thickness 0.15)
				)
			)
		)
		(property "Val" "10u"
			(at 0 0 90)
			(unlocked yes)
			(layer "F.Fab")
			(hide yes)
			(effects
				(font
					(size 1 1)
					(thickness 0.15)
				)
			)
		)
		(property "Voltage" "10V"
			(at 0 0 90)
			(unlocked yes)
			(layer "F.Fab")
			(hide yes)
			(effects
				(font
					(size 1 1)
					(thickness 0.15)
				)
			)
		)
		(property "Dielectric" "X7R"
			(at 0 0 90)
			(unlocked yes)
			(layer "F.Fab")
			(hide yes)
			(effects
				(font
					(size 1 1)
					(thickness 0.15)
				)
			)
		)
		(property "Manufacturer" "Murata"
			(at 0 0 90)
			(unlocked yes)
			(layer "F.Fab")
			(hide yes)
			(effects
				(font
					(size 1 1)
					(thickness 0.15)
				)
			)
		)
		(property "License" "Apache-2.0"
			(at 0 0 90)
			(unlocked yes)
			(layer "F.Fab")
			(hide yes)
			(effects
				(font
					(size 1 1)
					(thickness 0.15)
				)
			)
		)
		(property "Author" "Antmicro"
			(at 0 0 90)
			(unlocked yes)
			(layer "F.Fab")
			(hide yes)
			(effects
				(font
					(size 1 1)
					(thickness 0.15)
				)
			)
		)
		(sheetname "/X710-AT2 power/")
		(sheetfile "x710-at2-power.kicad_sch")
		(attr smd)
		(fp_line
			(start -0.15 -0.4)
			(end 0.15 -0.4)
			(stroke
				(width 0.15)
				(type solid)
			)
			(layer "F.SilkS")
		)
		(fp_line
			(start -0.15 0.4)
			(end 0.15 0.4)
			(stroke
				(width 0.15)
				(type solid)
			)
			(layer "F.SilkS")
		)
		(fp_rect
			(start -1.25 -0.65)
			(end 1.25 0.65)
			(stroke
				(width 0.05)
				(type solid)
			)
			(fill no)
			(layer "F.CrtYd")
		)
		(fp_rect
			(start -0.8 -0.4)
			(end 0.8 0.4)
			(stroke
				(width 0.15)
				(type solid)
			)
			(fill no)
			(layer "F.Fab")
		)
		(pad "1" smd roundrect
			(at -0.7 0 90)
			(size 0.8 1)
			(layers "F.Cu" "F.Mask" "F.Paste")
			(roundrect_rratio 0.2)
			(net 28 "GND")
			(pintype "passive")
		)
		(pad "2" smd roundrect
			(at 0.7 0 90)
			(size 0.8 1)
			(layers "F.Cu" "F.Mask" "F.Paste")
			(roundrect_rratio 0.2)
			(net 10 "AVDDH")
			(pintype "passive")
		)
	)
	(footprint "antmicro-footprints:C_0603_1608Metric_EIA"
		(layer "F.Cu")
		(at 60.649999 84.1)
		(descr "Capacitor SMD 0603, IPC-7351 Density Level A")
		(tags "Capacitor 0603")
		(property "Reference" "C16"
			(at -0.749999 -1.54 0)
			(layer "F.SilkS")
			(effects
				(font
					(size 0.7 0.7)
					(thickness 0.15)
				)
				(justify left bottom)
			)
		)
		(property "Value" "C_22u_16V_0603"
			(at -1.42757 1.770288 0)
			(layer "F.Fab")
			(hide yes)
			(effects
				(font
					(size 0.7 0.7)
					(thickness 0.15)
				)
				(justify left bottom)
			)
		)
		(property "Datasheet" "https://product.samsungsem.com/mlcc/CL10A226MO7JZN.do"
			(at 0 0 0)
			(layer "F.Fab")
			(hide yes)
			(effects
				(font
					(size 1.27 1.27)
					(thickness 0.15)
				)
			)
		)
		(property "Description" "SMD Multilayer Ceramic Capacitor"
			(at 0 0 0)
			(layer "F.Fab")
			(hide yes)
			(effects
				(font
					(size 1.27 1.27)
					(thickness 0.15)
				)
			)
		)
		(property "MPN" "CL10A226MO7JZNC"
			(at 0 0 0)
			(unlocked yes)
			(layer "F.Fab")
			(hide yes)
			(effects
				(font
					(size 1 1)
					(thickness 0.15)
				)
			)
		)
		(property "Manufacturer" "Samsung Electro-Mechanics"
			(at 0 0 0)
			(unlocked yes)
			(layer "F.Fab")
			(hide yes)
			(effects
				(font
					(size 1 1)
					(thickness 0.15)
				)
			)
		)
		(property "License" "Apache-2.0"
			(at 0 0 0)
			(unlocked yes)
			(layer "F.Fab")
			(hide yes)
			(effects
				(font
					(size 1 1)
					(thickness 0.15)
				)
			)
		)
		(property "Author" "Antmicro"
			(at 0 0 0)
			(unlocked yes)
			(layer "F.Fab")
			(hide yes)
			(effects
				(font
					(size 1 1)
					(thickness 0.15)
				)
			)
		)
		(property "Val" "22u"
			(at 0 0 0)
			(unlocked yes)
			(layer "F.Fab")
			(hide yes)
			(effects
				(font
					(size 1 1)
					(thickness 0.15)
				)
			)
		)
		(property "Voltage" "16V"
			(at 0 0 0)
			(unlocked yes)
			(layer "F.Fab")
			(hide yes)
			(effects
				(font
					(size 1 1)
					(thickness 0.15)
				)
			)
		)
		(property "Dielectric" ""
			(at 0 0 0)
			(unlocked yes)
			(layer "F.Fab")
			(hide yes)
			(effects
				(font
					(size 1 1)
					(thickness 0.15)
				)
			)
		)
		(property "Public" "False"
			(at 0 0 0)
			(unlocked yes)
			(layer "F.Fab")
			(hide yes)
			(effects
				(font
					(size 1 1)
					(thickness 0.15)
				)
			)
		)
		(sheetname "/Power/")
		(sheetfile "power.kicad_sch")
		(attr smd)
		(fp_line
			(start -0.15 -0.55)
			(end 0.15 -0.55)
			(stroke
				(width 0.15)
				(type solid)
			)
			(layer "F.SilkS")
		)
		(fp_line
			(start -0.15 0.55)
			(end 0.15 0.55)
			(stroke
				(width 0.15)
				(type solid)
			)
			(layer "F.SilkS")
		)
		(fp_rect
			(start -1.25 -0.65)
			(end 1.25 0.65)
			(stroke
				(width 0.05)
				(type solid)
			)
			(fill no)
			(layer "F.CrtYd")
		)
		(fp_rect
			(start -0.8 -0.45)
			(end 0.8 0.45)
			(stroke
				(width 0.15)
				(type solid)
			)
			(fill no)
			(layer "F.Fab")
		)
		(pad "1" smd roundrect
			(at -0.7 0)
			(size 0.8 1.1)
			(layers "F.Cu" "F.Mask" "F.Paste")
			(roundrect_rratio 0.2)
			(net 28 "GND")
			(pintype "passive")
		)
		(pad "2" smd roundrect
			(at 0.7 0)
			(size 0.8 1.1)
			(layers "F.Cu" "F.Mask" "F.Paste")
			(roundrect_rratio 0.2)
			(net 303 "/Power/+VCCD_OUT")
			(pintype "passive")
		)
	)
	(footprint "antmicro-footprints:R_0402_1005Metric"
		(layer "F.Cu")
		(at 57.15 120.4 180)
		(descr "Resistor SMD 0402")
		(tags "resistor SMD 0402")
		(property "Reference" "R147"
			(at -1.5 -0.772697 0)
			(layer "F.SilkS")
			(effects
				(font
					(size 0.7 0.7)
					(thickness 0.15)
				)
				(justify right top)
			)
		)
		(property "Value" "R_1k_0402"
			(at -1.011843 1.772046 0)
			(layer "F.Fab")
			(hide yes)
			(effects
				(font
					(size 0.7 0.7)
					(thickness 0.15)
				)
				(justify right top)
			)
		)
		(property "Datasheet" "https://www.bourns.com/docs/product-datasheets/cr.pdf"
			(at 0 0 0)
			(layer "F.Fab")
			(hide yes)
			(effects
				(font
					(size 1.27 1.27)
					(thickness 0.15)
				)
			)
		)
		(property "Description" "SMD Chip Resistor, 1 kohm, ± 1%, 63 mW, 0402 [1005 Metric], Thick Film, General Purpose"
			(at 0 0 0)
			(layer "F.Fab")
			(hide yes)
			(effects
				(font
					(size 1.27 1.27)
					(thickness 0.15)
				)
			)
		)
		(property "MPN" "CR0402-FX-1001GLF"
			(at 0 0 180)
			(unlocked yes)
			(layer "F.Fab")
			(hide yes)
			(effects
				(font
					(size 1 1)
					(thickness 0.15)
				)
			)
		)
		(property "Manufacturer" "Bourns"
			(at 0 0 180)
			(unlocked yes)
			(layer "F.Fab")
			(hide yes)
			(effects
				(font
					(size 1 1)
					(thickness 0.15)
				)
			)
		)
		(property "License" "Apache-2.0"
			(at 0 0 180)
			(unlocked yes)
			(layer "F.Fab")
			(hide yes)
			(effects
				(font
					(size 1 1)
					(thickness 0.15)
				)
			)
		)
		(property "Author" "Antmicro"
			(at 0 0 180)
			(unlocked yes)
			(layer "F.Fab")
			(hide yes)
			(effects
				(font
					(size 1 1)
					(thickness 0.15)
				)
			)
		)
		(property "Val" "1k"
			(at 0 0 180)
			(unlocked yes)
			(layer "F.Fab")
			(hide yes)
			(effects
				(font
					(size 1 1)
					(thickness 0.15)
				)
			)
		)
		(property "Tolerance" "1%"
			(at 0 0 180)
			(unlocked yes)
			(layer "F.Fab")
			(hide yes)
			(effects
				(font
					(size 1 1)
					(thickness 0.15)
				)
			)
		)
		(sheetname "/Power/")
		(sheetfile "power.kicad_sch")
		(attr smd)
		(fp_poly
			(pts
				(xy -0.925 -0.47) (xy 0.925 -0.47) (xy 0.925 0.47) (xy -0.925 0.47)
			)
			(stroke
				(width 0.05)
				(type default)
			)
			(fill no)
			(layer "F.CrtYd")
		)
		(fp_poly
			(pts
				(xy -0.5 -0.25) (xy 0.5 -0.25) (xy 0.5 0.25) (xy -0.5 0.25)
			)
			(stroke
				(width 0.15)
				(type solid)
			)
			(fill no)
			(layer "F.Fab")
		)
		(pad "1" smd roundrect
			(at -0.48 0 180)
			(size 0.59 0.64)
			(layers "F.Cu" "F.Mask" "F.Paste")
			(roundrect_rratio 0.25)
			(net 418 "Net-(Q8-C)")
			(pintype "passive")
		)
		(pad "2" smd roundrect
			(at 0.48 0 180)
			(size 0.59 0.64)
			(layers "F.Cu" "F.Mask" "F.Paste")
			(roundrect_rratio 0.25)
			(net 413 "Net-(D19-C)")
			(pintype "passive")
		)
	)
	(footprint "antmicro-footprints:C_0402_1005Metric"
		(layer "F.Cu")
		(at 102 65.285 -90)
		(descr "Capacitor SMD 0402")
		(tags "capacitor SMD 0402")
		(property "Reference" "C193"
			(at 0.792273 -0.399995 270)
			(layer "F.SilkS")
			(effects
				(font
					(size 0.7 0.7)
					(thickness 0.15)
				)
				(justify right bottom)
			)
		)
		(property "Value" "C_220n_16V_0402"
			(at -1.022927 2.155213 270)
			(layer "F.Fab")
			(hide yes)
			(effects
				(font
					(size 0.7 0.7)
					(thickness 0.15)
				)
				(justify left bottom)
			)
		)
		(property "Datasheet" "https://www.murata.com/products/productdetail?partno=GRM155R71C224KA12%23"
			(at 0 0 270)
			(layer "F.Fab")
			(hide yes)
			(effects
				(font
					(size 1.27 1.27)
					(thickness 0.15)
				)
			)
		)
		(property "Description" "SMD Multilayer Ceramic Capacitor, 0.22 µF, 16 V, 0402 [1005 Metric], ± 10%, X7R, GRM Series"
			(at 0 0 270)
			(layer "F.Fab")
			(hide yes)
			(effects
				(font
					(size 1.27 1.27)
					(thickness 0.15)
				)
			)
		)
		(property "MPN" "GRM155R71C224KA12D"
			(at 0 0 270)
			(unlocked yes)
			(layer "F.Fab")
			(hide yes)
			(effects
				(font
					(size 1 1)
					(thickness 0.15)
				)
			)
		)
		(property "Manufacturer" "Murata"
			(at 0 0 270)
			(unlocked yes)
			(layer "F.Fab")
			(hide yes)
			(effects
				(font
					(size 1 1)
					(thickness 0.15)
				)
			)
		)
		(property "License" "Apache-2.0"
			(at 0 0 270)
			(unlocked yes)
			(layer "F.Fab")
			(hide yes)
			(effects
				(font
					(size 1 1)
					(thickness 0.15)
				)
			)
		)
		(property "Author" "Antmicro"
			(at 0 0 270)
			(unlocked yes)
			(layer "F.Fab")
			(hide yes)
			(effects
				(font
					(size 1 1)
					(thickness 0.15)
				)
			)
		)
		(property "Val" "220n"
			(at 0 0 270)
			(unlocked yes)
			(layer "F.Fab")
			(hide yes)
			(effects
				(font
					(size 1 1)
					(thickness 0.15)
				)
			)
		)
		(property "Voltage" "16V"
			(at 0 0 270)
			(unlocked yes)
			(layer "F.Fab")
			(hide yes)
			(effects
				(font
					(size 1 1)
					(thickness 0.15)
				)
			)
		)
		(property "Dielectric" "X7R"
			(at 0 0 270)
			(unlocked yes)
			(layer "F.Fab")
			(hide yes)
			(effects
				(font
					(size 1 1)
					(thickness 0.15)
				)
			)
		)
		(sheetname "/X710-AT2 PCIe/")
		(sheetfile "x710-at2-pcie.kicad_sch")
		(attr smd)
		(fp_rect
			(start -0.925 -0.47)
			(end 0.925 0.47)
			(stroke
				(width 0.05)
				(type default)
			)
			(fill no)
			(layer "F.CrtYd")
		)
		(fp_line
			(start -0.494 0.248)
			(end -0.494 -0.25)
			(stroke
				(width 0.15)
				(type solid)
			)
			(layer "F.Fab")
		)
		(fp_line
			(start 0.504 0.248)
			(end -0.494 0.248)
			(stroke
				(width 0.15)
				(type solid)
			)
			(layer "F.Fab")
		)
		(fp_line
			(start -0.494 -0.25)
			(end 0.504 -0.25)
			(stroke
				(width 0.15)
				(type solid)
			)
			(layer "F.Fab")
		)
		(fp_line
			(start 0.504 -0.25)
			(end 0.504 0.248)
			(stroke
				(width 0.15)
				(type solid)
			)
			(layer "F.Fab")
		)
		(pad "1" smd roundrect
			(at -0.48 0 270)
			(size 0.59 0.64)
			(layers "F.Cu" "F.Mask" "F.Paste")
			(roundrect_rratio 0.25)
			(net 20 "/OCuLink/PCIe_{x4}.TX1-")
			(pintype "passive")
		)
		(pad "2" smd roundrect
			(at 0.48 0 270)
			(size 0.59 0.64)
			(layers "F.Cu" "F.Mask" "F.Paste")
			(roundrect_rratio 0.25)
			(net 38 "/X710-AT2 PCIe/PCIe_{x4}_AC.TX1-")
			(pintype "passive")
		)
	)
	(footprint "antmicro-footprints:R_0402_1005Metric"
		(layer "F.Cu")
		(at 58.24 80.7 -90)
		(descr "Resistor SMD 0402")
		(tags "resistor SMD 0402")
		(property "Reference" "R55"
			(at -1.77 -0.53 90)
			(layer "F.SilkS")
			(effects
				(font
					(size 0.7 0.7)
					(thickness 0.15)
				)
				(justify right top)
			)
		)
		(property "Value" "R_8k2_0402"
			(at -1.011843 1.772046 90)
			(layer "F.Fab")
			(hide yes)
			(effects
				(font
					(size 0.7 0.7)
					(thickness 0.15)
				)
				(justify right top)
			)
		)
		(property "Datasheet" "https://www.bourns.com/docs/product-datasheets/cr.pdf"
			(at 0 0 90)
			(layer "F.Fab")
			(hide yes)
			(effects
				(font
					(size 1.27 1.27)
					(thickness 0.15)
				)
			)
		)
		(property "Description" "SMD Chip Resistor"
			(at 0 0 90)
			(layer "F.Fab")
			(hide yes)
			(effects
				(font
					(size 1.27 1.27)
					(thickness 0.15)
				)
			)
		)
		(property "MPN" "CR0402-FX-8201GLF"
			(at 0 0 270)
			(unlocked yes)
			(layer "F.Fab")
			(hide yes)
			(effects
				(font
					(size 1 1)
					(thickness 0.15)
				)
			)
		)
		(property "Manufacturer" "Bourns"
			(at 0 0 270)
			(unlocked yes)
			(layer "F.Fab")
			(hide yes)
			(effects
				(font
					(size 1 1)
					(thickness 0.15)
				)
			)
		)
		(property "License" "Apache-2.0"
			(at 0 0 270)
			(unlocked yes)
			(layer "F.Fab")
			(hide yes)
			(effects
				(font
					(size 1 1)
					(thickness 0.15)
				)
			)
		)
		(property "Author" "Antmicro"
			(at 0 0 270)
			(unlocked yes)
			(layer "F.Fab")
			(hide yes)
			(effects
				(font
					(size 1 1)
					(thickness 0.15)
				)
			)
		)
		(property "Val" "8k2"
			(at 0 0 270)
			(unlocked yes)
			(layer "F.Fab")
			(hide yes)
			(effects
				(font
					(size 1 1)
					(thickness 0.15)
				)
			)
		)
		(property "Tolerance" "1%"
			(at 0 0 270)
			(unlocked yes)
			(layer "F.Fab")
			(hide yes)
			(effects
				(font
					(size 1 1)
					(thickness 0.15)
				)
			)
		)
		(sheetname "/X710-AT2 PCIe/")
		(sheetfile "x710-at2-pcie.kicad_sch")
		(attr smd)
		(fp_rect
			(start -0.925 -0.47)
			(end 0.925 0.47)
			(stroke
				(width 0.05)
				(type default)
			)
			(fill no)
			(layer "F.CrtYd")
		)
		(fp_rect
			(start -0.5 -0.25)
			(end 0.5 0.25)
			(stroke
				(width 0.15)
				(type solid)
			)
			(fill no)
			(layer "F.Fab")
		)
		(pad "1" smd roundrect
			(at -0.48 0 270)
			(size 0.59 0.64)
			(layers "F.Cu" "F.Mask" "F.Paste")
			(roundrect_rratio 0.25)
			(net 28 "GND")
			(pintype "passive")
		)
		(pad "2" smd roundrect
			(at 0.48 0 270)
			(size 0.59 0.64)
			(layers "F.Cu" "F.Mask" "F.Paste")
			(roundrect_rratio 0.25)
			(net 15 "/X710-AT2 PCIe/PCIe_JTAG.~{JRST}")
			(pintype "passive")
		)
	)
	(footprint "antmicro-footprints:LED_0603_1608Metric_G"
		(layer "F.Cu")
		(at 76.7 52.65 -90)
		(descr "LED SMD 0603 Green")
		(tags "LED SMD 0603 Green")
		(property "Reference" "D3"
			(at -0.607 1.31 90)
			(layer "F.SilkS")
			(effects
				(font
					(size 0.7 0.7)
					(thickness 0.15)
				)
				(justify right top)
			)
		)
		(property "Value" "LED_G_0603_LG_L29K-G2J1-24-Z"
			(at -0.001 1.599 90)
			(layer "F.Fab")
			(hide yes)
			(effects
				(font
					(size 0.7 0.7)
					(thickness 0.15)
				)
				(justify right top)
			)
		)
		(property "Datasheet" "https://look.ams-osram.com/m/19ee86b3ae0ee95b/original/LG-L29K.pdf"
			(at 0 0 90)
			(layer "F.Fab")
			(hide yes)
			(effects
				(font
					(size 1.27 1.27)
					(thickness 0.15)
				)
			)
		)
		(property "Description" "LED, Green, SMD, 0603, 20 mA, 1.7 V, 570 nm"
			(at 0 0 90)
			(layer "F.Fab")
			(hide yes)
			(effects
				(font
					(size 1.27 1.27)
					(thickness 0.15)
				)
			)
		)
		(property "MPN" "LG L29K-G2J1-24-Z"
			(at 0 0 270)
			(unlocked yes)
			(layer "F.Fab")
			(hide yes)
			(effects
				(font
					(size 1 1)
					(thickness 0.15)
				)
			)
		)
		(property "Manufacturer" "OSRAM"
			(at 0 0 270)
			(unlocked yes)
			(layer "F.Fab")
			(hide yes)
			(effects
				(font
					(size 1 1)
					(thickness 0.15)
				)
			)
		)
		(property "Color" "Green"
			(at 0 0 270)
			(unlocked yes)
			(layer "F.Fab")
			(hide yes)
			(effects
				(font
					(size 1 1)
					(thickness 0.15)
				)
			)
		)
		(property "Author" "Antmicro"
			(at 0 0 270)
			(unlocked yes)
			(layer "F.Fab")
			(hide yes)
			(effects
				(font
					(size 1 1)
					(thickness 0.15)
				)
			)
		)
		(property "License" "Apache-2.0"
			(at 0 0 270)
			(unlocked yes)
			(layer "F.Fab")
			(hide yes)
			(effects
				(font
					(size 1 1)
					(thickness 0.15)
				)
			)
		)
		(sheetname "/Power/")
		(sheetfile "power.kicad_sch")
		(attr smd)
		(fp_line
			(start 0.22 0.35)
			(end -0.22 0.35)
			(stroke
				(width 0.15)
				(type solid)
			)
			(layer "F.SilkS")
		)
		(fp_line
			(start -0.094672 0.201008)
			(end -0.094672 -0.198992)
			(stroke
				(width 0.1)
				(type solid)
			)
			(layer "F.SilkS")
		)
		(fp_line
			(start 0.105328 0.201008)
			(end -0.094672 0.001008)
			(stroke
				(width 0.1)
				(type solid)
			)
			(layer "F.SilkS")
		)
		(fp_line
			(start 0.105328 0.201008)
			(end 0.105328 -0.198992)
			(stroke
				(width 0.1)
				(type solid)
			)
			(layer "F.SilkS")
		)
		(fp_line
			(start -0.094672 0.001008)
			(end -0.24 0.001008)
			(stroke
				(width 0.1)
				(type solid)
			)
			(layer "F.SilkS")
		)
		(fp_line
			(start -0.094672 0.001008)
			(end 0.105328 -0.198992)
			(stroke
				(width 0.1)
				(type solid)
			)
			(layer "F.SilkS")
		)
		(fp_line
			(start 0.105328 0.001008)
			(end 0.24 0.001)
			(stroke
				(width 0.1)
				(type solid)
			)
			(layer "F.SilkS")
		)
		(fp_line
			(start -1.18 -0.319)
			(end -1.18 0.321)
			(stroke
				(width 0.15)
				(type solid)
			)
			(layer "F.SilkS")
		)
		(fp_line
			(start 0.22 -0.35)
			(end -0.22 -0.35)
			(stroke
				(width 0.15)
				(type solid)
			)
			(layer "F.SilkS")
		)
		(fp_rect
			(start 1.25 0.65)
			(end -1.25 -0.65)
			(stroke
				(width 0.05)
				(type solid)
			)
			(fill no)
			(layer "F.CrtYd")
		)
		(fp_line
			(start -0.199 0.2)
			(end -0.199 0.1)
			(stroke
				(width 0.15)
				(type solid)
			)
			(layer "F.Fab")
		)
		(fp_line
			(start 0.201 0.2)
			(end 0.201 0)
			(stroke
				(width 0.15)
				(type solid)
			)
			(layer "F.Fab")
		)
		(fp_line
			(start -0.199 0)
			(end -0.597 0)
			(stroke
				(width 0.15)
				(type solid)
			)
			(layer "F.Fab")
		)
		(fp_line
			(start -0.101 0)
			(end 0.201 0.2)
			(stroke
				(width 0.15)
				(type solid)
			)
			(layer "F.Fab")
		)
		(fp_line
			(start 0.201 0)
			(end 0.201 -0.202)
			(stroke
				(width 0.15)
				(type solid)
			)
			(layer "F.Fab")
		)
		(fp_line
			(start 0.599 0)
			(end 0.201 0)
			(stroke
				(width 0.15)
				(type solid)
			)
			(layer "F.Fab")
		)
		(fp_line
			(start -0.199 -0.202)
			(end -0.199 0.1)
			(stroke
				(width 0.15)
				(type solid)
			)
			(layer "F.Fab")
		)
		(fp_line
			(start 0.201 -0.202)
			(end -0.101 0)
			(stroke
				(width 0.15)
				(type solid)
			)
			(layer "F.Fab")
		)
		(fp_rect
			(start 0.848 0.4)
			(end -0.85 -0.402)
			(stroke
				(width 0.15)
				(type solid)
			)
			(fill no)
			(layer "F.Fab")
		)
		(fp_text user "Author: Antmicro"
			(at -1.4224 4.799 270)
			(layer "F.Fab")
			(effects
				(font
					(size 0.7 0.7)
					(thickness 0.15)
				)
				(justify left bottom)
			)
		)
		(fp_text user "${REFERENCE}"
			(at -1.4224 5.999 270)
			(layer "F.Fab")
			(effects
				(font
					(size 0.7 0.7)
					(thickness 0.15)
				)
				(justify left bottom)
			)
		)
		(fp_text user "License: Apache-2.0"
			(at -1.4224 3.599 270)
			(layer "F.Fab")
			(effects
				(font
					(size 0.7 0.7)
					(thickness 0.15)
				)
				(justify left bottom)
			)
		)
		(pad "1" smd roundrect
			(at -0.7 0 90)
			(size 0.8 1)
			(layers "F.Cu" "F.Mask" "F.Paste")
			(roundrect_rratio 0.2)
			(net 28 "GND")
			(pinfunction "C")
			(pintype "passive")
		)
		(pad "2" smd roundrect
			(at 0.7 0 90)
			(size 0.8 1)
			(layers "F.Cu" "F.Mask" "F.Paste")
			(roundrect_rratio 0.2)
			(net 75 "Net-(D3-A)")
			(pinfunction "A")
			(pintype "passive")
		)
	)
	(footprint "antmicro-footprints:C_0805_2012Metric"
		(layer "F.Cu")
		(at 71.3 110.39 90)
		(descr "Capacitor SMD 0805")
		(tags "capacitor SMD 0805")
		(property "Reference" "C164"
			(at -3.63 4.33 90)
			(layer "F.SilkS")
			(effects
				(font
					(size 0.7 0.7)
					(thickness 0.15)
				)
				(justify left bottom)
			)
		)
		(property "Value" "C_100u_0805"
			(at -2.055717 1.963153 90)
			(layer "F.Fab")
			(hide yes)
			(effects
				(font
					(size 0.7 0.7)
					(thickness 0.15)
				)
				(justify left bottom)
			)
		)
		(property "Datasheet" "https://www.murata.com/products/productdetail?partno=GRM21BR60J107ME15%23"
			(at 0 0 90)
			(layer "F.Fab")
			(hide yes)
			(effects
				(font
					(size 1.27 1.27)
					(thickness 0.15)
				)
			)
		)
		(property "Description" "SMD Multilayer Ceramic Capacitor, 100 µF, 6.3 V, 0805 [2012 Metric], ± 20%, X5R, GRM Series"
			(at 0 0 90)
			(layer "F.Fab")
			(hide yes)
			(effects
				(font
					(size 1.27 1.27)
					(thickness 0.15)
				)
			)
		)
		(property "MPN" "GRM21BR60J107ME15L"
			(at 0 0 90)
			(unlocked yes)
			(layer "F.Fab")
			(hide yes)
			(effects
				(font
					(size 1 1)
					(thickness 0.15)
				)
			)
		)
		(property "Manufacturer" "Murata"
			(at 0 0 90)
			(unlocked yes)
			(layer "F.Fab")
			(hide yes)
			(effects
				(font
					(size 1 1)
					(thickness 0.15)
				)
			)
		)
		(property "License" "Apache-2.0"
			(at 0 0 90)
			(unlocked yes)
			(layer "F.Fab")
			(hide yes)
			(effects
				(font
					(size 1 1)
					(thickness 0.15)
				)
			)
		)
		(property "Author" "Antmicro"
			(at 0 0 90)
			(unlocked yes)
			(layer "F.Fab")
			(hide yes)
			(effects
				(font
					(size 1 1)
					(thickness 0.15)
				)
			)
		)
		(property "Val" "100u"
			(at 0 0 90)
			(unlocked yes)
			(layer "F.Fab")
			(hide yes)
			(effects
				(font
					(size 1 1)
					(thickness 0.15)
				)
			)
		)
		(property "Voltage" ""
			(at 0 0 90)
			(unlocked yes)
			(layer "F.Fab")
			(hide yes)
			(effects
				(font
					(size 1 1)
					(thickness 0.15)
				)
			)
		)
		(property "Dielectric" ""
			(at 0 0 90)
			(unlocked yes)
			(layer "F.Fab")
			(hide yes)
			(effects
				(font
					(size 1 1)
					(thickness 0.15)
				)
			)
		)
		(property "Public" "False"
			(at 0 0 90)
			(unlocked yes)
			(layer "F.Fab")
			(hide yes)
			(effects
				(font
					(size 1 1)
					(thickness 0.15)
				)
			)
		)
		(sheetname "/X710-AT2 power/")
		(sheetfile "x710-at2-power.kicad_sch")
		(attr smd)
		(fp_line
			(start -0.3 -0.7)
			(end 0.3 -0.7)
			(stroke
				(width 0.15)
				(type solid)
			)
			(layer "F.SilkS")
		)
		(fp_line
			(start -0.3 0.7)
			(end 0.3 0.7)
			(stroke
				(width 0.15)
				(type solid)
			)
			(layer "F.SilkS")
		)
		(fp_rect
			(start 1.95 -0.9)
			(end -1.95 0.9)
			(stroke
				(width 0.05)
				(type default)
			)
			(fill no)
			(layer "F.CrtYd")
		)
		(fp_rect
			(start -0.95 -0.675)
			(end 0.95 0.675)
			(stroke
				(width 0.15)
				(type solid)
			)
			(fill no)
			(layer "F.Fab")
		)
		(pad "1" smd roundrect
			(at -1.1 0 90)
			(size 1.2 1.3)
			(layers "F.Cu" "F.Mask" "F.Paste")
			(roundrect_rratio 0.25)
			(net 28 "GND")
			(pintype "passive")
		)
		(pad "2" smd roundrect
			(at 1.1 0 90)
			(size 1.2 1.3)
			(layers "F.Cu" "F.Mask" "F.Paste")
			(roundrect_rratio 0.25)
			(net 5 "P0_AVDDL")
			(pintype "passive")
		)
	)
	(footprint "antmicro-footprints:C_0402_1005Metric"
		(layer "F.Cu")
		(at 56.399998 90.1)
		(descr "Capacitor SMD 0402")
		(tags "capacitor SMD 0402")
		(property "Reference" "C10"
			(at -2.809998 0.94 0)
			(layer "F.SilkS")
			(effects
				(font
					(size 0.7 0.7)
					(thickness 0.15)
				)
				(justify left bottom)
			)
		)
		(property "Value" "C_100n_0402"
			(at -1.022927 2.155213 0)
			(layer "F.Fab")
			(hide yes)
			(effects
				(font
					(size 0.7 0.7)
					(thickness 0.15)
				)
				(justify left bottom)
			)
		)
		(property "Datasheet" "https://www.murata.com/products/productdetail?partno=GRM155R61H104KE14%23"
			(at 0 0 0)
			(layer "F.Fab")
			(hide yes)
			(effects
				(font
					(size 1.27 1.27)
					(thickness 0.15)
				)
			)
		)
		(property "Description" "SMD Multilayer Ceramic Capacitor, 0.1 µF, 50 V, 0402 [1005 Metric], ± 10%, X5R, GRM Series"
			(at 0 0 0)
			(layer "F.Fab")
			(hide yes)
			(effects
				(font
					(size 1.27 1.27)
					(thickness 0.15)
				)
			)
		)
		(property "MPN" "GRM155R61H104KE14D"
			(at 0 0 0)
			(unlocked yes)
			(layer "F.Fab")
			(hide yes)
			(effects
				(font
					(size 1 1)
					(thickness 0.15)
				)
			)
		)
		(property "Manufacturer" "Murata"
			(at 0 0 0)
			(unlocked yes)
			(layer "F.Fab")
			(hide yes)
			(effects
				(font
					(size 1 1)
					(thickness 0.15)
				)
			)
		)
		(property "License" "Apache-2.0"
			(at 0 0 0)
			(unlocked yes)
			(layer "F.Fab")
			(hide yes)
			(effects
				(font
					(size 1 1)
					(thickness 0.15)
				)
			)
		)
		(property "Author" "Antmicro"
			(at 0 0 0)
			(unlocked yes)
			(layer "F.Fab")
			(hide yes)
			(effects
				(font
					(size 1 1)
					(thickness 0.15)
				)
			)
		)
		(property "Val" "100n"
			(at 0 0 0)
			(unlocked yes)
			(layer "F.Fab")
			(hide yes)
			(effects
				(font
					(size 1 1)
					(thickness 0.15)
				)
			)
		)
		(property "Voltage" "50V"
			(at 0 0 0)
			(unlocked yes)
			(layer "F.Fab")
			(hide yes)
			(effects
				(font
					(size 1 1)
					(thickness 0.15)
				)
			)
		)
		(property "Dielectric" "X5R"
			(at 0 0 0)
			(unlocked yes)
			(layer "F.Fab")
			(hide yes)
			(effects
				(font
					(size 1 1)
					(thickness 0.15)
				)
			)
		)
		(sheetname "/Power/")
		(sheetfile "power.kicad_sch")
		(attr smd)
		(fp_rect
			(start -0.925 -0.47)
			(end 0.925 0.47)
			(stroke
				(width 0.05)
				(type default)
			)
			(fill no)
			(layer "F.CrtYd")
		)
		(fp_line
			(start -0.494 -0.25)
			(end 0.504 -0.25)
			(stroke
				(width 0.15)
				(type solid)
			)
			(layer "F.Fab")
		)
		(fp_line
			(start -0.494 0.248)
			(end -0.494 -0.25)
			(stroke
				(width 0.15)
				(type solid)
			)
			(layer "F.Fab")
		)
		(fp_line
			(start 0.504 -0.25)
			(end 0.504 0.248)
			(stroke
				(width 0.15)
				(type solid)
			)
			(layer "F.Fab")
		)
		(fp_line
			(start 0.504 0.248)
			(end -0.494 0.248)
			(stroke
				(width 0.15)
				(type solid)
			)
			(layer "F.Fab")
		)
		(pad "1" smd roundrect
			(at -0.48 0)
			(size 0.59 0.64)
			(layers "F.Cu" "F.Mask" "F.Paste")
			(roundrect_rratio 0.25)
			(net 318 "/Power/VCCD_BST")
			(pintype "passive")
		)
		(pad "2" smd roundrect
			(at 0.48 0)
			(size 0.59 0.64)
			(layers "F.Cu" "F.Mask" "F.Paste")
			(roundrect_rratio 0.25)
			(net 334 "/Power/VCCD_SW")
			(pintype "passive")
		)
	)
	(footprint "antmicro-footprints:C_0603_1608Metric_EIA"
		(layer "F.Cu")
		(at 77.2 85 180)
		(descr "Capacitor SMD 0603, IPC-7351 Density Level A")
		(tags "Capacitor 0603")
		(property "Reference" "C152"
			(at -1.4 7.958 0)
			(layer "F.SilkS")
			(effects
				(font
					(size 0.7 0.7)
					(thickness 0.15)
				)
				(justify right top)
			)
		)
		(property "Value" "C_22u_16V_0603"
			(at -1.42757 1.770288 0)
			(layer "F.Fab")
			(hide yes)
			(effects
				(font
					(size 0.7 0.7)
					(thickness 0.15)
				)
				(justify right top)
			)
		)
		(property "Datasheet" "https://product.samsungsem.com/mlcc/CL10A226MO7JZN.do"
			(at 0 0 0)
			(layer "F.Fab")
			(hide yes)
			(effects
				(font
					(size 1.27 1.27)
					(thickness 0.15)
				)
			)
		)
		(property "Description" "SMD Multilayer Ceramic Capacitor"
			(at 0 0 0)
			(layer "F.Fab")
			(hide yes)
			(effects
				(font
					(size 1.27 1.27)
					(thickness 0.15)
				)
			)
		)
		(property "MPN" "CL10A226MO7JZNC"
			(at 0 0 180)
			(unlocked yes)
			(layer "F.Fab")
			(hide yes)
			(effects
				(font
					(size 1 1)
					(thickness 0.15)
				)
			)
		)
		(property "Manufacturer" "Samsung Electro-Mechanics"
			(at 0 0 180)
			(unlocked yes)
			(layer "F.Fab")
			(hide yes)
			(effects
				(font
					(size 1 1)
					(thickness 0.15)
				)
			)
		)
		(property "License" "Apache-2.0"
			(at 0 0 180)
			(unlocked yes)
			(layer "F.Fab")
			(hide yes)
			(effects
				(font
					(size 1 1)
					(thickness 0.15)
				)
			)
		)
		(property "Author" "Antmicro"
			(at 0 0 180)
			(unlocked yes)
			(layer "F.Fab")
			(hide yes)
			(effects
				(font
					(size 1 1)
					(thickness 0.15)
				)
			)
		)
		(property "Val" "22u"
			(at 0 0 180)
			(unlocked yes)
			(layer "F.Fab")
			(hide yes)
			(effects
				(font
					(size 1 1)
					(thickness 0.15)
				)
			)
		)
		(property "Voltage" "16V"
			(at 0 0 180)
			(unlocked yes)
			(layer "F.Fab")
			(hide yes)
			(effects
				(font
					(size 1 1)
					(thickness 0.15)
				)
			)
		)
		(property "Dielectric" ""
			(at 0 0 180)
			(unlocked yes)
			(layer "F.Fab")
			(hide yes)
			(effects
				(font
					(size 1 1)
					(thickness 0.15)
				)
			)
		)
		(sheetname "/X710-AT2 power/")
		(sheetfile "x710-at2-power.kicad_sch")
		(attr smd)
		(fp_line
			(start -0.15 0.55)
			(end 0.15 0.55)
			(stroke
				(width 0.15)
				(type solid)
			)
			(layer "F.SilkS")
		)
		(fp_line
			(start -0.15 -0.55)
			(end 0.15 -0.55)
			(stroke
				(width 0.15)
				(type solid)
			)
			(layer "F.SilkS")
		)
		(fp_rect
			(start -1.25 -0.65)
			(end 1.25 0.65)
			(stroke
				(width 0.05)
				(type solid)
			)
			(fill no)
			(layer "F.CrtYd")
		)
		(fp_rect
			(start -0.8 -0.45)
			(end 0.8 0.45)
			(stroke
				(width 0.15)
				(type solid)
			)
			(fill no)
			(layer "F.Fab")
		)
		(pad "1" smd roundrect
			(at -0.7 0 180)
			(size 0.8 1.1)
			(layers "F.Cu" "F.Mask" "F.Paste")
			(roundrect_rratio 0.2)
			(net 28 "GND")
			(pintype "passive")
		)
		(pad "2" smd roundrect
			(at 0.7 0 180)
			(size 0.8 1.1)
			(layers "F.Cu" "F.Mask" "F.Paste")
			(roundrect_rratio 0.2)
			(net 7 "+3V3")
			(pintype "passive")
		)
	)
	(footprint "antmicro-footprints:FB_0603_1608Metric"
		(layer "F.Cu")
		(at 67.25 113.1)
		(property "Reference" "FB6"
			(at -3.2 0.46 0)
			(layer "F.SilkS")
			(effects
				(font
					(size 0.7 0.7)
					(thickness 0.15)
				)
				(justify left bottom)
			)
		)
		(property "Value" "FB_33Z_3A_Murata-BLM18PG_0603"
			(at 0 1.5 0)
			(layer "F.Fab")
			(hide yes)
			(effects
				(font
					(size 0.7 0.7)
					(thickness 0.15)
				)
				(justify left bottom)
			)
		)
		(property "Datasheet" "https://www.murata.com/products/productdata/8796737273886/QNFA9101.pdf?1649080818000"
			(at 0 0 0)
			(layer "F.Fab")
			(hide yes)
			(effects
				(font
					(size 1.27 1.27)
					(thickness 0.15)
				)
			)
		)
		(property "Description" "Ferrite Bead, 0603 [1608 Metric], 33 ohm, 3 A, BLM18PG, 0.025 ohm, ± 25%, DC power line"
			(at 0 0 0)
			(layer "F.Fab")
			(hide yes)
			(effects
				(font
					(size 1.27 1.27)
					(thickness 0.15)
				)
			)
		)
		(property "Val" "33Z/3A"
			(at 0 0 0)
			(unlocked yes)
			(layer "F.Fab")
			(hide yes)
			(effects
				(font
					(size 1 1)
					(thickness 0.15)
				)
			)
		)
		(property "MPN" "BLM18PG330SH1D"
			(at 0 0 0)
			(unlocked yes)
			(layer "F.Fab")
			(hide yes)
			(effects
				(font
					(size 1 1)
					(thickness 0.15)
				)
			)
		)
		(property "Manufacturer" "Murata"
			(at 0 0 0)
			(unlocked yes)
			(layer "F.Fab")
			(hide yes)
			(effects
				(font
					(size 1 1)
					(thickness 0.15)
				)
			)
		)
		(property "Current" ""
			(at 0 0 0)
			(unlocked yes)
			(layer "F.Fab")
			(hide yes)
			(effects
				(font
					(size 1 1)
					(thickness 0.15)
				)
			)
		)
		(property "Author" "Antmicro"
			(at 0 0 0)
			(unlocked yes)
			(layer "F.Fab")
			(hide yes)
			(effects
				(font
					(size 1 1)
					(thickness 0.15)
				)
			)
		)
		(property "License" "Apache-2.0"
			(at 0 0 0)
			(unlocked yes)
			(layer "F.Fab")
			(hide yes)
			(effects
				(font
					(size 1 1)
					(thickness 0.15)
				)
			)
		)
		(sheetname "/X710-AT2 power/")
		(sheetfile "x710-at2-power.kicad_sch")
		(attr smd)
		(fp_line
			(start -0.15 -0.4)
			(end 0.15 -0.4)
			(stroke
				(width 0.15)
				(type solid)
			)
			(layer "F.SilkS")
		)
		(fp_line
			(start -0.15 0.4)
			(end 0.15 0.4)
			(stroke
				(width 0.15)
				(type solid)
			)
			(layer "F.SilkS")
		)
		(fp_rect
			(start -1.25 -0.65)
			(end 1.25 0.65)
			(stroke
				(width 0.05)
				(type solid)
			)
			(fill no)
			(layer "F.CrtYd")
		)
		(fp_line
			(start -0.803 0.406)
			(end -0.803 -0.408)
			(stroke
				(width 0.15)
				(type solid)
			)
			(layer "F.Fab")
		)
		(fp_line
			(start 0.8 -0.408)
			(end -0.803 -0.408)
			(stroke
				(width 0.15)
				(type solid)
			)
			(layer "F.Fab")
		)
		(fp_line
			(start 0.8 -0.408)
			(end 0.8 0.406)
			(stroke
				(width 0.15)
				(type solid)
			)
			(layer "F.Fab")
		)
		(fp_line
			(start 0.8 0.406)
			(end -0.803 0.406)
			(stroke
				(width 0.15)
				(type solid)
			)
			(layer "F.Fab")
		)
		(pad "1" smd roundrect
			(at -0.7 0)
			(size 0.8 1)
			(layers "F.Cu" "F.Mask" "F.Paste")
			(roundrect_rratio 0.2)
			(net 302 "+1V0")
			(pintype "passive")
		)
		(pad "2" smd roundrect
			(at 0.7 0)
			(size 0.8 1)
			(layers "F.Cu" "F.Mask" "F.Paste")
			(roundrect_rratio 0.2)
			(net 14 "P1_AVDDL")
			(pintype "passive")
		)
	)
	(footprint "antmicro-footprints:LED_0603_1608Metric_G"
		(layer "F.Cu")
		(at 54.35 122.75 180)
		(descr "LED SMD 0603 Green")
		(tags "LED SMD 0603 Green")
		(property "Reference" "D18"
			(at -1.1 -0.75 0)
			(layer "F.SilkS")
			(effects
				(font
					(size 0.7 0.7)
					(thickness 0.15)
				)
				(justify right top)
			)
		)
		(property "Value" "LED_G_0603_LG_L29K-G2J1-24-Z"
			(at -0.001 1.599 0)
			(layer "F.Fab")
			(hide yes)
			(effects
				(font
					(size 0.7 0.7)
					(thickness 0.15)
				)
				(justify right top)
			)
		)
		(property "Datasheet" "https://look.ams-osram.com/m/19ee86b3ae0ee95b/original/LG-L29K.pdf"
			(at 0 0 0)
			(layer "F.Fab")
			(hide yes)
			(effects
				(font
					(size 1.27 1.27)
					(thickness 0.15)
				)
			)
		)
		(property "Description" "LED, Green, SMD, 0603, 20 mA, 1.7 V, 570 nm"
			(at 0 0 0)
			(layer "F.Fab")
			(hide yes)
			(effects
				(font
					(size 1.27 1.27)
					(thickness 0.15)
				)
			)
		)
		(property "MPN" "LG L29K-G2J1-24-Z"
			(at 0 0 180)
			(unlocked yes)
			(layer "F.Fab")
			(hide yes)
			(effects
				(font
					(size 1 1)
					(thickness 0.15)
				)
			)
		)
		(property "Manufacturer" "OSRAM"
			(at 0 0 180)
			(unlocked yes)
			(layer "F.Fab")
			(hide yes)
			(effects
				(font
					(size 1 1)
					(thickness 0.15)
				)
			)
		)
		(property "Color" "Green"
			(at 0 0 180)
			(unlocked yes)
			(layer "F.Fab")
			(hide yes)
			(effects
				(font
					(size 1 1)
					(thickness 0.15)
				)
			)
		)
		(property "Author" "Antmicro"
			(at 0 0 180)
			(unlocked yes)
			(layer "F.Fab")
			(hide yes)
			(effects
				(font
					(size 1 1)
					(thickness 0.15)
				)
			)
		)
		(property "License" "Apache-2.0"
			(at 0 0 180)
			(unlocked yes)
			(layer "F.Fab")
			(hide yes)
			(effects
				(font
					(size 1 1)
					(thickness 0.15)
				)
			)
		)
		(sheetname "/Power/")
		(sheetfile "power.kicad_sch")
		(attr smd)
		(fp_line
			(start 0.22 0.35)
			(end -0.22 0.35)
			(stroke
				(width 0.15)
				(type solid)
			)
			(layer "F.SilkS")
		)
		(fp_line
			(start 0.22 -0.35)
			(end -0.22 -0.35)
			(stroke
				(width 0.15)
				(type solid)
			)
			(layer "F.SilkS")
		)
		(fp_line
			(start 0.105328 0.201008)
			(end 0.105328 -0.198992)
			(stroke
				(width 0.1)
				(type solid)
			)
			(layer "F.SilkS")
		)
		(fp_line
			(start 0.105328 0.201008)
			(end -0.094672 0.001008)
			(stroke
				(width 0.1)
				(type solid)
			)
			(layer "F.SilkS")
		)
		(fp_line
			(start 0.105328 0.001008)
			(end 0.24 0.001)
			(stroke
				(width 0.1)
				(type solid)
			)
			(layer "F.SilkS")
		)
		(fp_line
			(start -0.094672 0.201008)
			(end -0.094672 -0.198992)
			(stroke
				(width 0.1)
				(type solid)
			)
			(layer "F.SilkS")
		)
		(fp_line
			(start -0.094672 0.001008)
			(end 0.105328 -0.198992)
			(stroke
				(width 0.1)
				(type solid)
			)
			(layer "F.SilkS")
		)
		(fp_line
			(start -0.094672 0.001008)
			(end -0.24 0.001008)
			(stroke
				(width 0.1)
				(type solid)
			)
			(layer "F.SilkS")
		)
		(fp_line
			(start -1.18 -0.319)
			(end -1.18 0.321)
			(stroke
				(width 0.15)
				(type solid)
			)
			(layer "F.SilkS")
		)
		(fp_rect
			(start 1.25 0.65)
			(end -1.25 -0.65)
			(stroke
				(width 0.05)
				(type solid)
			)
			(fill no)
			(layer "F.CrtYd")
		)
		(fp_line
			(start 0.599 0)
			(end 0.201 0)
			(stroke
				(width 0.15)
				(type solid)
			)
			(layer "F.Fab")
		)
		(fp_line
			(start 0.201 0.2)
			(end 0.201 0)
			(stroke
				(width 0.15)
				(type solid)
			)
			(layer "F.Fab")
		)
		(fp_line
			(start 0.201 0)
			(end 0.201 -0.202)
			(stroke
				(width 0.15)
				(type solid)
			)
			(layer "F.Fab")
		)
		(fp_line
			(start 0.201 -0.202)
			(end -0.101 0)
			(stroke
				(width 0.15)
				(type solid)
			)
			(layer "F.Fab")
		)
		(fp_line
			(start -0.101 0)
			(end 0.201 0.2)
			(stroke
				(width 0.15)
				(type solid)
			)
			(layer "F.Fab")
		)
		(fp_line
			(start -0.199 0.2)
			(end -0.199 0.1)
			(stroke
				(width 0.15)
				(type solid)
			)
			(layer "F.Fab")
		)
		(fp_line
			(start -0.199 0)
			(end -0.597 0)
			(stroke
				(width 0.15)
				(type solid)
			)
			(layer "F.Fab")
		)
		(fp_line
			(start -0.199 -0.202)
			(end -0.199 0.1)
			(stroke
				(width 0.15)
				(type solid)
			)
			(layer "F.Fab")
		)
		(fp_rect
			(start 0.848 0.4)
			(end -0.85 -0.402)
			(stroke
				(width 0.15)
				(type solid)
			)
			(fill no)
			(layer "F.Fab")
		)
		(fp_text user "License: Apache-2.0"
			(at -1.4224 3.599 180)
			(layer "F.Fab")
			(effects
				(font
					(size 0.7 0.7)
					(thickness 0.15)
				)
				(justify left bottom)
			)
		)
		(fp_text user "${REFERENCE}"
			(at -1.4224 5.999 180)
			(layer "F.Fab")
			(effects
				(font
					(size 0.7 0.7)
					(thickness 0.15)
				)
				(justify left bottom)
			)
		)
		(fp_text user "Author: Antmicro"
			(at -1.4224 4.799 180)
			(layer "F.Fab")
			(effects
				(font
					(size 0.7 0.7)
					(thickness 0.15)
				)
				(justify left bottom)
			)
		)
		(pad "1" smd roundrect
			(at -0.7 0)
			(size 0.8 1)
			(layers "F.Cu" "F.Mask" "F.Paste")
			(roundrect_rratio 0.2)
			(net 412 "Net-(D18-C)")
			(pinfunction "C")
			(pintype "passive")
		)
		(pad "2" smd roundrect
			(at 0.7 0)
			(size 0.8 1)
			(layers "F.Cu" "F.Mask" "F.Paste")
			(roundrect_rratio 0.2)
			(net 255 "/Power/+3V3_OUT")
			(pinfunction "A")
			(pintype "passive")
		)
	)
	(footprint "antmicro-footprints:R_0402_1005Metric"
		(layer "F.Cu")
		(at 73.85 76.039996 180)
		(descr "Resistor SMD 0402")
		(tags "resistor SMD 0402")
		(property "Reference" "R2"
			(at -1 3.439994 0)
			(layer "F.SilkS")
			(effects
				(font
					(size 0.7 0.7)
					(thickness 0.15)
				)
				(justify right top)
			)
		)
		(property "Value" "R_255k_0402"
			(at -1.011843 1.772046 0)
			(layer "F.Fab")
			(hide yes)
			(effects
				(font
					(size 0.7 0.7)
					(thickness 0.15)
				)
				(justify right top)
			)
		)
		(property "Datasheet" "https://www.bourns.com/docs/product-datasheets/cr.pdf"
			(at 0 0 0)
			(layer "F.Fab")
			(hide yes)
			(effects
				(font
					(size 1.27 1.27)
					(thickness 0.15)
				)
			)
		)
		(property "Description" "SMD Chip Resistor, 255 kohm, ± 1%, 100 mW, 0402 [1005 Metric], Thick Film, Precision"
			(at 0 0 0)
			(layer "F.Fab")
			(hide yes)
			(effects
				(font
					(size 1.27 1.27)
					(thickness 0.15)
				)
			)
		)
		(property "MPN" "CR0402-FX-2553GLF"
			(at 0 0 180)
			(unlocked yes)
			(layer "F.Fab")
			(hide yes)
			(effects
				(font
					(size 1 1)
					(thickness 0.15)
				)
			)
		)
		(property "Manufacturer" "Bourns"
			(at 0 0 180)
			(unlocked yes)
			(layer "F.Fab")
			(hide yes)
			(effects
				(font
					(size 1 1)
					(thickness 0.15)
				)
			)
		)
		(property "License" "Apache-2.0"
			(at 0 0 180)
			(unlocked yes)
			(layer "F.Fab")
			(hide yes)
			(effects
				(font
					(size 1 1)
					(thickness 0.15)
				)
			)
		)
		(property "Author" "Antmicro"
			(at 0 0 180)
			(unlocked yes)
			(layer "F.Fab")
			(hide yes)
			(effects
				(font
					(size 1 1)
					(thickness 0.15)
				)
			)
		)
		(property "Val" "255k"
			(at 0 0 180)
			(unlocked yes)
			(layer "F.Fab")
			(hide yes)
			(effects
				(font
					(size 1 1)
					(thickness 0.15)
				)
			)
		)
		(property "Tolerance" "1%"
			(at 0 0 180)
			(unlocked yes)
			(layer "F.Fab")
			(hide yes)
			(effects
				(font
					(size 1 1)
					(thickness 0.15)
				)
			)
		)
		(sheetname "/Power/")
		(sheetfile "power.kicad_sch")
		(attr smd)
		(fp_rect
			(start -0.925 -0.47)
			(end 0.925 0.47)
			(stroke
				(width 0.05)
				(type default)
			)
			(fill no)
			(layer "F.CrtYd")
		)
		(fp_rect
			(start -0.5 -0.25)
			(end 0.5 0.25)
			(stroke
				(width 0.15)
				(type solid)
			)
			(fill no)
			(layer "F.Fab")
		)
		(pad "1" smd roundrect
			(at -0.48 0 180)
			(size 0.59 0.64)
			(layers "F.Cu" "F.Mask" "F.Paste")
			(roundrect_rratio 0.25)
			(net 379 "/Power/3V3_EN")
			(pintype "passive")
		)
		(pad "2" smd roundrect
			(at 0.48 0 180)
			(size 0.59 0.64)
			(layers "F.Cu" "F.Mask" "F.Paste")
			(roundrect_rratio 0.25)
			(net 314 "VCC")
			(pintype "passive")
		)
	)
	(footprint "antmicro-footprints:R_0402_1005Metric"
		(layer "F.Cu")
		(at 99.35 105.2)
		(descr "Resistor SMD 0402")
		(tags "resistor SMD 0402")
		(property "Reference" "R88"
			(at -1.25 15.3 0)
			(layer "F.SilkS")
			(effects
				(font
					(size 0.7 0.7)
					(thickness 0.15)
				)
				(justify left bottom)
			)
		)
		(property "Value" "R_100k_0402"
			(at -1.011843 1.772046 0)
			(layer "F.Fab")
			(hide yes)
			(effects
				(font
					(size 0.7 0.7)
					(thickness 0.15)
				)
				(justify left bottom)
			)
		)
		(property "Datasheet" "https://www.bourns.com/docs/product-datasheets/cr.pdf"
			(at 0 0 0)
			(layer "F.Fab")
			(hide yes)
			(effects
				(font
					(size 1.27 1.27)
					(thickness 0.15)
				)
			)
		)
		(property "Description" "SMD Chip Resistor, 100 kohm, ± 1%, 62.5 mW, 0402 [1005 Metric], Thick Film, General Purpose"
			(at 0 0 0)
			(layer "F.Fab")
			(hide yes)
			(effects
				(font
					(size 1.27 1.27)
					(thickness 0.15)
				)
			)
		)
		(property "MPN" "CR0402-FX-1003GLF"
			(at 0 0 0)
			(unlocked yes)
			(layer "F.Fab")
			(hide yes)
			(effects
				(font
					(size 1 1)
					(thickness 0.15)
				)
			)
		)
		(property "Manufacturer" "Bourns"
			(at 0 0 0)
			(unlocked yes)
			(layer "F.Fab")
			(hide yes)
			(effects
				(font
					(size 1 1)
					(thickness 0.15)
				)
			)
		)
		(property "License" "Apache-2.0"
			(at 0 0 0)
			(unlocked yes)
			(layer "F.Fab")
			(hide yes)
			(effects
				(font
					(size 1 1)
					(thickness 0.15)
				)
			)
		)
		(property "Author" "Antmicro"
			(at 0 0 0)
			(unlocked yes)
			(layer "F.Fab")
			(hide yes)
			(effects
				(font
					(size 1 1)
					(thickness 0.15)
				)
			)
		)
		(property "Val" "100k"
			(at 0 0 0)
			(unlocked yes)
			(layer "F.Fab")
			(hide yes)
			(effects
				(font
					(size 1 1)
					(thickness 0.15)
				)
			)
		)
		(property "Tolerance" "1%"
			(at 0 0 0)
			(unlocked yes)
			(layer "F.Fab")
			(hide yes)
			(effects
				(font
					(size 1 1)
					(thickness 0.15)
				)
			)
		)
		(sheetname "/X710-AT2 Misc/")
		(sheetfile "x710-at2-mics.kicad_sch")
		(attr smd)
		(fp_rect
			(start -0.925 -0.47)
			(end 0.925 0.47)
			(stroke
				(width 0.05)
				(type default)
			)
			(fill no)
			(layer "F.CrtYd")
		)
		(fp_rect
			(start -0.5 -0.25)
			(end 0.5 0.25)
			(stroke
				(width 0.15)
				(type solid)
			)
			(fill no)
			(layer "F.Fab")
		)
		(pad "1" smd roundrect
			(at -0.48 0)
			(size 0.59 0.64)
			(layers "F.Cu" "F.Mask" "F.Paste")
			(roundrect_rratio 0.25)
			(net 28 "GND")
			(pintype "passive")
		)
		(pad "2" smd roundrect
			(at 0.48 0)
			(size 0.59 0.64)
			(layers "F.Cu" "F.Mask" "F.Paste")
			(roundrect_rratio 0.25)
			(net 365 "/X710-AT2 Misc/NCSI.CRS_DV")
			(pintype "passive")
		)
	)
	(footprint "antmicro-footprints:R_0402_1005Metric"
		(layer "F.Cu")
		(at 69.8 91.305 90)
		(descr "Resistor SMD 0402")
		(tags "resistor SMD 0402")
		(property "Reference" "R110"
			(at 0.785 0.34 90)
			(layer "F.SilkS")
			(effects
				(font
					(size 0.7 0.7)
					(thickness 0.15)
				)
				(justify left bottom)
			)
		)
		(property "Value" "R_8k2_0402"
			(at -1.011843 1.772046 90)
			(layer "F.Fab")
			(hide yes)
			(effects
				(font
					(size 0.7 0.7)
					(thickness 0.15)
				)
				(justify left bottom)
			)
		)
		(property "Datasheet" "https://www.bourns.com/docs/product-datasheets/cr.pdf"
			(at 0 0 90)
			(layer "F.Fab")
			(hide yes)
			(effects
				(font
					(size 1.27 1.27)
					(thickness 0.15)
				)
			)
		)
		(property "Description" "SMD Chip Resistor"
			(at 0 0 90)
			(layer "F.Fab")
			(hide yes)
			(effects
				(font
					(size 1.27 1.27)
					(thickness 0.15)
				)
			)
		)
		(property "MPN" "CR0402-FX-8201GLF"
			(at 0 0 90)
			(unlocked yes)
			(layer "F.Fab")
			(hide yes)
			(effects
				(font
					(size 1 1)
					(thickness 0.15)
				)
			)
		)
		(property "Manufacturer" "Bourns"
			(at 0 0 90)
			(unlocked yes)
			(layer "F.Fab")
			(hide yes)
			(effects
				(font
					(size 1 1)
					(thickness 0.15)
				)
			)
		)
		(property "License" "Apache-2.0"
			(at 0 0 90)
			(unlocked yes)
			(layer "F.Fab")
			(hide yes)
			(effects
				(font
					(size 1 1)
					(thickness 0.15)
				)
			)
		)
		(property "Author" "Antmicro"
			(at 0 0 90)
			(unlocked yes)
			(layer "F.Fab")
			(hide yes)
			(effects
				(font
					(size 1 1)
					(thickness 0.15)
				)
			)
		)
		(property "Val" "8k2"
			(at 0 0 90)
			(unlocked yes)
			(layer "F.Fab")
			(hide yes)
			(effects
				(font
					(size 1 1)
					(thickness 0.15)
				)
			)
		)
		(property "Tolerance" "1%"
			(at 0 0 90)
			(unlocked yes)
			(layer "F.Fab")
			(hide yes)
			(effects
				(font
					(size 1 1)
					(thickness 0.15)
				)
			)
		)
		(sheetname "/X710-AT2 Misc/")
		(sheetfile "x710-at2-mics.kicad_sch")
		(attr smd)
		(fp_rect
			(start -0.925 -0.47)
			(end 0.925 0.47)
			(stroke
				(width 0.05)
				(type default)
			)
			(fill no)
			(layer "F.CrtYd")
		)
		(fp_rect
			(start -0.5 -0.25)
			(end 0.5 0.25)
			(stroke
				(width 0.15)
				(type solid)
			)
			(fill no)
			(layer "F.Fab")
		)
		(pad "1" smd roundrect
			(at -0.48 0 90)
			(size 0.59 0.64)
			(layers "F.Cu" "F.Mask" "F.Paste")
			(roundrect_rratio 0.25)
			(net 28 "GND")
			(pintype "passive")
		)
		(pad "2" smd roundrect
			(at 0.48 0 90)
			(size 0.59 0.64)
			(layers "F.Cu" "F.Mask" "F.Paste")
			(roundrect_rratio 0.25)
			(net 106 "/Flash memory/FLASH.CLK")
			(pintype "passive")
		)
	)
	(footprint "antmicro-footprints:C_0402_1005Metric"
		(layer "F.Cu")
		(at 57.099998 92.849999 -90)
		(descr "Capacitor SMD 0402")
		(tags "capacitor SMD 0402")
		(property "Reference" "C43"
			(at -1.819999 -0.350002 180)
			(layer "F.SilkS")
			(effects
				(font
					(size 0.7 0.7)
					(thickness 0.15)
				)
				(justify right top)
			)
		)
		(property "Value" "C_1u_25V_0402"
			(at -1.022927 2.155213 90)
			(layer "F.Fab")
			(hide yes)
			(effects
				(font
					(size 0.7 0.7)
					(thickness 0.15)
				)
				(justify right top)
			)
		)
		(property "Datasheet" "https://www.murata.com/products/productdetail?partno=GRM155R61E105KE11%23"
			(at 0 0 90)
			(layer "F.Fab")
			(hide yes)
			(effects
				(font
					(size 1.27 1.27)
					(thickness 0.15)
				)
			)
		)
		(property "Description" "SMD Multilayer Ceramic Capacitor, 1 µF, 25 V, 0402 [1005 Metric], ± 10%, X5R, GRM Series"
			(at 0 0 90)
			(layer "F.Fab")
			(hide yes)
			(effects
				(font
					(size 1.27 1.27)
					(thickness 0.15)
				)
			)
		)
		(property "MPN" "GRM155R61E105KE11J"
			(at 0 0 270)
			(unlocked yes)
			(layer "F.Fab")
			(hide yes)
			(effects
				(font
					(size 1 1)
					(thickness 0.15)
				)
			)
		)
		(property "Manufacturer" "Murata"
			(at 0 0 270)
			(unlocked yes)
			(layer "F.Fab")
			(hide yes)
			(effects
				(font
					(size 1 1)
					(thickness 0.15)
				)
			)
		)
		(property "License" "Apache-2.0"
			(at 0 0 270)
			(unlocked yes)
			(layer "F.Fab")
			(hide yes)
			(effects
				(font
					(size 1 1)
					(thickness 0.15)
				)
			)
		)
		(property "Author" "Antmicro"
			(at 0 0 270)
			(unlocked yes)
			(layer "F.Fab")
			(hide yes)
			(effects
				(font
					(size 1 1)
					(thickness 0.15)
				)
			)
		)
		(property "Val" "1u"
			(at 0 0 270)
			(unlocked yes)
			(layer "F.Fab")
			(hide yes)
			(effects
				(font
					(size 1 1)
					(thickness 0.15)
				)
			)
		)
		(property "Voltage" "25V"
			(at 0 0 270)
			(unlocked yes)
			(layer "F.Fab")
			(hide yes)
			(effects
				(font
					(size 1 1)
					(thickness 0.15)
				)
			)
		)
		(property "Dielectric" "X5R"
			(at 0 0 270)
			(unlocked yes)
			(layer "F.Fab")
			(hide yes)
			(effects
				(font
					(size 1 1)
					(thickness 0.15)
				)
			)
		)
		(sheetname "/Power/")
		(sheetfile "power.kicad_sch")
		(attr smd)
		(fp_rect
			(start -0.925 -0.47)
			(end 0.925 0.47)
			(stroke
				(width 0.05)
				(type default)
			)
			(fill no)
			(layer "F.CrtYd")
		)
		(fp_line
			(start -0.494 0.248)
			(end -0.494 -0.25)
			(stroke
				(width 0.15)
				(type solid)
			)
			(layer "F.Fab")
		)
		(fp_line
			(start 0.504 0.248)
			(end -0.494 0.248)
			(stroke
				(width 0.15)
				(type solid)
			)
			(layer "F.Fab")
		)
		(fp_line
			(start -0.494 -0.25)
			(end 0.504 -0.25)
			(stroke
				(width 0.15)
				(type solid)
			)
			(layer "F.Fab")
		)
		(fp_line
			(start 0.504 -0.25)
			(end 0.504 0.248)
			(stroke
				(width 0.15)
				(type solid)
			)
			(layer "F.Fab")
		)
		(pad "1" smd roundrect
			(at -0.48 0 270)
			(size 0.59 0.64)
			(layers "F.Cu" "F.Mask" "F.Paste")
			(roundrect_rratio 0.25)
			(net 28 "GND")
			(pintype "passive")
		)
		(pad "2" smd roundrect
			(at 0.48 0 270)
			(size 0.59 0.64)
			(layers "F.Cu" "F.Mask" "F.Paste")
			(roundrect_rratio 0.25)
			(net 326 "/Power/DVDD_VCC")
			(pintype "passive")
		)
	)
	(footprint "antmicro-footprints:R_0402_1005Metric"
		(layer "B.Cu")
		(at 96.45 101.1)
		(descr "Resistor SMD 0402")
		(tags "resistor SMD 0402")
		(property "Reference" "R62"
			(at 0.9 -0.316667 0)
			(layer "B.SilkS")
			(effects
				(font
					(size 0.7 0.7)
					(thickness 0.15)
				)
				(justify right top mirror)
			)
		)
		(property "Value" "R_3k3_0402"
			(at -1.011843 -1.772046 0)
			(layer "B.Fab")
			(hide yes)
			(effects
				(font
					(size 0.7 0.7)
					(thickness 0.15)
				)
				(justify right top mirror)
			)
		)
		(property "Datasheet" "https://www.bourns.com/docs/product-datasheets/cr.pdf"
			(at 0 0 0)
			(layer "B.Fab")
			(hide yes)
			(effects
				(font
					(size 1.27 1.27)
					(thickness 0.15)
				)
				(justify mirror)
			)
		)
		(property "Description" "SMD Chip Resistor, 3.3 kohm, ± 1%, 63 mW, 0402 [1005 Metric], Thick Film, General Purpose"
			(at 0 0 0)
			(layer "B.Fab")
			(hide yes)
			(effects
				(font
					(size 1.27 1.27)
					(thickness 0.15)
				)
				(justify mirror)
			)
		)
		(property "MPN" "CR0402-FX-3301GLF"
			(at 0 0 0)
			(unlocked yes)
			(layer "B.Fab")
			(hide yes)
			(effects
				(font
					(size 1 1)
					(thickness 0.15)
				)
				(justify mirror)
			)
		)
		(property "Manufacturer" "Bourns"
			(at 0 0 0)
			(unlocked yes)
			(layer "B.Fab")
			(hide yes)
			(effects
				(font
					(size 1 1)
					(thickness 0.15)
				)
				(justify mirror)
			)
		)
		(property "License" "Apache-2.0"
			(at 0 0 0)
			(unlocked yes)
			(layer "B.Fab")
			(hide yes)
			(effects
				(font
					(size 1 1)
					(thickness 0.15)
				)
				(justify mirror)
			)
		)
		(property "Author" "Antmicro"
			(at 0 0 0)
			(unlocked yes)
			(layer "B.Fab")
			(hide yes)
			(effects
				(font
					(size 1 1)
					(thickness 0.15)
				)
				(justify mirror)
			)
		)
		(property "Val" "3k3"
			(at 0 0 0)
			(unlocked yes)
			(layer "B.Fab")
			(hide yes)
			(effects
				(font
					(size 1 1)
					(thickness 0.15)
				)
				(justify mirror)
			)
		)
		(property "Tolerance" "1%"
			(at 0 0 0)
			(unlocked yes)
			(layer "B.Fab")
			(hide yes)
			(effects
				(font
					(size 1 1)
					(thickness 0.15)
				)
				(justify mirror)
			)
		)
		(sheetname "/X710-AT2 10GbE/")
		(sheetfile "x710-at2-10gbe.kicad_sch")
		(attr smd)
		(fp_rect
			(start -0.925 0.47)
			(end 0.925 -0.47)
			(stroke
				(width 0.05)
				(type default)
			)
			(fill no)
			(layer "B.CrtYd")
		)
		(fp_rect
			(start -0.5 0.25)
			(end 0.5 -0.25)
			(stroke
				(width 0.15)
				(type solid)
			)
			(fill no)
			(layer "B.Fab")
		)
		(pad "1" smd roundrect
			(at -0.48 0)
			(size 0.59 0.64)
			(layers "B.Cu" "B.Mask" "B.Paste")
			(roundrect_rratio 0.25)
			(net 101 "/X710-AT2 10GbE/MDIO2_SDA2")
			(pintype "passive")
		)
		(pad "2" smd roundrect
			(at 0.48 0)
			(size 0.59 0.64)
			(layers "B.Cu" "B.Mask" "B.Paste")
			(roundrect_rratio 0.25)
			(net 7 "+3V3")
			(pintype "passive")
		)
	)
	(footprint "antmicro-footprints:R_0402_1005Metric"
		(layer "B.Cu")
		(at 106.2 70.25 -90)
		(descr "Resistor SMD 0402")
		(tags "resistor SMD 0402")
		(property "Reference" "R92"
			(at 0.9 -0.48 90)
			(layer "B.SilkS")
			(effects
				(font
					(size 0.7 0.7)
					(thickness 0.15)
				)
				(justify left bottom mirror)
			)
		)
		(property "Value" "R_10k_0402"
			(at -1.011843 -1.772046 90)
			(layer "B.Fab")
			(hide yes)
			(effects
				(font
					(size 0.7 0.7)
					(thickness 0.15)
				)
				(justify left bottom mirror)
			)
		)
		(property "Datasheet" "https://www.bourns.com/docs/product-datasheets/cr.pdf"
			(at 0 0 90)
			(layer "B.Fab")
			(hide yes)
			(effects
				(font
					(size 1.27 1.27)
					(thickness 0.15)
				)
				(justify mirror)
			)
		)
		(property "Description" "SMD Chip Resistor, 10 kohm, ± 1%, 62.5 mW, 0402 [1005 Metric], Thick Film, General Purpose"
			(at 0 0 90)
			(layer "B.Fab")
			(hide yes)
			(effects
				(font
					(size 1.27 1.27)
					(thickness 0.15)
				)
				(justify mirror)
			)
		)
		(property "MPN" "CR0402-FX-1002GLF"
			(at 0 0 270)
			(unlocked yes)
			(layer "B.Fab")
			(hide yes)
			(effects
				(font
					(size 1 1)
					(thickness 0.15)
				)
				(justify mirror)
			)
		)
		(property "Manufacturer" "Bourns"
			(at 0 0 270)
			(unlocked yes)
			(layer "B.Fab")
			(hide yes)
			(effects
				(font
					(size 1 1)
					(thickness 0.15)
				)
				(justify mirror)
			)
		)
		(property "License" "Apache-2.0"
			(at 0 0 270)
			(unlocked yes)
			(layer "B.Fab")
			(hide yes)
			(effects
				(font
					(size 1 1)
					(thickness 0.15)
				)
				(justify mirror)
			)
		)
		(property "Author" "Antmicro"
			(at 0 0 270)
			(unlocked yes)
			(layer "B.Fab")
			(hide yes)
			(effects
				(font
					(size 1 1)
					(thickness 0.15)
				)
				(justify mirror)
			)
		)
		(property "Val" "10k"
			(at 0 0 270)
			(unlocked yes)
			(layer "B.Fab")
			(hide yes)
			(effects
				(font
					(size 1 1)
					(thickness 0.15)
				)
				(justify mirror)
			)
		)
		(property "Tolerance" "1%"
			(at 0 0 270)
			(unlocked yes)
			(layer "B.Fab")
			(hide yes)
			(effects
				(font
					(size 1 1)
					(thickness 0.15)
				)
				(justify mirror)
			)
		)
		(sheetname "/X710-AT2 Misc/")
		(sheetfile "x710-at2-mics.kicad_sch")
		(attr smd)
		(fp_rect
			(start -0.925 0.47)
			(end 0.925 -0.47)
			(stroke
				(width 0.05)
				(type default)
			)
			(fill no)
			(layer "B.CrtYd")
		)
		(fp_rect
			(start -0.5 0.25)
			(end 0.5 -0.25)
			(stroke
				(width 0.15)
				(type solid)
			)
			(fill no)
			(layer "B.Fab")
		)
		(pad "1" smd roundrect
			(at -0.48 0 270)
			(size 0.59 0.64)
			(layers "B.Cu" "B.Mask" "B.Paste")
			(roundrect_rratio 0.25)
			(net 394 "/OCuLink/SMBus.SCL")
			(pintype "passive")
		)
		(pad "2" smd roundrect
			(at 0.48 0 270)
			(size 0.59 0.64)
			(layers "B.Cu" "B.Mask" "B.Paste")
			(roundrect_rratio 0.25)
			(net 7 "+3V3")
			(pintype "passive")
		)
	)
	(footprint "antmicro-footprints:R_0402_1005Metric"
		(layer "B.Cu")
		(at 95.95 96.5 -90)
		(descr "Resistor SMD 0402")
		(tags "resistor SMD 0402")
		(property "Reference" "R99"
			(at 1.15 -3.35 90)
			(layer "B.SilkS")
			(effects
				(font
					(size 0.7 0.7)
					(thickness 0.15)
				)
				(justify right bottom mirror)
			)
		)
		(property "Value" "R_10k_0402"
			(at -1.011843 -1.772046 90)
			(layer "B.Fab")
			(hide yes)
			(effects
				(font
					(size 0.7 0.7)
					(thickness 0.15)
				)
				(justify left bottom mirror)
			)
		)
		(property "Datasheet" "https://www.bourns.com/docs/product-datasheets/cr.pdf"
			(at 0 0 90)
			(layer "B.Fab")
			(hide yes)
			(effects
				(font
					(size 1.27 1.27)
					(thickness 0.15)
				)
				(justify mirror)
			)
		)
		(property "Description" "SMD Chip Resistor, 10 kohm, ± 1%, 62.5 mW, 0402 [1005 Metric], Thick Film, General Purpose"
			(at 0 0 90)
			(layer "B.Fab")
			(hide yes)
			(effects
				(font
					(size 1.27 1.27)
					(thickness 0.15)
				)
				(justify mirror)
			)
		)
		(property "MPN" "CR0402-FX-1002GLF"
			(at 0 0 270)
			(unlocked yes)
			(layer "B.Fab")
			(hide yes)
			(effects
				(font
					(size 1 1)
					(thickness 0.15)
				)
				(justify mirror)
			)
		)
		(property "Manufacturer" "Bourns"
			(at 0 0 270)
			(unlocked yes)
			(layer "B.Fab")
			(hide yes)
			(effects
				(font
					(size 1 1)
					(thickness 0.15)
				)
				(justify mirror)
			)
		)
		(property "License" "Apache-2.0"
			(at 0 0 270)
			(unlocked yes)
			(layer "B.Fab")
			(hide yes)
			(effects
				(font
					(size 1 1)
					(thickness 0.15)
				)
				(justify mirror)
			)
		)
		(property "Author" "Antmicro"
			(at 0 0 270)
			(unlocked yes)
			(layer "B.Fab")
			(hide yes)
			(effects
				(font
					(size 1 1)
					(thickness 0.15)
				)
				(justify mirror)
			)
		)
		(property "Val" "10k"
			(at 0 0 270)
			(unlocked yes)
			(layer "B.Fab")
			(hide yes)
			(effects
				(font
					(size 1 1)
					(thickness 0.15)
				)
				(justify mirror)
			)
		)
		(property "Tolerance" "1%"
			(at 0 0 270)
			(unlocked yes)
			(layer "B.Fab")
			(hide yes)
			(effects
				(font
					(size 1 1)
					(thickness 0.15)
				)
				(justify mirror)
			)
		)
		(sheetname "/X710-AT2 Misc/")
		(sheetfile "x710-at2-mics.kicad_sch")
		(attr smd)
		(fp_rect
			(start -0.925 0.47)
			(end 0.925 -0.47)
			(stroke
				(width 0.05)
				(type default)
			)
			(fill no)
			(layer "B.CrtYd")
		)
		(fp_rect
			(start -0.5 0.25)
			(end 0.5 -0.25)
			(stroke
				(width 0.15)
				(type solid)
			)
			(fill no)
			(layer "B.Fab")
		)
		(pad "1" smd roundrect
			(at -0.48 0 270)
			(size 0.59 0.64)
			(layers "B.Cu" "B.Mask" "B.Paste")
			(roundrect_rratio 0.25)
			(net 289 "/X710-AT2 Misc/~{PCI_DIS}")
			(pintype "passive")
		)
		(pad "2" smd roundrect
			(at 0.48 0 270)
			(size 0.59 0.64)
			(layers "B.Cu" "B.Mask" "B.Paste")
			(roundrect_rratio 0.25)
			(net 7 "+3V3")
			(pintype "passive")
		)
	)
	(footprint "antmicro-footprints:R_0402_1005Metric"
		(layer "B.Cu")
		(at 106.2 68.15 -90)
		(descr "Resistor SMD 0402")
		(tags "resistor SMD 0402")
		(property "Reference" "R162"
			(at -3.64 -0.44 90)
			(layer "B.SilkS")
			(effects
				(font
					(size 0.7 0.7)
					(thickness 0.15)
				)
				(justify left bottom mirror)
			)
		)
		(property "Value" "R_0R_0402"
			(at -1.011843 -1.772046 90)
			(layer "B.Fab")
			(hide yes)
			(effects
				(font
					(size 0.7 0.7)
					(thickness 0.15)
				)
				(justify left bottom mirror)
			)
		)
		(property "Datasheet" "https://industrial.panasonic.com/cdbs/www-data/pdf/RDA0000/AOA0000C301.pdf"
			(at 0 0 90)
			(layer "B.Fab")
			(hide yes)
			(effects
				(font
					(size 1.27 1.27)
					(thickness 0.15)
				)
				(justify mirror)
			)
		)
		(property "Description" "SMD Chip Resistor, Jumper, 0 ohm, 100 mW, 0402 [1005 Metric], Thick Film, General Purpose"
			(at 0 0 90)
			(layer "B.Fab")
			(hide yes)
			(effects
				(font
					(size 1.27 1.27)
					(thickness 0.15)
				)
				(justify mirror)
			)
		)
		(property "MPN" "ERJ2GE0R00X"
			(at 0 0 270)
			(unlocked yes)
			(layer "B.Fab")
			(hide yes)
			(effects
				(font
					(size 1 1)
					(thickness 0.15)
				)
				(justify mirror)
			)
		)
		(property "Manufacturer" "Panasonic"
			(at 0 0 270)
			(unlocked yes)
			(layer "B.Fab")
			(hide yes)
			(effects
				(font
					(size 1 1)
					(thickness 0.15)
				)
				(justify mirror)
			)
		)
		(property "License" "Apache-2.0"
			(at 0 0 270)
			(unlocked yes)
			(layer "B.Fab")
			(hide yes)
			(effects
				(font
					(size 1 1)
					(thickness 0.15)
				)
				(justify mirror)
			)
		)
		(property "Author" "Antmicro"
			(at 0 0 270)
			(unlocked yes)
			(layer "B.Fab")
			(hide yes)
			(effects
				(font
					(size 1 1)
					(thickness 0.15)
				)
				(justify mirror)
			)
		)
		(property "Val" "0R"
			(at 0 0 270)
			(unlocked yes)
			(layer "B.Fab")
			(hide yes)
			(effects
				(font
					(size 1 1)
					(thickness 0.15)
				)
				(justify mirror)
			)
		)
		(property "Tolerance" "~"
			(at 0 0 270)
			(unlocked yes)
			(layer "B.Fab")
			(hide yes)
			(effects
				(font
					(size 1 1)
					(thickness 0.15)
				)
				(justify mirror)
			)
		)
		(property "Current" "1A"
			(at 0 0 270)
			(unlocked yes)
			(layer "B.Fab")
			(hide yes)
			(effects
				(font
					(size 1 1)
					(thickness 0.15)
				)
				(justify mirror)
			)
		)
		(sheetname "/OCuLink/")
		(sheetfile "oculink.kicad_sch")
		(attr smd)
		(fp_rect
			(start -0.925 0.47)
			(end 0.925 -0.47)
			(stroke
				(width 0.05)
				(type default)
			)
			(fill no)
			(layer "B.CrtYd")
		)
		(fp_rect
			(start -0.5 0.25)
			(end 0.5 -0.25)
			(stroke
				(width 0.15)
				(type solid)
			)
			(fill no)
			(layer "B.Fab")
		)
		(pad "1" smd roundrect
			(at -0.48 0 270)
			(size 0.59 0.64)
			(layers "B.Cu" "B.Mask" "B.Paste")
			(roundrect_rratio 0.25)
			(net 304 "/OCuLink/SCL")
			(pintype "passive")
		)
		(pad "2" smd roundrect
			(at 0.48 0 270)
			(size 0.59 0.64)
			(layers "B.Cu" "B.Mask" "B.Paste")
			(roundrect_rratio 0.25)
			(net 394 "/OCuLink/SMBus.SCL")
			(pintype "passive")
		)
	)
	(footprint "antmicro-footprints:C_0402_1005Metric"
		(layer "B.Cu")
		(at 91.2 96.45 -90)
		(descr "Capacitor SMD 0402")
		(tags "capacitor SMD 0402")
		(property "Reference" "C121"
			(at -14.39 -0.412657 90)
			(layer "B.SilkS")
			(effects
				(font
					(size 0.7 0.7)
					(thickness 0.15)
				)
				(justify left bottom mirror)
			)
		)
		(property "Value" "C_1u_25V_0402"
			(at -1.022927 -2.155213 90)
			(layer "B.Fab")
			(hide yes)
			(effects
				(font
					(size 0.7 0.7)
					(thickness 0.15)
				)
				(justify left bottom mirror)
			)
		)
		(property "Datasheet" "https://www.murata.com/products/productdetail?partno=GRM155R61E105KE11%23"
			(at 0 0 90)
			(layer "B.Fab")
			(hide yes)
			(effects
				(font
					(size 1.27 1.27)
					(thickness 0.15)
				)
				(justify mirror)
			)
		)
		(property "Description" "SMD Multilayer Ceramic Capacitor, 1 µF, 25 V, 0402 [1005 Metric], ± 10%, X5R, GRM Series"
			(at 0 0 90)
			(layer "B.Fab")
			(hide yes)
			(effects
				(font
					(size 1.27 1.27)
					(thickness 0.15)
				)
				(justify mirror)
			)
		)
		(property "MPN" "GRM155R61E105KE11J"
			(at 0 0 270)
			(unlocked yes)
			(layer "B.Fab")
			(hide yes)
			(effects
				(font
					(size 1 1)
					(thickness 0.15)
				)
				(justify mirror)
			)
		)
		(property "Manufacturer" "Murata"
			(at 0 0 270)
			(unlocked yes)
			(layer "B.Fab")
			(hide yes)
			(effects
				(font
					(size 1 1)
					(thickness 0.15)
				)
				(justify mirror)
			)
		)
		(property "License" "Apache-2.0"
			(at 0 0 270)
			(unlocked yes)
			(layer "B.Fab")
			(hide yes)
			(effects
				(font
					(size 1 1)
					(thickness 0.15)
				)
				(justify mirror)
			)
		)
		(property "Author" "Antmicro"
			(at 0 0 270)
			(unlocked yes)
			(layer "B.Fab")
			(hide yes)
			(effects
				(font
					(size 1 1)
					(thickness 0.15)
				)
				(justify mirror)
			)
		)
		(property "Val" "1u"
			(at 0 0 270)
			(unlocked yes)
			(layer "B.Fab")
			(hide yes)
			(effects
				(font
					(size 1 1)
					(thickness 0.15)
				)
				(justify mirror)
			)
		)
		(property "Voltage" "25V"
			(at 0 0 270)
			(unlocked yes)
			(layer "B.Fab")
			(hide yes)
			(effects
				(font
					(size 1 1)
					(thickness 0.15)
				)
				(justify mirror)
			)
		)
		(property "Dielectric" "X5R"
			(at 0 0 270)
			(unlocked yes)
			(layer "B.Fab")
			(hide yes)
			(effects
				(font
					(size 1 1)
					(thickness 0.15)
				)
				(justify mirror)
			)
		)
		(sheetname "/X710-AT2 power/")
		(sheetfile "x710-at2-power.kicad_sch")
		(attr smd)
		(fp_rect
			(start -0.925 0.47)
			(end 0.925 -0.47)
			(stroke
				(width 0.05)
				(type default)
			)
			(fill no)
			(layer "B.CrtYd")
		)
		(fp_line
			(start -0.494 0.25)
			(end 0.504 0.25)
			(stroke
				(width 0.15)
				(type solid)
			)
			(layer "B.Fab")
		)
		(fp_line
			(start 0.504 0.25)
			(end 0.504 -0.248)
			(stroke
				(width 0.15)
				(type solid)
			)
			(layer "B.Fab")
		)
		(fp_line
			(start -0.494 -0.248)
			(end -0.494 0.25)
			(stroke
				(width 0.15)
				(type solid)
			)
			(layer "B.Fab")
		)
		(fp_line
			(start 0.504 -0.248)
			(end -0.494 -0.248)
			(stroke
				(width 0.15)
				(type solid)
			)
			(layer "B.Fab")
		)
		(pad "1" smd roundrect
			(at -0.48 0 270)
			(size 0.59 0.64)
			(layers "B.Cu" "B.Mask" "B.Paste")
			(roundrect_rratio 0.25)
			(net 28 "GND")
			(pintype "passive")
		)
		(pad "2" smd roundrect
			(at 0.48 0 270)
			(size 0.59 0.64)
			(layers "B.Cu" "B.Mask" "B.Paste")
			(roundrect_rratio 0.25)
			(net 9 "VCCD")
			(pintype "passive")
		)
	)
	(footprint "antmicro-footprints:TP_SMD_1mm"
		(layer "B.Cu")
		(at 84.74 74.55 -90)
		(property "Reference" "TP35"
			(at -1.13 9.818102 90)
			(layer "B.SilkS")
			(effects
				(font
					(size 0.7 0.7)
					(thickness 0.15)
				)
				(justify left bottom mirror)
			)
		)
		(property "Value" "TP_1mm_SMD"
			(at 0 -1.4 90)
			(layer "B.Fab")
			(hide yes)
			(effects
				(font
					(size 0.7 0.7)
					(thickness 0.15)
				)
				(justify left bottom mirror)
			)
		)
		(property "Description" "Test point 1mm SMD"
			(at 0 0 90)
			(layer "B.Fab")
			(hide yes)
			(effects
				(font
					(size 1.27 1.27)
					(thickness 0.15)
				)
				(justify mirror)
			)
		)
		(property "MPN" ""
			(at 0 0 90)
			(unlocked yes)
			(layer "B.Fab")
			(hide yes)
			(effects
				(font
					(size 1 1)
					(thickness 0.15)
				)
				(justify mirror)
			)
		)
		(property "Manufacturer" ""
			(at 0 0 90)
			(unlocked yes)
			(layer "B.Fab")
			(hide yes)
			(effects
				(font
					(size 1 1)
					(thickness 0.15)
				)
				(justify mirror)
			)
		)
		(property "Author" "Antmicro"
			(at 0 0 90)
			(unlocked yes)
			(layer "B.Fab")
			(hide yes)
			(effects
				(font
					(size 1 1)
					(thickness 0.15)
				)
				(justify mirror)
			)
		)
		(property "License" "Apache-2.0"
			(at 0 0 90)
			(unlocked yes)
			(layer "B.Fab")
			(hide yes)
			(effects
				(font
					(size 1 1)
					(thickness 0.15)
				)
				(justify mirror)
			)
		)
		(sheetname "/X710-AT2 power/")
		(sheetfile "x710-at2-power.kicad_sch")
		(attr exclude_from_pos_files exclude_from_bom)
		(fp_circle
			(center 0 0)
			(end 0.6 0)
			(stroke
				(width 0.05)
				(type default)
			)
			(fill no)
			(layer "B.CrtYd")
		)
		(pad "1" smd circle
			(at 0 0 270)
			(size 1 1)
			(layers "B.Cu" "B.Mask")
			(net 1 "VCCA")
			(pinfunction "1")
			(pintype "passive")
		)
	)
	(footprint "antmicro-footprints:Tag-Connect_TC2050-IDC-NL_2x5_P1.27mm"
		(layer "B.Cu")
		(at 55.7 74.35 180)
		(property "Reference" "J10"
			(at -0.3 2.35 0)
			(layer "B.SilkS")
			(effects
				(font
					(size 0.7 0.7)
					(thickness 0.15)
				)
				(justify left bottom mirror)
			)
		)
		(property "Value" "Tag-Connect_TC2050-IDC-NL_2x5_P1.27mm"
			(at 0 -4.4 0)
			(layer "B.Fab")
			(hide yes)
			(effects
				(font
					(size 0.7 0.7)
					(thickness 0.15)
				)
				(justify left bottom mirror)
			)
		)
		(property "Datasheet" "https://www.tag-connect.com/wp-content/uploads/bsk-pdf-manager/TC2050-IDC-NL_Datasheet_8.pdf"
			(at 0 0 0)
			(layer "B.Fab")
			(hide yes)
			(effects
				(font
					(size 1.27 1.27)
					(thickness 0.15)
				)
				(justify mirror)
			)
		)
		(property "Description" "Tag Connect 2x5 1.27mm terminal"
			(at 0 0 0)
			(layer "B.Fab")
			(hide yes)
			(effects
				(font
					(size 1.27 1.27)
					(thickness 0.15)
				)
				(justify mirror)
			)
		)
		(property "MPN" "TC2050-IDC-NL"
			(at 0 0 180)
			(unlocked yes)
			(layer "B.Fab")
			(hide yes)
			(effects
				(font
					(size 1 1)
					(thickness 0.15)
				)
				(justify mirror)
			)
		)
		(property "Manufacturer" "Tag Connect"
			(at 0 0 180)
			(unlocked yes)
			(layer "B.Fab")
			(hide yes)
			(effects
				(font
					(size 1 1)
					(thickness 0.15)
				)
				(justify mirror)
			)
		)
		(property "Author" "Antmicro"
			(at 0 0 180)
			(unlocked yes)
			(layer "B.Fab")
			(hide yes)
			(effects
				(font
					(size 1 1)
					(thickness 0.15)
				)
				(justify mirror)
			)
		)
		(property "License" "Apache-2.0"
			(at 0 0 180)
			(unlocked yes)
			(layer "B.Fab")
			(hide yes)
			(effects
				(font
					(size 1 1)
					(thickness 0.15)
				)
				(justify mirror)
			)
		)
		(sheetname "/Flash memory/")
		(sheetfile "flash-memory.kicad_sch")
		(attr exclude_from_pos_files exclude_from_bom dnp)
		(fp_line
			(start 5.1 1.7)
			(end 5.1 -1.7)
			(stroke
				(width 0.15)
				(type solid)
			)
			(layer "B.SilkS")
		)
		(fp_line
			(start 4.7 2.05)
			(end 5.1 1.7)
			(stroke
				(width 0.15)
				(type solid)
			)
			(layer "B.SilkS")
		)
		(fp_line
			(start 4.7 -2.049)
			(end 5.1 -1.7)
			(stroke
				(width 0.15)
				(type solid)
			)
			(layer "B.SilkS")
		)
		(fp_line
			(start 4.7 -2.049)
			(end -2.3 -2.049)
			(stroke
				(width 0.15)
				(type solid)
			)
			(layer "B.SilkS")
		)
		(fp_line
			(start -2.2 2.05)
			(end 4.7 2.05)
			(stroke
				(width 0.15)
				(type solid)
			)
			(layer "B.SilkS")
		)
		(fp_line
			(start -2.3 -2.049)
			(end -5.08 -0.8)
			(stroke
				(width 0.15)
				(type solid)
			)
			(layer "B.SilkS")
		)
		(fp_line
			(start -3.101 -1.269)
			(end -3.101 -0.4)
			(stroke
				(width 0.15)
				(type solid)
			)
			(layer "B.SilkS")
		)
		(fp_line
			(start -5.08 0.9)
			(end -2.2 2.05)
			(stroke
				(width 0.15)
				(type solid)
			)
			(layer "B.SilkS")
		)
		(fp_line
			(start -5.08 -0.8)
			(end -5.08 0.9)
			(stroke
				(width 0.15)
				(type solid)
			)
			(layer "B.SilkS")
		)
		(fp_line
			(start 5.32 1.8)
			(end 5.32 -1.8)
			(stroke
				(width 0.05)
				(type solid)
			)
			(layer "B.CrtYd")
		)
		(fp_line
			(start 4.8 2.3)
			(end 5.32 1.8)
			(stroke
				(width 0.05)
				(type solid)
			)
			(layer "B.CrtYd")
		)
		(fp_line
			(start 4.8 -2.29)
			(end 5.32 -1.8)
			(stroke
				(width 0.05)
				(type solid)
			)
			(layer "B.CrtYd")
		)
		(fp_line
			(start 4.8 -2.29)
			(end -2.4 -2.29)
			(stroke
				(width 0.05)
				(type solid)
			)
			(layer "B.CrtYd")
		)
		(fp_line
			(start -2.3 2.3)
			(end 4.8 2.3)
			(stroke
				(width 0.05)
				(type solid)
			)
			(layer "B.CrtYd")
		)
		(fp_line
			(start -2.4 -2.29)
			(end -5.33 -1)
			(stroke
				(width 0.05)
				(type solid)
			)
			(layer "B.CrtYd")
		)
		(fp_line
			(start -5.33 1.1)
			(end -2.3 2.3)
			(stroke
				(width 0.05)
				(type solid)
			)
			(layer "B.CrtYd")
		)
		(fp_line
			(start -5.33 -1)
			(end -5.33 1.1)
			(stroke
				(width 0.05)
				(type solid)
			)
			(layer "B.CrtYd")
		)
		(pad "" np_thru_hole circle
			(at -3.81 0 180)
			(size 0.9906 0.9906)
			(drill 0.9906)
			(layers "*.Cu" "*.Mask")
		)
		(pad "" np_thru_hole circle
			(at 3.809 -1.015 180)
			(size 0.9906 0.9906)
			(drill 0.9906)
			(layers "*.Cu" "*.Mask")
		)
		(pad "" np_thru_hole circle
			(at 3.809 1.016 180)
			(size 0.9906 0.9906)
			(drill 0.9906)
			(layers "*.Cu" "*.Mask")
		)
		(pad "1" connect circle
			(at -2.54 -0.634 180)
			(size 0.7874 0.7874)
			(layers "B.Cu" "B.Mask")
			(net 110 "/Flash memory/+3V3_FLASH")
			(pinfunction "3V3")
			(pintype "passive")
		)
		(pad "2" connect circle
			(at -1.27 -0.634 180)
			(size 0.7874 0.7874)
			(layers "B.Cu" "B.Mask")
			(net 105 "/Flash memory/FLASH.~{CE}")
			(pinfunction "SPI_CS")
			(pintype "passive")
		)
		(pad "3" connect circle
			(at 0 -0.634 180)
			(size 0.7874 0.7874)
			(layers "B.Cu" "B.Mask")
			(net 28 "GND")
			(pinfunction "GND")
			(pintype "passive")
		)
		(pad "4" connect circle
			(at 1.269 -0.634 180)
			(size 0.7874 0.7874)
			(layers "B.Cu" "B.Mask")
			(net 106 "/Flash memory/FLASH.CLK")
			(pinfunction "SPI_SCK")
			(pintype "passive")
		)
		(pad "5" connect circle
			(at 2.539 -0.634 180)
			(size 0.7874 0.7874)
			(layers "B.Cu" "B.Mask")
			(net 28 "GND")
			(pinfunction "GND")
			(pintype "passive")
		)
		(pad "6" connect circle
			(at 2.539 0.635 180)
			(size 0.7874 0.7874)
			(layers "B.Cu" "B.Mask")
			(net 140 "/Flash memory/FLASH.MISO")
			(pinfunction "SPI_MISO")
			(pintype "passive")
		)
		(pad "7" connect circle
			(at 1.269 0.635 180)
			(size 0.7874 0.7874)
			(layers "B.Cu" "B.Mask")
			(net 91 "unconnected-(J10-Pad7)")
			(pinfunction "NC")
			(pintype "passive")
		)
		(pad "8" connect circle
			(at 0 0.635 180)
			(size 0.7874 0.7874)
			(layers "B.Cu" "B.Mask")
			(net 139 "/Flash memory/FLASH.MOSI")
			(pinfunction "SPI_MOSI")
			(pintype "passive")
		)
		(pad "9" connect circle
			(at -1.27 0.635 180)
			(size 0.7874 0.7874)
			(layers "B.Cu" "B.Mask")
			(net 28 "GND")
			(pinfunction "GND")
			(pintype "passive")
		)
		(pad "10" connect circle
			(at -2.54 0.635 180)
			(size 0.7874 0.7874)
			(layers "B.Cu" "B.Mask")
			(net 111 "unconnected-(J10-Pad10)")
			(pinfunction "SPI_NC")
			(pintype "passive+no_connect")
		)
	)
	(footprint "antmicro-footprints:R_0402_1005Metric"
		(layer "B.Cu")
		(at 110.49 86.76 90)
		(descr "Resistor SMD 0402")
		(tags "resistor SMD 0402")
		(property "Reference" "R130"
			(at 0.81 -0.31 90)
			(layer "B.SilkS")
			(effects
				(font
					(size 0.7 0.7)
					(thickness 0.15)
				)
				(justify right top mirror)
			)
		)
		(property "Value" "R_1k_0402"
			(at -1.011843 -1.772046 90)
			(layer "B.Fab")
			(hide yes)
			(effects
				(font
					(size 0.7 0.7)
					(thickness 0.15)
				)
				(justify right top mirror)
			)
		)
		(property "Datasheet" "https://www.bourns.com/docs/product-datasheets/cr.pdf"
			(at 0 0 90)
			(layer "B.Fab")
			(hide yes)
			(effects
				(font
					(size 1.27 1.27)
					(thickness 0.15)
				)
				(justify mirror)
			)
		)
		(property "Description" "SMD Chip Resistor, 1 kohm, ± 1%, 63 mW, 0402 [1005 Metric], Thick Film, General Purpose"
			(at 0 0 90)
			(layer "B.Fab")
			(hide yes)
			(effects
				(font
					(size 1.27 1.27)
					(thickness 0.15)
				)
				(justify mirror)
			)
		)
		(property "MPN" "CR0402-FX-1001GLF"
			(at 0 0 90)
			(unlocked yes)
			(layer "B.Fab")
			(hide yes)
			(effects
				(font
					(size 1 1)
					(thickness 0.15)
				)
				(justify mirror)
			)
		)
		(property "Manufacturer" "Bourns"
			(at 0 0 90)
			(unlocked yes)
			(layer "B.Fab")
			(hide yes)
			(effects
				(font
					(size 1 1)
					(thickness 0.15)
				)
				(justify mirror)
			)
		)
		(property "License" "Apache-2.0"
			(at 0 0 90)
			(unlocked yes)
			(layer "B.Fab")
			(hide yes)
			(effects
				(font
					(size 1 1)
					(thickness 0.15)
				)
				(justify mirror)
			)
		)
		(property "Author" "Antmicro"
			(at 0 0 90)
			(unlocked yes)
			(layer "B.Fab")
			(hide yes)
			(effects
				(font
					(size 1 1)
					(thickness 0.15)
				)
				(justify mirror)
			)
		)
		(property "Val" "1k"
			(at 0 0 90)
			(unlocked yes)
			(layer "B.Fab")
			(hide yes)
			(effects
				(font
					(size 1 1)
					(thickness 0.15)
				)
				(justify mirror)
			)
		)
		(property "Tolerance" "1%"
			(at 0 0 90)
			(unlocked yes)
			(layer "B.Fab")
			(hide yes)
			(effects
				(font
					(size 1 1)
					(thickness 0.15)
				)
				(justify mirror)
			)
		)
		(sheetname "/X710-AT2 RSVD/")
		(sheetfile "x710-at2-rsvd.kicad_sch")
		(attr smd)
		(fp_rect
			(start -0.925 0.47)
			(end 0.925 -0.47)
			(stroke
				(width 0.05)
				(type default)
			)
			(fill no)
			(layer "B.CrtYd")
		)
		(fp_rect
			(start -0.5 0.25)
			(end 0.5 -0.25)
			(stroke
				(width 0.15)
				(type solid)
			)
			(fill no)
			(layer "B.Fab")
		)
		(pad "1" smd roundrect
			(at -0.48 0 90)
			(size 0.59 0.64)
			(layers "B.Cu" "B.Mask" "B.Paste")
			(roundrect_rratio 0.25)
			(net 121 "/X710-AT2 RSVD/DEBUG_Y16")
			(pintype "passive")
		)
		(pad "2" smd roundrect
			(at 0.48 0 90)
			(size 0.59 0.64)
			(layers "B.Cu" "B.Mask" "B.Paste")
			(roundrect_rratio 0.25)
			(net 114 "/X710-AT2 RSVD/DEBUG_EN")
			(pintype "passive")
		)
	)
	(footprint "antmicro-footprints:R_0402_1005Metric"
		(layer "B.Cu")
		(at 96.95 96.5 90)
		(descr "Resistor SMD 0402")
		(tags "resistor SMD 0402")
		(property "Reference" "R108"
			(at -1.15 3.3 90)
			(layer "B.SilkS")
			(effects
				(font
					(size 0.7 0.7)
					(thickness 0.15)
				)
				(justify right bottom mirror)
			)
		)
		(property "Value" "R_100R_0402"
			(at -1.011843 -1.772046 90)
			(layer "B.Fab")
			(hide yes)
			(effects
				(font
					(size 0.7 0.7)
					(thickness 0.15)
				)
				(justify right top mirror)
			)
		)
		(property "Datasheet" "https://www.bourns.com/docs/product-datasheets/cr.pdf"
			(at 0 0 90)
			(layer "B.Fab")
			(hide yes)
			(effects
				(font
					(size 1.27 1.27)
					(thickness 0.15)
				)
				(justify mirror)
			)
		)
		(property "Description" "SMD Chip Resistor, 100 ohm, ± 1%, 62.5 mW, 0402 [1005 Metric], Thick Film, General Purpose"
			(at 0 0 90)
			(layer "B.Fab")
			(hide yes)
			(effects
				(font
					(size 1.27 1.27)
					(thickness 0.15)
				)
				(justify mirror)
			)
		)
		(property "MPN" "CR0402-FX-1000GLF"
			(at 0 0 90)
			(unlocked yes)
			(layer "B.Fab")
			(hide yes)
			(effects
				(font
					(size 1 1)
					(thickness 0.15)
				)
				(justify mirror)
			)
		)
		(property "Manufacturer" "Bourns"
			(at 0 0 90)
			(unlocked yes)
			(layer "B.Fab")
			(hide yes)
			(effects
				(font
					(size 1 1)
					(thickness 0.15)
				)
				(justify mirror)
			)
		)
		(property "License" "Apache-2.0"
			(at 0 0 90)
			(unlocked yes)
			(layer "B.Fab")
			(hide yes)
			(effects
				(font
					(size 1 1)
					(thickness 0.15)
				)
				(justify mirror)
			)
		)
		(property "Author" "Antmicro"
			(at 0 0 90)
			(unlocked yes)
			(layer "B.Fab")
			(hide yes)
			(effects
				(font
					(size 1 1)
					(thickness 0.15)
				)
				(justify mirror)
			)
		)
		(property "Val" "100R"
			(at 0 0 90)
			(unlocked yes)
			(layer "B.Fab")
			(hide yes)
			(effects
				(font
					(size 1 1)
					(thickness 0.15)
				)
				(justify mirror)
			)
		)
		(property "Tolerance" "1%"
			(at 0 0 90)
			(unlocked yes)
			(layer "B.Fab")
			(hide yes)
			(effects
				(font
					(size 1 1)
					(thickness 0.15)
				)
				(justify mirror)
			)
		)
		(sheetname "/X710-AT2 Misc/")
		(sheetfile "x710-at2-mics.kicad_sch")
		(attr smd exclude_from_pos_files exclude_from_bom dnp)
		(fp_rect
			(start -0.925 0.47)
			(end 0.925 -0.47)
			(stroke
				(width 0.05)
				(type default)
			)
			(fill no)
			(layer "B.CrtYd")
		)
		(fp_rect
			(start -0.5 0.25)
			(end 0.5 -0.25)
			(stroke
				(width 0.15)
				(type solid)
			)
			(fill no)
			(layer "B.Fab")
		)
		(pad "1" smd roundrect
			(at -0.48 0 90)
			(size 0.59 0.64)
			(layers "B.Cu" "B.Mask" "B.Paste")
			(roundrect_rratio 0.25)
			(net 28 "GND")
			(pintype "passive")
		)
		(pad "2" smd roundrect
			(at 0.48 0 90)
			(size 0.59 0.64)
			(layers "B.Cu" "B.Mask" "B.Paste")
			(roundrect_rratio 0.25)
			(net 289 "/X710-AT2 Misc/~{PCI_DIS}")
			(pintype "passive")
		)
	)
	(footprint "antmicro-footprints:TP_SMD_0.75mm"
		(layer "B.Cu")
		(at 103.55 105.7 90)
		(property "Reference" "TP8"
			(at 0.565351 0.658866 180)
			(layer "B.SilkS")
			(effects
				(font
					(size 0.7 0.7)
					(thickness 0.15)
				)
				(justify right top mirror)
			)
		)
		(property "Value" "TP_0.75mm_SMD"
			(at 0 -1.2 90)
			(layer "B.Fab")
			(hide yes)
			(effects
				(font
					(size 0.7 0.7)
					(thickness 0.15)
				)
				(justify right top mirror)
			)
		)
		(property "Description" "SMT test point"
			(at 0 0 90)
			(layer "B.Fab")
			(hide yes)
			(effects
				(font
					(size 1.27 1.27)
					(thickness 0.15)
				)
				(justify mirror)
			)
		)
		(property "MPN" ""
			(at 0 0 90)
			(unlocked yes)
			(layer "B.Fab")
			(hide yes)
			(effects
				(font
					(size 1 1)
					(thickness 0.15)
				)
				(justify mirror)
			)
		)
		(property "Manufacturer" ""
			(at 0 0 90)
			(unlocked yes)
			(layer "B.Fab")
			(hide yes)
			(effects
				(font
					(size 1 1)
					(thickness 0.15)
				)
				(justify mirror)
			)
		)
		(property "Author" "Antmicro"
			(at 0 0 90)
			(unlocked yes)
			(layer "B.Fab")
			(hide yes)
			(effects
				(font
					(size 1 1)
					(thickness 0.15)
				)
				(justify mirror)
			)
		)
		(property "License" "Apache-2.0"
			(at 0 0 90)
			(unlocked yes)
			(layer "B.Fab")
			(hide yes)
			(effects
				(font
					(size 1 1)
					(thickness 0.15)
				)
				(justify mirror)
			)
		)
		(sheetname "/X710-AT2 Misc/")
		(sheetfile "x710-at2-mics.kicad_sch")
		(attr exclude_from_pos_files exclude_from_bom)
		(fp_circle
			(center 0 0)
			(end 0.475 0)
			(stroke
				(width 0.05)
				(type default)
			)
			(fill no)
			(layer "B.CrtYd")
		)
		(pad "1" smd circle
			(at 0 0 90)
			(size 0.75 0.75)
			(layers "B.Cu" "B.Mask")
			(net 361 "/X710-AT2 Misc/NCSI.TXD_1")
			(pinfunction "1")
			(pintype "passive")
		)
	)
	(footprint "antmicro-footprints:C_0402_1005Metric"
		(layer "B.Cu")
		(at 78.44 105.08 90)
		(descr "Capacitor SMD 0402")
		(tags "capacitor SMD 0402")
		(property "Reference" "C82"
			(at -11.81 -0.04 90)
			(layer "B.SilkS")
			(effects
				(font
					(size 0.7 0.7)
					(thickness 0.15)
				)
				(justify right top mirror)
			)
		)
		(property "Value" "C_1u_25V_0402"
			(at -1.022927 -2.155213 90)
			(layer "B.Fab")
			(hide yes)
			(effects
				(font
					(size 0.7 0.7)
					(thickness 0.15)
				)
				(justify right top mirror)
			)
		)
		(property "Datasheet" "https://www.murata.com/products/productdetail?partno=GRM155R61E105KE11%23"
			(at 0 0 90)
			(layer "B.Fab")
			(hide yes)
			(effects
				(font
					(size 1.27 1.27)
					(thickness 0.15)
				)
				(justify mirror)
			)
		)
		(property "Description" "SMD Multilayer Ceramic Capacitor, 1 µF, 25 V, 0402 [1005 Metric], ± 10%, X5R, GRM Series"
			(at 0 0 90)
			(layer "B.Fab")
			(hide yes)
			(effects
				(font
					(size 1.27 1.27)
					(thickness 0.15)
				)
				(justify mirror)
			)
		)
		(property "MPN" "GRM155R61E105KE11J"
			(at 0 0 90)
			(unlocked yes)
			(layer "B.Fab")
			(hide yes)
			(effects
				(font
					(size 1 1)
					(thickness 0.15)
				)
				(justify mirror)
			)
		)
		(property "Manufacturer" "Murata"
			(at 0 0 90)
			(unlocked yes)
			(layer "B.Fab")
			(hide yes)
			(effects
				(font
					(size 1 1)
					(thickness 0.15)
				)
				(justify mirror)
			)
		)
		(property "License" "Apache-2.0"
			(at 0 0 90)
			(unlocked yes)
			(layer "B.Fab")
			(hide yes)
			(effects
				(font
					(size 1 1)
					(thickness 0.15)
				)
				(justify mirror)
			)
		)
		(property "Author" "Antmicro"
			(at 0 0 90)
			(unlocked yes)
			(layer "B.Fab")
			(hide yes)
			(effects
				(font
					(size 1 1)
					(thickness 0.15)
				)
				(justify mirror)
			)
		)
		(property "Val" "1u"
			(at 0 0 90)
			(unlocked yes)
			(layer "B.Fab")
			(hide yes)
			(effects
				(font
					(size 1 1)
					(thickness 0.15)
				)
				(justify mirror)
			)
		)
		(property "Voltage" "25V"
			(at 0 0 90)
			(unlocked yes)
			(layer "B.Fab")
			(hide yes)
			(effects
				(font
					(size 1 1)
					(thickness 0.15)
				)
				(justify mirror)
			)
		)
		(property "Dielectric" "X5R"
			(at 0 0 90)
			(unlocked yes)
			(layer "B.Fab")
			(hide yes)
			(effects
				(font
					(size 1 1)
					(thickness 0.15)
				)
				(justify mirror)
			)
		)
		(sheetname "/X710-AT2 power/")
		(sheetfile "x710-at2-power.kicad_sch")
		(attr smd)
		(fp_rect
			(start -0.925 0.47)
			(end 0.925 -0.47)
			(stroke
				(width 0.05)
				(type default)
			)
			(fill no)
			(layer "B.CrtYd")
		)
		(fp_line
			(start 0.504 -0.248)
			(end -0.494 -0.248)
			(stroke
				(width 0.15)
				(type solid)
			)
			(layer "B.Fab")
		)
		(fp_line
			(start -0.494 -0.248)
			(end -0.494 0.25)
			(stroke
				(width 0.15)
				(type solid)
			)
			(layer "B.Fab")
		)
		(fp_line
			(start 0.504 0.25)
			(end 0.504 -0.248)
			(stroke
				(width 0.15)
				(type solid)
			)
			(layer "B.Fab")
		)
		(fp_line
			(start -0.494 0.25)
			(end 0.504 0.25)
			(stroke
				(width 0.15)
				(type solid)
			)
			(layer "B.Fab")
		)
		(pad "1" smd roundrect
			(at -0.48 0 90)
			(size 0.59 0.64)
			(layers "B.Cu" "B.Mask" "B.Paste")
			(roundrect_rratio 0.25)
			(net 28 "GND")
			(pintype "passive")
		)
		(pad "2" smd roundrect
			(at 0.48 0 90)
			(size 0.59 0.64)
			(layers "B.Cu" "B.Mask" "B.Paste")
			(roundrect_rratio 0.25)
			(net 6 "DVDD")
			(pintype "passive")
		)
	)
	(footprint "antmicro-footprints:R_0402_1005Metric"
		(layer "B.Cu")
		(at 91.7 103.45 180)
		(descr "Resistor SMD 0402")
		(tags "resistor SMD 0402")
		(property "Reference" "R77"
			(at -2.95 -0.42 0)
			(layer "B.SilkS")
			(effects
				(font
					(size 0.7 0.7)
					(thickness 0.15)
				)
				(justify left bottom mirror)
			)
		)
		(property "Value" "R_100R_0402"
			(at -1.011843 -1.772046 0)
			(layer "B.Fab")
			(hide yes)
			(effects
				(font
					(size 0.7 0.7)
					(thickness 0.15)
				)
				(justify left bottom mirror)
			)
		)
		(property "Datasheet" "https://www.bourns.com/docs/product-datasheets/cr.pdf"
			(at 0 0 0)
			(layer "B.Fab")
			(hide yes)
			(effects
				(font
					(size 1.27 1.27)
					(thickness 0.15)
				)
				(justify mirror)
			)
		)
		(property "Description" "SMD Chip Resistor, 100 ohm, ± 1%, 62.5 mW, 0402 [1005 Metric], Thick Film, General Purpose"
			(at 0 0 0)
			(layer "B.Fab")
			(hide yes)
			(effects
				(font
					(size 1.27 1.27)
					(thickness 0.15)
				)
				(justify mirror)
			)
		)
		(property "MPN" "CR0402-FX-1000GLF"
			(at 0 0 180)
			(unlocked yes)
			(layer "B.Fab")
			(hide yes)
			(effects
				(font
					(size 1 1)
					(thickness 0.15)
				)
				(justify mirror)
			)
		)
		(property "Manufacturer" "Bourns"
			(at 0 0 180)
			(unlocked yes)
			(layer "B.Fab")
			(hide yes)
			(effects
				(font
					(size 1 1)
					(thickness 0.15)
				)
				(justify mirror)
			)
		)
		(property "License" "Apache-2.0"
			(at 0 0 180)
			(unlocked yes)
			(layer "B.Fab")
			(hide yes)
			(effects
				(font
					(size 1 1)
					(thickness 0.15)
				)
				(justify mirror)
			)
		)
		(property "Author" "Antmicro"
			(at 0 0 180)
			(unlocked yes)
			(layer "B.Fab")
			(hide yes)
			(effects
				(font
					(size 1 1)
					(thickness 0.15)
				)
				(justify mirror)
			)
		)
		(property "Val" "100R"
			(at 0 0 180)
			(unlocked yes)
			(layer "B.Fab")
			(hide yes)
			(effects
				(font
					(size 1 1)
					(thickness 0.15)
				)
				(justify mirror)
			)
		)
		(property "Tolerance" "1%"
			(at 0 0 180)
			(unlocked yes)
			(layer "B.Fab")
			(hide yes)
			(effects
				(font
					(size 1 1)
					(thickness 0.15)
				)
				(justify mirror)
			)
		)
		(sheetname "/X710-AT2 10GbE/")
		(sheetfile "x710-at2-10gbe.kicad_sch")
		(attr smd exclude_from_pos_files exclude_from_bom dnp)
		(fp_rect
			(start -0.925 0.47)
			(end 0.925 -0.47)
			(stroke
				(width 0.05)
				(type default)
			)
			(fill no)
			(layer "B.CrtYd")
		)
		(fp_rect
			(start -0.5 0.25)
			(end 0.5 -0.25)
			(stroke
				(width 0.15)
				(type solid)
			)
			(fill no)
			(layer "B.Fab")
		)
		(pad "1" smd roundrect
			(at -0.48 0 180)
			(size 0.59 0.64)
			(layers "B.Cu" "B.Mask" "B.Paste")
			(roundrect_rratio 0.25)
			(net 28 "GND")
			(pintype "passive")
		)
		(pad "2" smd roundrect
			(at 0.48 0 180)
			(size 0.59 0.64)
			(layers "B.Cu" "B.Mask" "B.Paste")
			(roundrect_rratio 0.25)
			(net 85 "/X710-AT2 10GbE/OSC_SEL")
			(pintype "passive")
		)
	)
	(footprint "antmicro-footprints:C_0402_1005Metric"
		(layer "B.Cu")
		(at 79.55 97.4 90)
		(descr "Capacitor SMD 0402")
		(tags "capacitor SMD 0402")
		(property "Reference" "C137"
			(at 1.02 -0.28 90)
			(layer "B.SilkS")
			(effects
				(font
					(size 0.7 0.7)
					(thickness 0.15)
				)
				(justify right top mirror)
			)
		)
		(property "Value" "C_1u_25V_0402"
			(at -1.022927 -2.155213 90)
			(layer "B.Fab")
			(hide yes)
			(effects
				(font
					(size 0.7 0.7)
					(thickness 0.15)
				)
				(justify right top mirror)
			)
		)
		(property "Datasheet" "https://www.murata.com/products/productdetail?partno=GRM155R61E105KE11%23"
			(at 0 0 90)
			(layer "B.Fab")
			(hide yes)
			(effects
				(font
					(size 1.27 1.27)
					(thickness 0.15)
				)
				(justify mirror)
			)
		)
		(property "Description" "SMD Multilayer Ceramic Capacitor, 1 µF, 25 V, 0402 [1005 Metric], ± 10%, X5R, GRM Series"
			(at 0 0 90)
			(layer "B.Fab")
			(hide yes)
			(effects
				(font
					(size 1.27 1.27)
					(thickness 0.15)
				)
				(justify mirror)
			)
		)
		(property "MPN" "GRM155R61E105KE11J"
			(at 0 0 90)
			(unlocked yes)
			(layer "B.Fab")
			(hide yes)
			(effects
				(font
					(size 1 1)
					(thickness 0.15)
				)
				(justify mirror)
			)
		)
		(property "Manufacturer" "Murata"
			(at 0 0 90)
			(unlocked yes)
			(layer "B.Fab")
			(hide yes)
			(effects
				(font
					(size 1 1)
					(thickness 0.15)
				)
				(justify mirror)
			)
		)
		(property "License" "Apache-2.0"
			(at 0 0 90)
			(unlocked yes)
			(layer "B.Fab")
			(hide yes)
			(effects
				(font
					(size 1 1)
					(thickness 0.15)
				)
				(justify mirror)
			)
		)
		(property "Author" "Antmicro"
			(at 0 0 90)
			(unlocked yes)
			(layer "B.Fab")
			(hide yes)
			(effects
				(font
					(size 1 1)
					(thickness 0.15)
				)
				(justify mirror)
			)
		)
		(property "Val" "1u"
			(at 0 0 90)
			(unlocked yes)
			(layer "B.Fab")
			(hide yes)
			(effects
				(font
					(size 1 1)
					(thickness 0.15)
				)
				(justify mirror)
			)
		)
		(property "Voltage" "25V"
			(at 0 0 90)
			(unlocked yes)
			(layer "B.Fab")
			(hide yes)
			(effects
				(font
					(size 1 1)
					(thickness 0.15)
				)
				(justify mirror)
			)
		)
		(property "Dielectric" "X5R"
			(at 0 0 90)
			(unlocked yes)
			(layer "B.Fab")
			(hide yes)
			(effects
				(font
					(size 1 1)
					(thickness 0.15)
				)
				(justify mirror)
			)
		)
		(sheetname "/X710-AT2 power/")
		(sheetfile "x710-at2-power.kicad_sch")
		(attr smd)
		(fp_rect
			(start -0.925 0.47)
			(end 0.925 -0.47)
			(stroke
				(width 0.05)
				(type default)
			)
			(fill no)
			(layer "B.CrtYd")
		)
		(fp_line
			(start 0.504 -0.248)
			(end -0.494 -0.248)
			(stroke
				(width 0.15)
				(type solid)
			)
			(layer "B.Fab")
		)
		(fp_line
			(start -0.494 -0.248)
			(end -0.494 0.25)
			(stroke
				(width 0.15)
				(type solid)
			)
			(layer "B.Fab")
		)
		(fp_line
			(start 0.504 0.25)
			(end 0.504 -0.248)
			(stroke
				(width 0.15)
				(type solid)
			)
			(layer "B.Fab")
		)
		(fp_line
			(start -0.494 0.25)
			(end 0.504 0.25)
			(stroke
				(width 0.15)
				(type solid)
			)
			(layer "B.Fab")
		)
		(pad "1" smd roundrect
			(at -0.48 0 90)
			(size 0.59 0.64)
			(layers "B.Cu" "B.Mask" "B.Paste")
			(roundrect_rratio 0.25)
			(net 28 "GND")
			(pintype "passive")
		)
		(pad "2" smd roundrect
			(at 0.48 0 90)
			(size 0.59 0.64)
			(layers "B.Cu" "B.Mask" "B.Paste")
			(roundrect_rratio 0.25)
			(net 7 "+3V3")
			(pintype "passive")
		)
	)
	(footprint "antmicro-footprints:C_0402_1005Metric"
		(layer "B.Cu")
		(at 76.95 100.35 180)
		(descr "Capacitor SMD 0402")
		(tags "capacitor SMD 0402")
		(property "Reference" "C101"
			(at -0.85 -0.45 0)
			(layer "B.SilkS")
			(effects
				(font
					(size 0.7 0.7)
					(thickness 0.15)
				)
				(justify right bottom mirror)
			)
		)
		(property "Value" "C_1u_25V_0402"
			(at -1.022927 -2.155213 0)
			(layer "B.Fab")
			(hide yes)
			(effects
				(font
					(size 0.7 0.7)
					(thickness 0.15)
				)
				(justify left bottom mirror)
			)
		)
		(property "Datasheet" "https://www.murata.com/products/productdetail?partno=GRM155R61E105KE11%23"
			(at 0 0 0)
			(layer "B.Fab")
			(hide yes)
			(effects
				(font
					(size 1.27 1.27)
					(thickness 0.15)
				)
				(justify mirror)
			)
		)
		(property "Description" "SMD Multilayer Ceramic Capacitor, 1 µF, 25 V, 0402 [1005 Metric], ± 10%, X5R, GRM Series"
			(at 0 0 0)
			(layer "B.Fab")
			(hide yes)
			(effects
				(font
					(size 1.27 1.27)
					(thickness 0.15)
				)
				(justify mirror)
			)
		)
		(property "MPN" "GRM155R61E105KE11J"
			(at 0 0 180)
			(unlocked yes)
			(layer "B.Fab")
			(hide yes)
			(effects
				(font
					(size 1 1)
					(thickness 0.15)
				)
				(justify mirror)
			)
		)
		(property "Manufacturer" "Murata"
			(at 0 0 180)
			(unlocked yes)
			(layer "B.Fab")
			(hide yes)
			(effects
				(font
					(size 1 1)
					(thickness 0.15)
				)
				(justify mirror)
			)
		)
		(property "License" "Apache-2.0"
			(at 0 0 180)
			(unlocked yes)
			(layer "B.Fab")
			(hide yes)
			(effects
				(font
					(size 1 1)
					(thickness 0.15)
				)
				(justify mirror)
			)
		)
		(property "Author" "Antmicro"
			(at 0 0 180)
			(unlocked yes)
			(layer "B.Fab")
			(hide yes)
			(effects
				(font
					(size 1 1)
					(thickness 0.15)
				)
				(justify mirror)
			)
		)
		(property "Val" "1u"
			(at 0 0 180)
			(unlocked yes)
			(layer "B.Fab")
			(hide yes)
			(effects
				(font
					(size 1 1)
					(thickness 0.15)
				)
				(justify mirror)
			)
		)
		(property "Voltage" "25V"
			(at 0 0 180)
			(unlocked yes)
			(layer "B.Fab")
			(hide yes)
			(effects
				(font
					(size 1 1)
					(thickness 0.15)
				)
				(justify mirror)
			)
		)
		(property "Dielectric" "X5R"
			(at 0 0 180)
			(unlocked yes)
			(layer "B.Fab")
			(hide yes)
			(effects
				(font
					(size 1 1)
					(thickness 0.15)
				)
				(justify mirror)
			)
		)
		(sheetname "/X710-AT2 power/")
		(sheetfile "x710-at2-power.kicad_sch")
		(attr smd)
		(fp_rect
			(start -0.925 0.47)
			(end 0.925 -0.47)
			(stroke
				(width 0.05)
				(type default)
			)
			(fill no)
			(layer "B.CrtYd")
		)
		(fp_line
			(start 0.504 0.25)
			(end 0.504 -0.248)
			(stroke
				(width 0.15)
				(type solid)
			)
			(layer "B.Fab")
		)
		(fp_line
			(start 0.504 -0.248)
			(end -0.494 -0.248)
			(stroke
				(width 0.15)
				(type solid)
			)
			(layer "B.Fab")
		)
		(fp_line
			(start -0.494 0.25)
			(end 0.504 0.25)
			(stroke
				(width 0.15)
				(type solid)
			)
			(layer "B.Fab")
		)
		(fp_line
			(start -0.494 -0.248)
			(end -0.494 0.25)
			(stroke
				(width 0.15)
				(type solid)
			)
			(layer "B.Fab")
		)
		(pad "1" smd roundrect
			(at -0.48 0 180)
			(size 0.59 0.64)
			(layers "B.Cu" "B.Mask" "B.Paste")
			(roundrect_rratio 0.25)
			(net 28 "GND")
			(pintype "passive")
		)
		(pad "2" smd roundrect
			(at 0.48 0 180)
			(size 0.59 0.64)
			(layers "B.Cu" "B.Mask" "B.Paste")
			(roundrect_rratio 0.25)
			(net 18 "+1V88")
			(pintype "passive")
		)
	)
	(footprint "antmicro-footprints:R_0402_1005Metric"
		(layer "B.Cu")
		(at 83.3 102 -90)
		(descr "Resistor SMD 0402")
		(tags "resistor SMD 0402")
		(property "Reference" "R121"
			(at -11.92 -0.3 90)
			(layer "B.SilkS")
			(effects
				(font
					(size 0.7 0.7)
					(thickness 0.15)
				)
				(justify left bottom mirror)
			)
		)
		(property "Value" "R_1k_0402"
			(at -1.011843 -1.772046 90)
			(layer "B.Fab")
			(hide yes)
			(effects
				(font
					(size 0.7 0.7)
					(thickness 0.15)
				)
				(justify left bottom mirror)
			)
		)
		(property "Datasheet" "https://www.bourns.com/docs/product-datasheets/cr.pdf"
			(at 0 0 90)
			(layer "B.Fab")
			(hide yes)
			(effects
				(font
					(size 1.27 1.27)
					(thickness 0.15)
				)
				(justify mirror)
			)
		)
		(property "Description" "SMD Chip Resistor, 1 kohm, ± 1%, 63 mW, 0402 [1005 Metric], Thick Film, General Purpose"
			(at 0 0 90)
			(layer "B.Fab")
			(hide yes)
			(effects
				(font
					(size 1.27 1.27)
					(thickness 0.15)
				)
				(justify mirror)
			)
		)
		(property "MPN" "CR0402-FX-1001GLF"
			(at 0 0 270)
			(unlocked yes)
			(layer "B.Fab")
			(hide yes)
			(effects
				(font
					(size 1 1)
					(thickness 0.15)
				)
				(justify mirror)
			)
		)
		(property "Manufacturer" "Bourns"
			(at 0 0 270)
			(unlocked yes)
			(layer "B.Fab")
			(hide yes)
			(effects
				(font
					(size 1 1)
					(thickness 0.15)
				)
				(justify mirror)
			)
		)
		(property "License" "Apache-2.0"
			(at 0 0 270)
			(unlocked yes)
			(layer "B.Fab")
			(hide yes)
			(effects
				(font
					(size 1 1)
					(thickness 0.15)
				)
				(justify mirror)
			)
		)
		(property "Author" "Antmicro"
			(at 0 0 270)
			(unlocked yes)
			(layer "B.Fab")
			(hide yes)
			(effects
				(font
					(size 1 1)
					(thickness 0.15)
				)
				(justify mirror)
			)
		)
		(property "Val" "1k"
			(at 0 0 270)
			(unlocked yes)
			(layer "B.Fab")
			(hide yes)
			(effects
				(font
					(size 1 1)
					(thickness 0.15)
				)
				(justify mirror)
			)
		)
		(property "Tolerance" "1%"
			(at 0 0 270)
			(unlocked yes)
			(layer "B.Fab")
			(hide yes)
			(effects
				(font
					(size 1 1)
					(thickness 0.15)
				)
				(justify mirror)
			)
		)
		(sheetname "/X710-AT2 Misc/")
		(sheetfile "x710-at2-mics.kicad_sch")
		(attr smd)
		(fp_rect
			(start -0.925 0.47)
			(end 0.925 -0.47)
			(stroke
				(width 0.05)
				(type default)
			)
			(fill no)
			(layer "B.CrtYd")
		)
		(fp_rect
			(start -0.5 0.25)
			(end 0.5 -0.25)
			(stroke
				(width 0.15)
				(type solid)
			)
			(fill no)
			(layer "B.Fab")
		)
		(pad "1" smd roundrect
			(at -0.48 0 270)
			(size 0.59 0.64)
			(layers "B.Cu" "B.Mask" "B.Paste")
			(roundrect_rratio 0.25)
			(net 28 "GND")
			(pintype "passive")
		)
		(pad "2" smd roundrect
			(at 0.48 0 270)
			(size 0.59 0.64)
			(layers "B.Cu" "B.Mask" "B.Paste")
			(roundrect_rratio 0.25)
			(net 116 "/X710-AT2 Misc/~{PHY_TRST}")
			(pintype "passive")
		)
	)
	(footprint "antmicro-footprints:Tag-Connect_TC2050-IDC-NL_2x5_P1.27mm"
		(layer "B.Cu")
		(at 55.7 81.65 180)
		(property "Reference" "J7"
			(at 0.1 2.3 0)
			(layer "B.SilkS")
			(effects
				(font
					(size 0.7 0.7)
					(thickness 0.15)
				)
				(justify left bottom mirror)
			)
		)
		(property "Value" "Tag-Connect_TC2050-IDC-NL_2x5_P1.27mm"
			(at 0 -4.4 0)
			(layer "B.Fab")
			(hide yes)
			(effects
				(font
					(size 0.7 0.7)
					(thickness 0.15)
				)
				(justify left bottom mirror)
			)
		)
		(property "Datasheet" "https://www.tag-connect.com/wp-content/uploads/bsk-pdf-manager/TC2050-IDC-NL_Datasheet_8.pdf"
			(at 0 0 0)
			(layer "B.Fab")
			(hide yes)
			(effects
				(font
					(size 1.27 1.27)
					(thickness 0.15)
				)
				(justify mirror)
			)
		)
		(property "Description" "Tag Connect 2x5 1.27mm terminal"
			(at 0 0 0)
			(layer "B.Fab")
			(hide yes)
			(effects
				(font
					(size 1.27 1.27)
					(thickness 0.15)
				)
				(justify mirror)
			)
		)
		(property "MPN" "TC2050-IDC-NL"
			(at 0 0 180)
			(unlocked yes)
			(layer "B.Fab")
			(hide yes)
			(effects
				(font
					(size 1 1)
					(thickness 0.15)
				)
				(justify mirror)
			)
		)
		(property "Manufacturer" "Tag Connect"
			(at 0 0 180)
			(unlocked yes)
			(layer "B.Fab")
			(hide yes)
			(effects
				(font
					(size 1 1)
					(thickness 0.15)
				)
				(justify mirror)
			)
		)
		(property "Author" "Antmicro"
			(at 0 0 180)
			(unlocked yes)
			(layer "B.Fab")
			(hide yes)
			(effects
				(font
					(size 1 1)
					(thickness 0.15)
				)
				(justify mirror)
			)
		)
		(property "License" "Apache-2.0"
			(at 0 0 180)
			(unlocked yes)
			(layer "B.Fab")
			(hide yes)
			(effects
				(font
					(size 1 1)
					(thickness 0.15)
				)
				(justify mirror)
			)
		)
		(sheetname "/X710-AT2 PCIe/")
		(sheetfile "x710-at2-pcie.kicad_sch")
		(attr exclude_from_pos_files exclude_from_bom dnp)
		(fp_line
			(start 5.1 1.7)
			(end 5.1 -1.7)
			(stroke
				(width 0.15)
				(type solid)
			)
			(layer "B.SilkS")
		)
		(fp_line
			(start 4.7 2.05)
			(end 5.1 1.7)
			(stroke
				(width 0.15)
				(type solid)
			)
			(layer "B.SilkS")
		)
		(fp_line
			(start 4.7 -2.049)
			(end 5.1 -1.7)
			(stroke
				(width 0.15)
				(type solid)
			)
			(layer "B.SilkS")
		)
		(fp_line
			(start 4.7 -2.049)
			(end -2.3 -2.049)
			(stroke
				(width 0.15)
				(type solid)
			)
			(layer "B.SilkS")
		)
		(fp_line
			(start -2.2 2.05)
			(end 4.7 2.05)
			(stroke
				(width 0.15)
				(type solid)
			)
			(layer "B.SilkS")
		)
		(fp_line
			(start -2.3 -2.049)
			(end -5.08 -0.8)
			(stroke
				(width 0.15)
				(type solid)
			)
			(layer "B.SilkS")
		)
		(fp_line
			(start -3.101 -1.269)
			(end -3.101 -0.4)
			(stroke
				(width 0.15)
				(type solid)
			)
			(layer "B.SilkS")
		)
		(fp_line
			(start -5.08 0.9)
			(end -2.2 2.05)
			(stroke
				(width 0.15)
				(type solid)
			)
			(layer "B.SilkS")
		)
		(fp_line
			(start -5.08 -0.8)
			(end -5.08 0.9)
			(stroke
				(width 0.15)
				(type solid)
			)
			(layer "B.SilkS")
		)
		(fp_line
			(start 5.32 1.8)
			(end 5.32 -1.8)
			(stroke
				(width 0.05)
				(type solid)
			)
			(layer "B.CrtYd")
		)
		(fp_line
			(start 4.8 2.3)
			(end 5.32 1.8)
			(stroke
				(width 0.05)
				(type solid)
			)
			(layer "B.CrtYd")
		)
		(fp_line
			(start 4.8 -2.29)
			(end 5.32 -1.8)
			(stroke
				(width 0.05)
				(type solid)
			)
			(layer "B.CrtYd")
		)
		(fp_line
			(start 4.8 -2.29)
			(end -2.4 -2.29)
			(stroke
				(width 0.05)
				(type solid)
			)
			(layer "B.CrtYd")
		)
		(fp_line
			(start -2.3 2.3)
			(end 4.8 2.3)
			(stroke
				(width 0.05)
				(type solid)
			)
			(layer "B.CrtYd")
		)
		(fp_line
			(start -2.4 -2.29)
			(end -5.33 -1)
			(stroke
				(width 0.05)
				(type solid)
			)
			(layer "B.CrtYd")
		)
		(fp_line
			(start -5.33 1.1)
			(end -2.3 2.3)
			(stroke
				(width 0.05)
				(type solid)
			)
			(layer "B.CrtYd")
		)
		(fp_line
			(start -5.33 -1)
			(end -5.33 1.1)
			(stroke
				(width 0.05)
				(type solid)
			)
			(layer "B.CrtYd")
		)
		(pad "" np_thru_hole circle
			(at -3.81 0 180)
			(size 0.9906 0.9906)
			(drill 0.9906)
			(layers "*.Cu" "*.Mask")
		)
		(pad "" np_thru_hole circle
			(at 3.809 -1.015 180)
			(size 0.9906 0.9906)
			(drill 0.9906)
			(layers "*.Cu" "*.Mask")
		)
		(pad "" np_thru_hole circle
			(at 3.809 1.016 180)
			(size 0.9906 0.9906)
			(drill 0.9906)
			(layers "*.Cu" "*.Mask")
		)
		(pad "1" connect circle
			(at -2.54 -0.634 180)
			(size 0.7874 0.7874)
			(layers "B.Cu" "B.Mask")
			(net 147 "unconnected-(J7-Pad1)")
			(pinfunction "3V3")
			(pintype "passive+no_connect")
		)
		(pad "2" connect circle
			(at -1.27 -0.634 180)
			(size 0.7874 0.7874)
			(layers "B.Cu" "B.Mask")
			(net 4 "/X710-AT2 PCIe/PCIe_JTAG.JTMS")
			(pinfunction "JTAG_TMS")
			(pintype "passive")
		)
		(pad "3" connect circle
			(at 0 -0.634 180)
			(size 0.7874 0.7874)
			(layers "B.Cu" "B.Mask")
			(net 28 "GND")
			(pinfunction "GND")
			(pintype "passive")
		)
		(pad "4" connect circle
			(at 1.269 -0.634 180)
			(size 0.7874 0.7874)
			(layers "B.Cu" "B.Mask")
			(net 16 "/X710-AT2 PCIe/PCIe_JTAG.JTCK")
			(pinfunction "JTAG_TCK")
			(pintype "passive")
		)
		(pad "5" connect circle
			(at 2.539 -0.634 180)
			(size 0.7874 0.7874)
			(layers "B.Cu" "B.Mask")
			(net 28 "GND")
			(pinfunction "GND")
			(pintype "passive")
		)
		(pad "6" connect circle
			(at 2.539 0.635 180)
			(size 0.7874 0.7874)
			(layers "B.Cu" "B.Mask")
			(net 8 "/X710-AT2 PCIe/PCIe_JTAG.JTDO")
			(pinfunction "JTAG_TDO")
			(pintype "passive")
		)
		(pad "7" connect circle
			(at 1.269 0.635 180)
			(size 0.7874 0.7874)
			(layers "B.Cu" "B.Mask")
			(net 148 "unconnected-(J7-Pad7)")
			(pinfunction "NC")
			(pintype "passive")
		)
		(pad "8" connect circle
			(at 0 0.635 180)
			(size 0.7874 0.7874)
			(layers "B.Cu" "B.Mask")
			(net 11 "/X710-AT2 PCIe/PCIe_JTAG.JTDI")
			(pinfunction "JTAG_TDI")
			(pintype "passive")
		)
		(pad "9" connect circle
			(at -1.27 0.635 180)
			(size 0.7874 0.7874)
			(layers "B.Cu" "B.Mask")
			(net 28 "GND")
			(pinfunction "GND")
			(pintype "passive")
		)
		(pad "10" connect circle
			(at -2.54 0.635 180)
			(size 0.7874 0.7874)
			(layers "B.Cu" "B.Mask")
			(net 15 "/X710-AT2 PCIe/PCIe_JTAG.~{JRST}")
			(pinfunction "JTAG_~{RESET}")
			(pintype "passive")
		)
	)
	(footprint "antmicro-footprints:C_0402_1005Metric"
		(layer "B.Cu")
		(at 87.225 102 90)
		(descr "Capacitor SMD 0402")
		(tags "capacitor SMD 0402")
		(property "Reference" "C98"
			(at 9.09 -0.447343 90)
			(layer "B.SilkS")
			(effects
				(font
					(size 0.7 0.7)
					(thickness 0.15)
				)
				(justify right top mirror)
			)
		)
		(property "Value" "C_1u_25V_0402"
			(at -1.022927 -2.155213 90)
			(layer "B.Fab")
			(hide yes)
			(effects
				(font
					(size 0.7 0.7)
					(thickness 0.15)
				)
				(justify right top mirror)
			)
		)
		(property "Datasheet" "https://www.murata.com/products/productdetail?partno=GRM155R61E105KE11%23"
			(at 0 0 90)
			(layer "B.Fab")
			(hide yes)
			(effects
				(font
					(size 1.27 1.27)
					(thickness 0.15)
				)
				(justify mirror)
			)
		)
		(property "Description" "SMD Multilayer Ceramic Capacitor, 1 µF, 25 V, 0402 [1005 Metric], ± 10%, X5R, GRM Series"
			(at 0 0 90)
			(layer "B.Fab")
			(hide yes)
			(effects
				(font
					(size 1.27 1.27)
					(thickness 0.15)
				)
				(justify mirror)
			)
		)
		(property "MPN" "GRM155R61E105KE11J"
			(at 0 0 90)
			(unlocked yes)
			(layer "B.Fab")
			(hide yes)
			(effects
				(font
					(size 1 1)
					(thickness 0.15)
				)
				(justify mirror)
			)
		)
		(property "Manufacturer" "Murata"
			(at 0 0 90)
			(unlocked yes)
			(layer "B.Fab")
			(hide yes)
			(effects
				(font
					(size 1 1)
					(thickness 0.15)
				)
				(justify mirror)
			)
		)
		(property "License" "Apache-2.0"
			(at 0 0 90)
			(unlocked yes)
			(layer "B.Fab")
			(hide yes)
			(effects
				(font
					(size 1 1)
					(thickness 0.15)
				)
				(justify mirror)
			)
		)
		(property "Author" "Antmicro"
			(at 0 0 90)
			(unlocked yes)
			(layer "B.Fab")
			(hide yes)
			(effects
				(font
					(size 1 1)
					(thickness 0.15)
				)
				(justify mirror)
			)
		)
		(property "Val" "1u"
			(at 0 0 90)
			(unlocked yes)
			(layer "B.Fab")
			(hide yes)
			(effects
				(font
					(size 1 1)
					(thickness 0.15)
				)
				(justify mirror)
			)
		)
		(property "Voltage" "25V"
			(at 0 0 90)
			(unlocked yes)
			(layer "B.Fab")
			(hide yes)
			(effects
				(font
					(size 1 1)
					(thickness 0.15)
				)
				(justify mirror)
			)
		)
		(property "Dielectric" "X5R"
			(at 0 0 90)
			(unlocked yes)
			(layer "B.Fab")
			(hide yes)
			(effects
				(font
					(size 1 1)
					(thickness 0.15)
				)
				(justify mirror)
			)
		)
		(sheetname "/X710-AT2 power/")
		(sheetfile "x710-at2-power.kicad_sch")
		(attr smd)
		(fp_rect
			(start -0.925 0.47)
			(end 0.925 -0.47)
			(stroke
				(width 0.05)
				(type default)
			)
			(fill no)
			(layer "B.CrtYd")
		)
		(fp_line
			(start 0.504 -0.248)
			(end -0.494 -0.248)
			(stroke
				(width 0.15)
				(type solid)
			)
			(layer "B.Fab")
		)
		(fp_line
			(start -0.494 -0.248)
			(end -0.494 0.25)
			(stroke
				(width 0.15)
				(type solid)
			)
			(layer "B.Fab")
		)
		(fp_line
			(start 0.504 0.25)
			(end 0.504 -0.248)
			(stroke
				(width 0.15)
				(type solid)
			)
			(layer "B.Fab")
		)
		(fp_line
			(start -0.494 0.25)
			(end 0.504 0.25)
			(stroke
				(width 0.15)
				(type solid)
			)
			(layer "B.Fab")
		)
		(pad "1" smd roundrect
			(at -0.48 0 90)
			(size 0.59 0.64)
			(layers "B.Cu" "B.Mask" "B.Paste")
			(roundrect_rratio 0.25)
			(net 28 "GND")
			(pintype "passive")
		)
		(pad "2" smd roundrect
			(at 0.48 0 90)
			(size 0.59 0.64)
			(layers "B.Cu" "B.Mask" "B.Paste")
			(roundrect_rratio 0.25)
			(net 1 "VCCA")
			(pintype "passive")
		)
	)
	(footprint "antmicro-footprints:TP_SMD_0.75mm"
		(layer "B.Cu")
		(at 110.95 69.1 90)
		(property "Reference" "TP15"
			(at 0.598685 0.625533 180)
			(layer "B.SilkS")
			(effects
				(font
					(size 0.7 0.7)
					(thickness 0.15)
				)
				(justify right top mirror)
			)
		)
		(property "Value" "TP_0.75mm_SMD"
			(at 0 -1.2 90)
			(layer "B.Fab")
			(hide yes)
			(effects
				(font
					(size 0.7 0.7)
					(thickness 0.15)
				)
				(justify right top mirror)
			)
		)
		(property "Description" "SMT test point"
			(at 0 0 90)
			(layer "B.Fab")
			(hide yes)
			(effects
				(font
					(size 1.27 1.27)
					(thickness 0.15)
				)
				(justify mirror)
			)
		)
		(property "MPN" ""
			(at 0 0 90)
			(unlocked yes)
			(layer "B.Fab")
			(hide yes)
			(effects
				(font
					(size 1 1)
					(thickness 0.15)
				)
				(justify mirror)
			)
		)
		(property "Manufacturer" ""
			(at 0 0 90)
			(unlocked yes)
			(layer "B.Fab")
			(hide yes)
			(effects
				(font
					(size 1 1)
					(thickness 0.15)
				)
				(justify mirror)
			)
		)
		(property "Author" "Antmicro"
			(at 0 0 90)
			(unlocked yes)
			(layer "B.Fab")
			(hide yes)
			(effects
				(font
					(size 1 1)
					(thickness 0.15)
				)
				(justify mirror)
			)
		)
		(property "License" "Apache-2.0"
			(at 0 0 90)
			(unlocked yes)
			(layer "B.Fab")
			(hide yes)
			(effects
				(font
					(size 1 1)
					(thickness 0.15)
				)
				(justify mirror)
			)
		)
		(sheetname "/OCuLink/")
		(sheetfile "oculink.kicad_sch")
		(attr exclude_from_pos_files exclude_from_bom)
		(fp_circle
			(center 0 0)
			(end 0.475 0)
			(stroke
				(width 0.05)
				(type default)
			)
			(fill no)
			(layer "B.CrtYd")
		)
		(pad "1" smd circle
			(at 0 0 90)
			(size 0.75 0.75)
			(layers "B.Cu" "B.Mask")
			(net 321 "/OCuLink/~{CPRSNT}_R")
			(pinfunction "1")
			(pintype "passive")
		)
	)
	(footprint "antmicro-footprints:R_0402_1005Metric"
		(layer "B.Cu")
		(at 96.45 106.1 180)
		(descr "Resistor SMD 0402")
		(tags "resistor SMD 0402")
		(property "Reference" "R84"
			(at -0.9 0.261111 0)
			(layer "B.SilkS")
			(effects
				(font
					(size 0.7 0.7)
					(thickness 0.15)
				)
				(justify right top mirror)
			)
		)
		(property "Value" "R_22R_0402"
			(at -1.011843 -1.772047 0)
			(layer "B.Fab")
			(hide yes)
			(effects
				(font
					(size 0.7 0.7)
					(thickness 0.15)
				)
				(justify left bottom mirror)
			)
		)
		(property "Datasheet" "https://www.bourns.com/docs/product-datasheets/cr.pdf"
			(at 0 0 0)
			(layer "B.Fab")
			(hide yes)
			(effects
				(font
					(size 1.27 1.27)
					(thickness 0.15)
				)
				(justify mirror)
			)
		)
		(property "Description" "SMD Chip Resistor, 22 ohm, ± 1%, 62.5 mW, 0402 [1005 Metric], Thick Film, General Purpose"
			(at 0 0 0)
			(layer "B.Fab")
			(hide yes)
			(effects
				(font
					(size 1.27 1.27)
					(thickness 0.15)
				)
				(justify mirror)
			)
		)
		(property "MPN" "CR0402-FX-22R0GLF"
			(at 0 0 180)
			(unlocked yes)
			(layer "B.Fab")
			(hide yes)
			(effects
				(font
					(size 1 1)
					(thickness 0.15)
				)
				(justify mirror)
			)
		)
		(property "Manufacturer" "Bourns"
			(at 0 0 180)
			(unlocked yes)
			(layer "B.Fab")
			(hide yes)
			(effects
				(font
					(size 1 1)
					(thickness 0.15)
				)
				(justify mirror)
			)
		)
		(property "License" "Apache-2.0"
			(at 0 0 180)
			(unlocked yes)
			(layer "B.Fab")
			(hide yes)
			(effects
				(font
					(size 1 1)
					(thickness 0.15)
				)
				(justify mirror)
			)
		)
		(property "Author" "Antmicro"
			(at 0 0 180)
			(unlocked yes)
			(layer "B.Fab")
			(hide yes)
			(effects
				(font
					(size 1 1)
					(thickness 0.15)
				)
				(justify mirror)
			)
		)
		(property "Val" "22R"
			(at 0 0 180)
			(unlocked yes)
			(layer "B.Fab")
			(hide yes)
			(effects
				(font
					(size 1 1)
					(thickness 0.15)
				)
				(justify mirror)
			)
		)
		(property "Tolerance" "1%"
			(at 0 0 180)
			(unlocked yes)
			(layer "B.Fab")
			(hide yes)
			(effects
				(font
					(size 1 1)
					(thickness 0.15)
				)
				(justify mirror)
			)
		)
		(sheetname "/X710-AT2 Misc/")
		(sheetfile "x710-at2-mics.kicad_sch")
		(attr smd)
		(fp_rect
			(start -0.925 0.47)
			(end 0.925 -0.47)
			(stroke
				(width 0.05)
				(type default)
			)
			(fill no)
			(layer "B.CrtYd")
		)
		(fp_rect
			(start -0.5 0.25)
			(end 0.5 -0.25)
			(stroke
				(width 0.15)
				(type solid)
			)
			(fill no)
			(layer "B.Fab")
		)
		(pad "1" smd roundrect
			(at -0.48 0 180)
			(size 0.59 0.64)
			(layers "B.Cu" "B.Mask" "B.Paste")
			(roundrect_rratio 0.25)
			(net 365 "/X710-AT2 Misc/NCSI.CRS_DV")
			(pintype "passive")
		)
		(pad "2" smd roundrect
			(at 0.48 0 180)
			(size 0.59 0.64)
			(layers "B.Cu" "B.Mask" "B.Paste")
			(roundrect_rratio 0.25)
			(net 160 "Net-(U9D-NCSI_CRS_DV)")
			(pintype "passive")
		)
	)
	(footprint "antmicro-footprints:C_0402_1005Metric"
		(layer "B.Cu")
		(at 90.225 102 90)
		(descr "Capacitor SMD 0402")
		(tags "capacitor SMD 0402")
		(property "Reference" "C88"
			(at 9.09 -0.447343 90)
			(layer "B.SilkS")
			(effects
				(font
					(size 0.7 0.7)
					(thickness 0.15)
				)
				(justify right top mirror)
			)
		)
		(property "Value" "C_1u_25V_0402"
			(at -1.022927 -2.155213 90)
			(layer "B.Fab")
			(hide yes)
			(effects
				(font
					(size 0.7 0.7)
					(thickness 0.15)
				)
				(justify right top mirror)
			)
		)
		(property "Datasheet" "https://www.murata.com/products/productdetail?partno=GRM155R61E105KE11%23"
			(at 0 0 90)
			(layer "B.Fab")
			(hide yes)
			(effects
				(font
					(size 1.27 1.27)
					(thickness 0.15)
				)
				(justify mirror)
			)
		)
		(property "Description" "SMD Multilayer Ceramic Capacitor, 1 µF, 25 V, 0402 [1005 Metric], ± 10%, X5R, GRM Series"
			(at 0 0 90)
			(layer "B.Fab")
			(hide yes)
			(effects
				(font
					(size 1.27 1.27)
					(thickness 0.15)
				)
				(justify mirror)
			)
		)
		(property "MPN" "GRM155R61E105KE11J"
			(at 0 0 90)
			(unlocked yes)
			(layer "B.Fab")
			(hide yes)
			(effects
				(font
					(size 1 1)
					(thickness 0.15)
				)
				(justify mirror)
			)
		)
		(property "Manufacturer" "Murata"
			(at 0 0 90)
			(unlocked yes)
			(layer "B.Fab")
			(hide yes)
			(effects
				(font
					(size 1 1)
					(thickness 0.15)
				)
				(justify mirror)
			)
		)
		(property "License" "Apache-2.0"
			(at 0 0 90)
			(unlocked yes)
			(layer "B.Fab")
			(hide yes)
			(effects
				(font
					(size 1 1)
					(thickness 0.15)
				)
				(justify mirror)
			)
		)
		(property "Author" "Antmicro"
			(at 0 0 90)
			(unlocked yes)
			(layer "B.Fab")
			(hide yes)
			(effects
				(font
					(size 1 1)
					(thickness 0.15)
				)
				(justify mirror)
			)
		)
		(property "Val" "1u"
			(at 0 0 90)
			(unlocked yes)
			(layer "B.Fab")
			(hide yes)
			(effects
				(font
					(size 1 1)
					(thickness 0.15)
				)
				(justify mirror)
			)
		)
		(property "Voltage" "25V"
			(at 0 0 90)
			(unlocked yes)
			(layer "B.Fab")
			(hide yes)
			(effects
				(font
					(size 1 1)
					(thickness 0.15)
				)
				(justify mirror)
			)
		)
		(property "Dielectric" "X5R"
			(at 0 0 90)
			(unlocked yes)
			(layer "B.Fab")
			(hide yes)
			(effects
				(font
					(size 1 1)
					(thickness 0.15)
				)
				(justify mirror)
			)
		)
		(sheetname "/X710-AT2 power/")
		(sheetfile "x710-at2-power.kicad_sch")
		(attr smd)
		(fp_rect
			(start -0.925 0.47)
			(end 0.925 -0.47)
			(stroke
				(width 0.05)
				(type default)
			)
			(fill no)
			(layer "B.CrtYd")
		)
		(fp_line
			(start 0.504 -0.248)
			(end -0.494 -0.248)
			(stroke
				(width 0.15)
				(type solid)
			)
			(layer "B.Fab")
		)
		(fp_line
			(start -0.494 -0.248)
			(end -0.494 0.25)
			(stroke
				(width 0.15)
				(type solid)
			)
			(layer "B.Fab")
		)
		(fp_line
			(start 0.504 0.25)
			(end 0.504 -0.248)
			(stroke
				(width 0.15)
				(type solid)
			)
			(layer "B.Fab")
		)
		(fp_line
			(start -0.494 0.25)
			(end 0.504 0.25)
			(stroke
				(width 0.15)
				(type solid)
			)
			(layer "B.Fab")
		)
		(pad "1" smd roundrect
			(at -0.48 0 90)
			(size 0.59 0.64)
			(layers "B.Cu" "B.Mask" "B.Paste")
			(roundrect_rratio 0.25)
			(net 28 "GND")
			(pintype "passive")
		)
		(pad "2" smd roundrect
			(at 0.48 0 90)
			(size 0.59 0.64)
			(layers "B.Cu" "B.Mask" "B.Paste")
			(roundrect_rratio 0.25)
			(net 1 "VCCA")
			(pintype "passive")
		)
	)
	(footprint "antmicro-footprints:TP_SMD_0.75mm"
		(layer "B.Cu")
		(at 110.95 67.1 90)
		(property "Reference" "TP14"
			(at 0.298685 0.858866 180)
			(layer "B.SilkS")
			(effects
				(font
					(size 0.7 0.7)
					(thickness 0.15)
				)
				(justify right top mirror)
			)
		)
		(property "Value" "TP_0.75mm_SMD"
			(at 0 -1.2 90)
			(layer "B.Fab")
			(hide yes)
			(effects
				(font
					(size 0.7 0.7)
					(thickness 0.15)
				)
				(justify right top mirror)
			)
		)
		(property "Description" "SMT test point"
			(at 0 0 90)
			(layer "B.Fab")
			(hide yes)
			(effects
				(font
					(size 1.27 1.27)
					(thickness 0.15)
				)
				(justify mirror)
			)
		)
		(property "MPN" ""
			(at 0 0 90)
			(unlocked yes)
			(layer "B.Fab")
			(hide yes)
			(effects
				(font
					(size 1 1)
					(thickness 0.15)
				)
				(justify mirror)
			)
		)
		(property "Manufacturer" ""
			(at 0 0 90)
			(unlocked yes)
			(layer "B.Fab")
			(hide yes)
			(effects
				(font
					(size 1 1)
					(thickness 0.15)
				)
				(justify mirror)
			)
		)
		(property "Author" "Antmicro"
			(at 0 0 90)
			(unlocked yes)
			(layer "B.Fab")
			(hide yes)
			(effects
				(font
					(size 1 1)
					(thickness 0.15)
				)
				(justify mirror)
			)
		)
		(property "License" "Apache-2.0"
			(at 0 0 90)
			(unlocked yes)
			(layer "B.Fab")
			(hide yes)
			(effects
				(font
					(size 1 1)
					(thickness 0.15)
				)
				(justify mirror)
			)
		)
		(sheetname "/OCuLink/")
		(sheetfile "oculink.kicad_sch")
		(attr exclude_from_pos_files exclude_from_bom)
		(fp_circle
			(center 0 0)
			(end 0.475 0)
			(stroke
				(width 0.05)
				(type default)
			)
			(fill no)
			(layer "B.CrtYd")
		)
		(pad "1" smd circle
			(at 0 0 90)
			(size 0.75 0.75)
			(layers "B.Cu" "B.Mask")
			(net 319 "/OCuLink/~{PE_ RST}_R")
			(pinfunction "1")
			(pintype "passive")
		)
	)
	(footprint "antmicro-footprints:R_0402_1005Metric"
		(layer "B.Cu")
		(at 91.2 98.3 -90)
		(descr "Resistor SMD 0402")
		(tags "resistor SMD 0402")
		(property "Reference" "R141"
			(at -13.56 -0.482657 90)
			(layer "B.SilkS")
			(effects
				(font
					(size 0.7 0.7)
					(thickness 0.15)
				)
				(justify left bottom mirror)
			)
		)
		(property "Value" "R_100R_0402"
			(at -1.011843 -1.772046 90)
			(layer "B.Fab")
			(hide yes)
			(effects
				(font
					(size 0.7 0.7)
					(thickness 0.15)
				)
				(justify left bottom mirror)
			)
		)
		(property "Datasheet" "https://www.bourns.com/docs/product-datasheets/cr.pdf"
			(at 0 0 90)
			(layer "B.Fab")
			(hide yes)
			(effects
				(font
					(size 1.27 1.27)
					(thickness 0.15)
				)
				(justify mirror)
			)
		)
		(property "Description" "SMD Chip Resistor, 100 ohm, ± 1%, 62.5 mW, 0402 [1005 Metric], Thick Film, General Purpose"
			(at 0 0 90)
			(layer "B.Fab")
			(hide yes)
			(effects
				(font
					(size 1.27 1.27)
					(thickness 0.15)
				)
				(justify mirror)
			)
		)
		(property "MPN" "CR0402-FX-1000GLF"
			(at 0 0 270)
			(unlocked yes)
			(layer "B.Fab")
			(hide yes)
			(effects
				(font
					(size 1 1)
					(thickness 0.15)
				)
				(justify mirror)
			)
		)
		(property "Manufacturer" "Bourns"
			(at 0 0 270)
			(unlocked yes)
			(layer "B.Fab")
			(hide yes)
			(effects
				(font
					(size 1 1)
					(thickness 0.15)
				)
				(justify mirror)
			)
		)
		(property "License" "Apache-2.0"
			(at 0 0 270)
			(unlocked yes)
			(layer "B.Fab")
			(hide yes)
			(effects
				(font
					(size 1 1)
					(thickness 0.15)
				)
				(justify mirror)
			)
		)
		(property "Author" "Antmicro"
			(at 0 0 270)
			(unlocked yes)
			(layer "B.Fab")
			(hide yes)
			(effects
				(font
					(size 1 1)
					(thickness 0.15)
				)
				(justify mirror)
			)
		)
		(property "Val" "100R"
			(at 0 0 270)
			(unlocked yes)
			(layer "B.Fab")
			(hide yes)
			(effects
				(font
					(size 1 1)
					(thickness 0.15)
				)
				(justify mirror)
			)
		)
		(property "Tolerance" "1%"
			(at 0 0 270)
			(unlocked yes)
			(layer "B.Fab")
			(hide yes)
			(effects
				(font
					(size 1 1)
					(thickness 0.15)
				)
				(justify mirror)
			)
		)
		(sheetname "/X710-AT2 RSVD/")
		(sheetfile "x710-at2-rsvd.kicad_sch")
		(attr smd)
		(fp_rect
			(start -0.925 0.47)
			(end 0.925 -0.47)
			(stroke
				(width 0.05)
				(type default)
			)
			(fill no)
			(layer "B.CrtYd")
		)
		(fp_rect
			(start -0.5 0.25)
			(end 0.5 -0.25)
			(stroke
				(width 0.15)
				(type solid)
			)
			(fill no)
			(layer "B.Fab")
		)
		(pad "1" smd roundrect
			(at -0.48 0 270)
			(size 0.59 0.64)
			(layers "B.Cu" "B.Mask" "B.Paste")
			(roundrect_rratio 0.25)
			(net 28 "GND")
			(pintype "passive")
		)
		(pad "2" smd roundrect
			(at 0.48 0 270)
			(size 0.59 0.64)
			(layers "B.Cu" "B.Mask" "B.Paste")
			(roundrect_rratio 0.25)
			(net 129 "/X710-AT2 RSVD/RSVDP8_VSS")
			(pintype "passive")
		)
	)
	(footprint "antmicro-footprints:R_0402_1005Metric"
		(layer "B.Cu")
		(at 96.88 113.960001)
		(descr "Resistor SMD 0402")
		(tags "resistor SMD 0402")
		(property "Reference" "R50"
			(at -2.96 -0.380001 0)
			(layer "B.SilkS")
			(effects
				(font
					(size 0.7 0.7)
					(thickness 0.15)
				)
				(justify right top mirror)
			)
		)
		(property "Value" "R_100R_0402"
			(at -1.011843 -1.772046 0)
			(layer "B.Fab")
			(hide yes)
			(effects
				(font
					(size 0.7 0.7)
					(thickness 0.15)
				)
				(justify right top mirror)
			)
		)
		(property "Datasheet" "https://www.bourns.com/docs/product-datasheets/cr.pdf"
			(at 0 0 0)
			(layer "B.Fab")
			(hide yes)
			(effects
				(font
					(size 1.27 1.27)
					(thickness 0.15)
				)
				(justify mirror)
			)
		)
		(property "Description" "SMD Chip Resistor, 100 ohm, ± 1%, 62.5 mW, 0402 [1005 Metric], Thick Film, General Purpose"
			(at 0 0 0)
			(layer "B.Fab")
			(hide yes)
			(effects
				(font
					(size 1.27 1.27)
					(thickness 0.15)
				)
				(justify mirror)
			)
		)
		(property "MPN" "CR0402-FX-1000GLF"
			(at 0 0 0)
			(unlocked yes)
			(layer "B.Fab")
			(hide yes)
			(effects
				(font
					(size 1 1)
					(thickness 0.15)
				)
				(justify mirror)
			)
		)
		(property "Manufacturer" "Bourns"
			(at 0 0 0)
			(unlocked yes)
			(layer "B.Fab")
			(hide yes)
			(effects
				(font
					(size 1 1)
					(thickness 0.15)
				)
				(justify mirror)
			)
		)
		(property "License" "Apache-2.0"
			(at 0 0 0)
			(unlocked yes)
			(layer "B.Fab")
			(hide yes)
			(effects
				(font
					(size 1 1)
					(thickness 0.15)
				)
				(justify mirror)
			)
		)
		(property "Author" "Antmicro"
			(at 0 0 0)
			(unlocked yes)
			(layer "B.Fab")
			(hide yes)
			(effects
				(font
					(size 1 1)
					(thickness 0.15)
				)
				(justify mirror)
			)
		)
		(property "Val" "100R"
			(at 0 0 0)
			(unlocked yes)
			(layer "B.Fab")
			(hide yes)
			(effects
				(font
					(size 1 1)
					(thickness 0.15)
				)
				(justify mirror)
			)
		)
		(property "Tolerance" "1%"
			(at 0 0 0)
			(unlocked yes)
			(layer "B.Fab")
			(hide yes)
			(effects
				(font
					(size 1 1)
					(thickness 0.15)
				)
				(justify mirror)
			)
		)
		(sheetname "/X710-AT2 Misc/")
		(sheetfile "x710-at2-mics.kicad_sch")
		(attr smd)
		(fp_rect
			(start -0.925 0.47)
			(end 0.925 -0.47)
			(stroke
				(width 0.05)
				(type default)
			)
			(fill no)
			(layer "B.CrtYd")
		)
		(fp_rect
			(start -0.5 0.25)
			(end 0.5 -0.25)
			(stroke
				(width 0.15)
				(type solid)
			)
			(fill no)
			(layer "B.Fab")
		)
		(pad "1" smd roundrect
			(at -0.48 0)
			(size 0.59 0.64)
			(layers "B.Cu" "B.Mask" "B.Paste")
			(roundrect_rratio 0.25)
			(net 28 "GND")
			(pintype "passive")
		)
		(pad "2" smd roundrect
			(at 0.48 0)
			(size 0.59 0.64)
			(layers "B.Cu" "B.Mask" "B.Paste")
			(roundrect_rratio 0.25)
			(net 158 "Net-(U7-B_{2})")
			(pintype "passive")
		)
	)
	(footprint "antmicro-footprints:C_0402_1005Metric"
		(layer "B.Cu")
		(at 60.670003 88.449998)
		(descr "Capacitor SMD 0402")
		(tags "capacitor SMD 0402")
		(property "Reference" "C18"
			(at -1.070003 0.550002 0)
			(layer "B.SilkS")
			(effects
				(font
					(size 0.7 0.7)
					(thickness 0.15)
				)
				(justify right top mirror)
			)
		)
		(property "Value" "C_100n_0402"
			(at -1.022927 -2.155213 0)
			(layer "B.Fab")
			(hide yes)
			(effects
				(font
					(size 0.7 0.7)
					(thickness 0.15)
				)
				(justify right top mirror)
			)
		)
		(property "Datasheet" "https://www.murata.com/products/productdetail?partno=GRM155R61H104KE14%23"
			(at 0 0 0)
			(layer "B.Fab")
			(hide yes)
			(effects
				(font
					(size 1.27 1.27)
					(thickness 0.15)
				)
				(justify mirror)
			)
		)
		(property "Description" "SMD Multilayer Ceramic Capacitor, 0.1 µF, 50 V, 0402 [1005 Metric], ± 10%, X5R, GRM Series"
			(at 0 0 0)
			(layer "B.Fab")
			(hide yes)
			(effects
				(font
					(size 1.27 1.27)
					(thickness 0.15)
				)
				(justify mirror)
			)
		)
		(property "MPN" "GRM155R61H104KE14D"
			(at 0 0 0)
			(unlocked yes)
			(layer "B.Fab")
			(hide yes)
			(effects
				(font
					(size 1 1)
					(thickness 0.15)
				)
				(justify mirror)
			)
		)
		(property "Manufacturer" "Murata"
			(at 0 0 0)
			(unlocked yes)
			(layer "B.Fab")
			(hide yes)
			(effects
				(font
					(size 1 1)
					(thickness 0.15)
				)
				(justify mirror)
			)
		)
		(property "License" "Apache-2.0"
			(at 0 0 0)
			(unlocked yes)
			(layer "B.Fab")
			(hide yes)
			(effects
				(font
					(size 1 1)
					(thickness 0.15)
				)
				(justify mirror)
			)
		)
		(property "Author" "Antmicro"
			(at 0 0 0)
			(unlocked yes)
			(layer "B.Fab")
			(hide yes)
			(effects
				(font
					(size 1 1)
					(thickness 0.15)
				)
				(justify mirror)
			)
		)
		(property "Val" "100n"
			(at 0 0 0)
			(unlocked yes)
			(layer "B.Fab")
			(hide yes)
			(effects
				(font
					(size 1 1)
					(thickness 0.15)
				)
				(justify mirror)
			)
		)
		(property "Voltage" "50V"
			(at 0 0 0)
			(unlocked yes)
			(layer "B.Fab")
			(hide yes)
			(effects
				(font
					(size 1 1)
					(thickness 0.15)
				)
				(justify mirror)
			)
		)
		(property "Dielectric" "X5R"
			(at 0 0 0)
			(unlocked yes)
			(layer "B.Fab")
			(hide yes)
			(effects
				(font
					(size 1 1)
					(thickness 0.15)
				)
				(justify mirror)
			)
		)
		(sheetname "/Power/")
		(sheetfile "power.kicad_sch")
		(attr smd)
		(fp_rect
			(start -0.925 0.47)
			(end 0.925 -0.47)
			(stroke
				(width 0.05)
				(type default)
			)
			(fill no)
			(layer "B.CrtYd")
		)
		(fp_line
			(start -0.494 -0.248)
			(end -0.494 0.25)
			(stroke
				(width 0.15)
				(type solid)
			)
			(layer "B.Fab")
		)
		(fp_line
			(start -0.494 0.25)
			(end 0.504 0.25)
			(stroke
				(width 0.15)
				(type solid)
			)
			(layer "B.Fab")
		)
		(fp_line
			(start 0.504 -0.248)
			(end -0.494 -0.248)
			(stroke
				(width 0.15)
				(type solid)
			)
			(layer "B.Fab")
		)
		(fp_line
			(start 0.504 0.25)
			(end 0.504 -0.248)
			(stroke
				(width 0.15)
				(type solid)
			)
			(layer "B.Fab")
		)
		(pad "1" smd roundrect
			(at -0.48 0)
			(size 0.59 0.64)
			(layers "B.Cu" "B.Mask" "B.Paste")
			(roundrect_rratio 0.25)
			(net 28 "GND")
			(pintype "passive")
		)
		(pad "2" smd roundrect
			(at 0.48 0)
			(size 0.59 0.64)
			(layers "B.Cu" "B.Mask" "B.Paste")
			(roundrect_rratio 0.25)
			(net 303 "/Power/+VCCD_OUT")
			(pintype "passive")
		)
	)
	(footprint "antmicro-footprints:R_0402_1005Metric"
		(layer "B.Cu")
		(at 74 99.65)
		(descr "Resistor SMD 0402")
		(tags "resistor SMD 0402")
		(property "Reference" "R106"
			(at -0.85 0.45 0)
			(layer "B.SilkS")
			(effects
				(font
					(size 0.7 0.7)
					(thickness 0.15)
				)
				(justify left bottom mirror)
			)
		)
		(property "Value" "R_100R_0402"
			(at -1.011843 -1.772046 0)
			(layer "B.Fab")
			(hide yes)
			(effects
				(font
					(size 0.7 0.7)
					(thickness 0.15)
				)
				(justify right top mirror)
			)
		)
		(property "Datasheet" "https://www.bourns.com/docs/product-datasheets/cr.pdf"
			(at 0 0 0)
			(layer "B.Fab")
			(hide yes)
			(effects
				(font
					(size 1.27 1.27)
					(thickness 0.15)
				)
				(justify mirror)
			)
		)
		(property "Description" "SMD Chip Resistor, 100 ohm, ± 1%, 62.5 mW, 0402 [1005 Metric], Thick Film, General Purpose"
			(at 0 0 0)
			(layer "B.Fab")
			(hide yes)
			(effects
				(font
					(size 1.27 1.27)
					(thickness 0.15)
				)
				(justify mirror)
			)
		)
		(property "MPN" "CR0402-FX-1000GLF"
			(at 0 0 0)
			(unlocked yes)
			(layer "B.Fab")
			(hide yes)
			(effects
				(font
					(size 1 1)
					(thickness 0.15)
				)
				(justify mirror)
			)
		)
		(property "Manufacturer" "Bourns"
			(at 0 0 0)
			(unlocked yes)
			(layer "B.Fab")
			(hide yes)
			(effects
				(font
					(size 1 1)
					(thickness 0.15)
				)
				(justify mirror)
			)
		)
		(property "License" "Apache-2.0"
			(at 0 0 0)
			(unlocked yes)
			(layer "B.Fab")
			(hide yes)
			(effects
				(font
					(size 1 1)
					(thickness 0.15)
				)
				(justify mirror)
			)
		)
		(property "Author" "Antmicro"
			(at 0 0 0)
			(unlocked yes)
			(layer "B.Fab")
			(hide yes)
			(effects
				(font
					(size 1 1)
					(thickness 0.15)
				)
				(justify mirror)
			)
		)
		(property "Val" "100R"
			(at 0 0 0)
			(unlocked yes)
			(layer "B.Fab")
			(hide yes)
			(effects
				(font
					(size 1 1)
					(thickness 0.15)
				)
				(justify mirror)
			)
		)
		(property "Tolerance" "1%"
			(at 0 0 0)
			(unlocked yes)
			(layer "B.Fab")
			(hide yes)
			(effects
				(font
					(size 1 1)
					(thickness 0.15)
				)
				(justify mirror)
			)
		)
		(sheetname "/X710-AT2 Misc/")
		(sheetfile "x710-at2-mics.kicad_sch")
		(attr smd)
		(fp_rect
			(start -0.925 0.47)
			(end 0.925 -0.47)
			(stroke
				(width 0.05)
				(type default)
			)
			(fill no)
			(layer "B.CrtYd")
		)
		(fp_rect
			(start -0.5 0.25)
			(end 0.5 -0.25)
			(stroke
				(width 0.15)
				(type solid)
			)
			(fill no)
			(layer "B.Fab")
		)
		(pad "1" smd roundrect
			(at -0.48 0)
			(size 0.59 0.64)
			(layers "B.Cu" "B.Mask" "B.Paste")
			(roundrect_rratio 0.25)
			(net 28 "GND")
			(pintype "passive")
		)
		(pad "2" smd roundrect
			(at 0.48 0)
			(size 0.59 0.64)
			(layers "B.Cu" "B.Mask" "B.Paste")
			(roundrect_rratio 0.25)
			(net 47 "/X710-AT2 Misc/POR_BYPASS")
			(pintype "passive")
		)
	)
	(footprint "antmicro-footprints:C_0603_1608Metric_EIA"
		(layer "B.Cu")
		(at 83.3 125.8)
		(descr "Capacitor SMD 0603, IPC-7351 Density Level A")
		(tags "Capacitor 0603")
		(property "Reference" "C52"
			(at -0.95 -1.55 0)
			(layer "B.SilkS")
			(effects
				(font
					(size 0.7 0.7)
					(thickness 0.15)
				)
				(justify right top mirror)
			)
		)
		(property "Value" "C_22u_16V_0603"
			(at -1.42757 -1.770288 0)
			(layer "B.Fab")
			(hide yes)
			(effects
				(font
					(size 0.7 0.7)
					(thickness 0.15)
				)
				(justify right top mirror)
			)
		)
		(property "Datasheet" "https://product.samsungsem.com/mlcc/CL10A226MO7JZN.do"
			(at 0 0 0)
			(layer "B.Fab")
			(hide yes)
			(effects
				(font
					(size 1.27 1.27)
					(thickness 0.15)
				)
				(justify mirror)
			)
		)
		(property "Description" "SMD Multilayer Ceramic Capacitor"
			(at 0 0 0)
			(layer "B.Fab")
			(hide yes)
			(effects
				(font
					(size 1.27 1.27)
					(thickness 0.15)
				)
				(justify mirror)
			)
		)
		(property "MPN" "CL10A226MO7JZNC"
			(at 0 0 0)
			(unlocked yes)
			(layer "B.Fab")
			(hide yes)
			(effects
				(font
					(size 1 1)
					(thickness 0.15)
				)
				(justify mirror)
			)
		)
		(property "Manufacturer" "Samsung Electro-Mechanics"
			(at 0 0 0)
			(unlocked yes)
			(layer "B.Fab")
			(hide yes)
			(effects
				(font
					(size 1 1)
					(thickness 0.15)
				)
				(justify mirror)
			)
		)
		(property "License" "Apache-2.0"
			(at 0 0 0)
			(unlocked yes)
			(layer "B.Fab")
			(hide yes)
			(effects
				(font
					(size 1 1)
					(thickness 0.15)
				)
				(justify mirror)
			)
		)
		(property "Author" "Antmicro"
			(at 0 0 0)
			(unlocked yes)
			(layer "B.Fab")
			(hide yes)
			(effects
				(font
					(size 1 1)
					(thickness 0.15)
				)
				(justify mirror)
			)
		)
		(property "Val" "22u"
			(at 0 0 0)
			(unlocked yes)
			(layer "B.Fab")
			(hide yes)
			(effects
				(font
					(size 1 1)
					(thickness 0.15)
				)
				(justify mirror)
			)
		)
		(property "Voltage" "16V"
			(at 0 0 0)
			(unlocked yes)
			(layer "B.Fab")
			(hide yes)
			(effects
				(font
					(size 1 1)
					(thickness 0.15)
				)
				(justify mirror)
			)
		)
		(property "Dielectric" ""
			(at 0 0 0)
			(unlocked yes)
			(layer "B.Fab")
			(hide yes)
			(effects
				(font
					(size 1 1)
					(thickness 0.15)
				)
				(justify mirror)
			)
		)
		(sheetname "/2xRJ45/")
		(sheetfile "2xrj45.kicad_sch")
		(attr smd)
		(fp_line
			(start -0.15 -0.55)
			(end 0.15 -0.55)
			(stroke
				(width 0.15)
				(type solid)
			)
			(layer "B.SilkS")
		)
		(fp_line
			(start -0.15 0.55)
			(end 0.15 0.55)
			(stroke
				(width 0.15)
				(type solid)
			)
			(layer "B.SilkS")
		)
		(fp_rect
			(start -1.25 0.65)
			(end 1.25 -0.65)
			(stroke
				(width 0.05)
				(type solid)
			)
			(fill no)
			(layer "B.CrtYd")
		)
		(fp_rect
			(start -0.8 0.45)
			(end 0.8 -0.45)
			(stroke
				(width 0.15)
				(type solid)
			)
			(fill no)
			(layer "B.Fab")
		)
		(pad "1" smd roundrect
			(at -0.7 0)
			(size 0.8 1.1)
			(layers "B.Cu" "B.Mask" "B.Paste")
			(roundrect_rratio 0.2)
			(net 28 "GND")
			(pintype "passive")
		)
		(pad "2" smd roundrect
			(at 0.7 0)
			(size 0.8 1.1)
			(layers "B.Cu" "B.Mask" "B.Paste")
			(roundrect_rratio 0.2)
			(net 18 "+1V88")
			(pintype "passive")
		)
	)
	(footprint "antmicro-footprints:C_0402_1005Metric"
		(layer "B.Cu")
		(at 85.225 96.45 90)
		(descr "Capacitor SMD 0402")
		(tags "capacitor SMD 0402")
		(property "Reference" "C134"
			(at 11.58 -0.432343 90)
			(layer "B.SilkS")
			(effects
				(font
					(size 0.7 0.7)
					(thickness 0.15)
				)
				(justify right top mirror)
			)
		)
		(property "Value" "C_1u_25V_0402"
			(at -1.022927 -2.155213 90)
			(layer "B.Fab")
			(hide yes)
			(effects
				(font
					(size 0.7 0.7)
					(thickness 0.15)
				)
				(justify right top mirror)
			)
		)
		(property "Datasheet" "https://www.murata.com/products/productdetail?partno=GRM155R61E105KE11%23"
			(at 0 0 90)
			(layer "B.Fab")
			(hide yes)
			(effects
				(font
					(size 1.27 1.27)
					(thickness 0.15)
				)
				(justify mirror)
			)
		)
		(property "Description" "SMD Multilayer Ceramic Capacitor, 1 µF, 25 V, 0402 [1005 Metric], ± 10%, X5R, GRM Series"
			(at 0 0 90)
			(layer "B.Fab")
			(hide yes)
			(effects
				(font
					(size 1.27 1.27)
					(thickness 0.15)
				)
				(justify mirror)
			)
		)
		(property "MPN" "GRM155R61E105KE11J"
			(at 0 0 90)
			(unlocked yes)
			(layer "B.Fab")
			(hide yes)
			(effects
				(font
					(size 1 1)
					(thickness 0.15)
				)
				(justify mirror)
			)
		)
		(property "Manufacturer" "Murata"
			(at 0 0 90)
			(unlocked yes)
			(layer "B.Fab")
			(hide yes)
			(effects
				(font
					(size 1 1)
					(thickness 0.15)
				)
				(justify mirror)
			)
		)
		(property "License" "Apache-2.0"
			(at 0 0 90)
			(unlocked yes)
			(layer "B.Fab")
			(hide yes)
			(effects
				(font
					(size 1 1)
					(thickness 0.15)
				)
				(justify mirror)
			)
		)
		(property "Author" "Antmicro"
			(at 0 0 90)
			(unlocked yes)
			(layer "B.Fab")
			(hide yes)
			(effects
				(font
					(size 1 1)
					(thickness 0.15)
				)
				(justify mirror)
			)
		)
		(property "Val" "1u"
			(at 0 0 90)
			(unlocked yes)
			(layer "B.Fab")
			(hide yes)
			(effects
				(font
					(size 1 1)
					(thickness 0.15)
				)
				(justify mirror)
			)
		)
		(property "Voltage" "25V"
			(at 0 0 90)
			(unlocked yes)
			(layer "B.Fab")
			(hide yes)
			(effects
				(font
					(size 1 1)
					(thickness 0.15)
				)
				(justify mirror)
			)
		)
		(property "Dielectric" "X5R"
			(at 0 0 90)
			(unlocked yes)
			(layer "B.Fab")
			(hide yes)
			(effects
				(font
					(size 1 1)
					(thickness 0.15)
				)
				(justify mirror)
			)
		)
		(sheetname "/X710-AT2 power/")
		(sheetfile "x710-at2-power.kicad_sch")
		(attr smd)
		(fp_rect
			(start -0.925 0.47)
			(end 0.925 -0.47)
			(stroke
				(width 0.05)
				(type default)
			)
			(fill no)
			(layer "B.CrtYd")
		)
		(fp_line
			(start 0.504 -0.248)
			(end -0.494 -0.248)
			(stroke
				(width 0.15)
				(type solid)
			)
			(layer "B.Fab")
		)
		(fp_line
			(start -0.494 -0.248)
			(end -0.494 0.25)
			(stroke
				(width 0.15)
				(type solid)
			)
			(layer "B.Fab")
		)
		(fp_line
			(start 0.504 0.25)
			(end 0.504 -0.248)
			(stroke
				(width 0.15)
				(type solid)
			)
			(layer "B.Fab")
		)
		(fp_line
			(start -0.494 0.25)
			(end 0.504 0.25)
			(stroke
				(width 0.15)
				(type solid)
			)
			(layer "B.Fab")
		)
		(pad "1" smd roundrect
			(at -0.48 0 90)
			(size 0.59 0.64)
			(layers "B.Cu" "B.Mask" "B.Paste")
			(roundrect_rratio 0.25)
			(net 28 "GND")
			(pintype "passive")
		)
		(pad "2" smd roundrect
			(at 0.48 0 90)
			(size 0.59 0.64)
			(layers "B.Cu" "B.Mask" "B.Paste")
			(roundrect_rratio 0.25)
			(net 7 "+3V3")
			(pintype "passive")
		)
	)
	(footprint "antmicro-footprints:R_0402_1005Metric"
		(layer "B.Cu")
		(at 92.8 112.61)
		(descr "Resistor SMD 0402")
		(tags "resistor SMD 0402")
		(property "Reference" "R149"
			(at -1.45 1.72 0)
			(layer "B.SilkS")
			(effects
				(font
					(size 0.7 0.7)
					(thickness 0.15)
				)
				(justify right top mirror)
			)
		)
		(property "Value" "R_2k_0402"
			(at -1.011843 -1.772047 0)
			(layer "B.Fab")
			(effects
				(font
					(size 0.7 0.7)
					(thickness 0.15)
				)
				(justify right top mirror)
			)
		)
		(property "Datasheet" "https://www.bourns.com/docs/product-datasheets/cr.pdf"
			(at 0 0 0)
			(layer "B.Fab")
			(hide yes)
			(effects
				(font
					(size 1.27 1.27)
					(thickness 0.15)
				)
				(justify mirror)
			)
		)
		(property "Description" "SMD Chip Resistor, 2 kohm, ± 1%, 62.5 mW, 0402 [1005 Metric], Thick Film, General Purpose"
			(at 0 0 0)
			(layer "B.Fab")
			(hide yes)
			(effects
				(font
					(size 1.27 1.27)
					(thickness 0.15)
				)
				(justify mirror)
			)
		)
		(property "MPN" "CR0402-FX-2001GLF"
			(at 0 0 180)
			(unlocked yes)
			(layer "B.Fab")
			(hide yes)
			(effects
				(font
					(size 1 1)
					(thickness 0.15)
				)
				(justify mirror)
			)
		)
		(property "Manufacturer" "Bourns"
			(at 0 0 180)
			(unlocked yes)
			(layer "B.Fab")
			(hide yes)
			(effects
				(font
					(size 1 1)
					(thickness 0.15)
				)
				(justify mirror)
			)
		)
		(property "License" "Apache-2.0"
			(at 0 0 180)
			(unlocked yes)
			(layer "B.Fab")
			(hide yes)
			(effects
				(font
					(size 1 1)
					(thickness 0.15)
				)
				(justify mirror)
			)
		)
		(property "Author" "Antmicro"
			(at 0 0 180)
			(unlocked yes)
			(layer "B.Fab")
			(hide yes)
			(effects
				(font
					(size 1 1)
					(thickness 0.15)
				)
				(justify mirror)
			)
		)
		(property "Val" "2k"
			(at 0 0 180)
			(unlocked yes)
			(layer "B.Fab")
			(hide yes)
			(effects
				(font
					(size 1 1)
					(thickness 0.15)
				)
				(justify mirror)
			)
		)
		(property "Tolerance" "1%"
			(at 0 0 180)
			(unlocked yes)
			(layer "B.Fab")
			(hide yes)
			(effects
				(font
					(size 1 1)
					(thickness 0.15)
				)
				(justify mirror)
			)
		)
		(sheetname "/X710-AT2 Misc/")
		(sheetfile "x710-at2-mics.kicad_sch")
		(attr smd)
		(fp_rect
			(start -0.925 0.47)
			(end 0.925 -0.47)
			(stroke
				(width 0.05)
				(type default)
			)
			(fill no)
			(layer "B.CrtYd")
		)
		(fp_rect
			(start -0.5 0.25)
			(end 0.5 -0.25)
			(stroke
				(width 0.15)
				(type solid)
			)
			(fill no)
			(layer "B.Fab")
		)
		(fp_text user "License: Apache-2.0"
			(at -0.95 -5.169 0)
			(layer "B.Fab")
			(effects
				(font
					(size 0.7 0.7)
					(thickness 0.15)
				)
				(justify right top mirror)
			)
		)
		(fp_text user "Author: Antmicro"
			(at -0.95 -4.169 0)
			(layer "B.Fab")
			(effects
				(font
					(size 0.7 0.7)
					(thickness 0.15)
				)
				(justify right top mirror)
			)
		)
		(fp_text user "${REFERENCE}"
			(at -0.95 -3.168 0)
			(layer "B.Fab")
			(effects
				(font
					(size 0.7 0.7)
					(thickness 0.15)
				)
				(justify right top mirror)
			)
		)
		(pad "1" smd roundrect
			(at -0.48 0)
			(size 0.59 0.64)
			(layers "B.Cu" "B.Mask" "B.Paste")
			(roundrect_rratio 0.25)
			(net 384 "/X710-AT2 Misc/~{PHY_RESET}")
			(pintype "passive")
		)
		(pad "2" smd roundrect
			(at 0.48 0)
			(size 0.59 0.64)
			(layers "B.Cu" "B.Mask" "B.Paste")
			(roundrect_rratio 0.25)
			(net 18 "+1V88")
			(pintype "passive")
		)
	)
	(footprint "antmicro-footprints:C_0402_1005Metric"
		(layer "B.Cu")
		(at 80.36 105.08 90)
		(descr "Capacitor SMD 0402")
		(tags "capacitor SMD 0402")
		(property "Reference" "C84"
			(at -11.81 0.085 90)
			(layer "B.SilkS")
			(effects
				(font
					(size 0.7 0.7)
					(thickness 0.15)
				)
				(justify right top mirror)
			)
		)
		(property "Value" "C_1u_25V_0402"
			(at -1.022927 -2.155213 90)
			(layer "B.Fab")
			(hide yes)
			(effects
				(font
					(size 0.7 0.7)
					(thickness 0.15)
				)
				(justify right top mirror)
			)
		)
		(property "Datasheet" "https://www.murata.com/products/productdetail?partno=GRM155R61E105KE11%23"
			(at 0 0 90)
			(layer "B.Fab")
			(hide yes)
			(effects
				(font
					(size 1.27 1.27)
					(thickness 0.15)
				)
				(justify mirror)
			)
		)
		(property "Description" "SMD Multilayer Ceramic Capacitor, 1 µF, 25 V, 0402 [1005 Metric], ± 10%, X5R, GRM Series"
			(at 0 0 90)
			(layer "B.Fab")
			(hide yes)
			(effects
				(font
					(size 1.27 1.27)
					(thickness 0.15)
				)
				(justify mirror)
			)
		)
		(property "MPN" "GRM155R61E105KE11J"
			(at 0 0 90)
			(unlocked yes)
			(layer "B.Fab")
			(hide yes)
			(effects
				(font
					(size 1 1)
					(thickness 0.15)
				)
				(justify mirror)
			)
		)
		(property "Manufacturer" "Murata"
			(at 0 0 90)
			(unlocked yes)
			(layer "B.Fab")
			(hide yes)
			(effects
				(font
					(size 1 1)
					(thickness 0.15)
				)
				(justify mirror)
			)
		)
		(property "License" "Apache-2.0"
			(at 0 0 90)
			(unlocked yes)
			(layer "B.Fab")
			(hide yes)
			(effects
				(font
					(size 1 1)
					(thickness 0.15)
				)
				(justify mirror)
			)
		)
		(property "Author" "Antmicro"
			(at 0 0 90)
			(unlocked yes)
			(layer "B.Fab")
			(hide yes)
			(effects
				(font
					(size 1 1)
					(thickness 0.15)
				)
				(justify mirror)
			)
		)
		(property "Val" "1u"
			(at 0 0 90)
			(unlocked yes)
			(layer "B.Fab")
			(hide yes)
			(effects
				(font
					(size 1 1)
					(thickness 0.15)
				)
				(justify mirror)
			)
		)
		(property "Voltage" "25V"
			(at 0 0 90)
			(unlocked yes)
			(layer "B.Fab")
			(hide yes)
			(effects
				(font
					(size 1 1)
					(thickness 0.15)
				)
				(justify mirror)
			)
		)
		(property "Dielectric" "X5R"
			(at 0 0 90)
			(unlocked yes)
			(layer "B.Fab")
			(hide yes)
			(effects
				(font
					(size 1 1)
					(thickness 0.15)
				)
				(justify mirror)
			)
		)
		(sheetname "/X710-AT2 power/")
		(sheetfile "x710-at2-power.kicad_sch")
		(attr smd)
		(fp_rect
			(start -0.925 0.47)
			(end 0.925 -0.47)
			(stroke
				(width 0.05)
				(type default)
			)
			(fill no)
			(layer "B.CrtYd")
		)
		(fp_line
			(start 0.504 -0.248)
			(end -0.494 -0.248)
			(stroke
				(width 0.15)
				(type solid)
			)
			(layer "B.Fab")
		)
		(fp_line
			(start -0.494 -0.248)
			(end -0.494 0.25)
			(stroke
				(width 0.15)
				(type solid)
			)
			(layer "B.Fab")
		)
		(fp_line
			(start 0.504 0.25)
			(end 0.504 -0.248)
			(stroke
				(width 0.15)
				(type solid)
			)
			(layer "B.Fab")
		)
		(fp_line
			(start -0.494 0.25)
			(end 0.504 0.25)
			(stroke
				(width 0.15)
				(type solid)
			)
			(layer "B.Fab")
		)
		(pad "1" smd roundrect
			(at -0.48 0 90)
			(size 0.59 0.64)
			(layers "B.Cu" "B.Mask" "B.Paste")
			(roundrect_rratio 0.25)
			(net 28 "GND")
			(pintype "passive")
		)
		(pad "2" smd roundrect
			(at 0.48 0 90)
			(size 0.59 0.64)
			(layers "B.Cu" "B.Mask" "B.Paste")
			(roundrect_rratio 0.25)
			(net 6 "DVDD")
			(pintype "passive")
		)
	)
	(footprint "antmicro-footprints:C_0402_1005Metric"
		(layer "B.Cu")
		(at 70.85 83.93 -90)
		(descr "Capacitor SMD 0402")
		(tags "capacitor SMD 0402")
		(property "Reference" "C9"
			(at -0.63 0.45 90)
			(layer "B.SilkS")
			(effects
				(font
					(size 0.7 0.7)
					(thickness 0.15)
				)
				(justify left bottom mirror)
			)
		)
		(property "Value" "C_100n_0402"
			(at -1.022927 -2.155213 90)
			(layer "B.Fab")
			(hide yes)
			(effects
				(font
					(size 0.7 0.7)
					(thickness 0.15)
				)
				(justify left bottom mirror)
			)
		)
		(property "Datasheet" "https://www.murata.com/products/productdetail?partno=GRM155R61H104KE14%23"
			(at 0 0 90)
			(layer "B.Fab")
			(hide yes)
			(effects
				(font
					(size 1.27 1.27)
					(thickness 0.15)
				)
				(justify mirror)
			)
		)
		(property "Description" "SMD Multilayer Ceramic Capacitor, 0.1 µF, 50 V, 0402 [1005 Metric], ± 10%, X5R, GRM Series"
			(at 0 0 90)
			(layer "B.Fab")
			(hide yes)
			(effects
				(font
					(size 1.27 1.27)
					(thickness 0.15)
				)
				(justify mirror)
			)
		)
		(property "MPN" "GRM155R61H104KE14D"
			(at 0 0 270)
			(unlocked yes)
			(layer "B.Fab")
			(hide yes)
			(effects
				(font
					(size 1 1)
					(thickness 0.15)
				)
				(justify mirror)
			)
		)
		(property "Manufacturer" "Murata"
			(at 0 0 270)
			(unlocked yes)
			(layer "B.Fab")
			(hide yes)
			(effects
				(font
					(size 1 1)
					(thickness 0.15)
				)
				(justify mirror)
			)
		)
		(property "License" "Apache-2.0"
			(at 0 0 270)
			(unlocked yes)
			(layer "B.Fab")
			(hide yes)
			(effects
				(font
					(size 1 1)
					(thickness 0.15)
				)
				(justify mirror)
			)
		)
		(property "Author" "Antmicro"
			(at 0 0 270)
			(unlocked yes)
			(layer "B.Fab")
			(hide yes)
			(effects
				(font
					(size 1 1)
					(thickness 0.15)
				)
				(justify mirror)
			)
		)
		(property "Val" "100n"
			(at 0 0 270)
			(unlocked yes)
			(layer "B.Fab")
			(hide yes)
			(effects
				(font
					(size 1 1)
					(thickness 0.15)
				)
				(justify mirror)
			)
		)
		(property "Voltage" "50V"
			(at 0 0 270)
			(unlocked yes)
			(layer "B.Fab")
			(hide yes)
			(effects
				(font
					(size 1 1)
					(thickness 0.15)
				)
				(justify mirror)
			)
		)
		(property "Dielectric" "X5R"
			(at 0 0 270)
			(unlocked yes)
			(layer "B.Fab")
			(hide yes)
			(effects
				(font
					(size 1 1)
					(thickness 0.15)
				)
				(justify mirror)
			)
		)
		(sheetname "/Power/")
		(sheetfile "power.kicad_sch")
		(attr smd)
		(fp_rect
			(start -0.925 0.47)
			(end 0.925 -0.47)
			(stroke
				(width 0.05)
				(type default)
			)
			(fill no)
			(layer "B.CrtYd")
		)
		(fp_line
			(start -0.494 0.25)
			(end 0.504 0.25)
			(stroke
				(width 0.15)
				(type solid)
			)
			(layer "B.Fab")
		)
		(fp_line
			(start 0.504 0.25)
			(end 0.504 -0.248)
			(stroke
				(width 0.15)
				(type solid)
			)
			(layer "B.Fab")
		)
		(fp_line
			(start -0.494 -0.248)
			(end -0.494 0.25)
			(stroke
				(width 0.15)
				(type solid)
			)
			(layer "B.Fab")
		)
		(fp_line
			(start 0.504 -0.248)
			(end -0.494 -0.248)
			(stroke
				(width 0.15)
				(type solid)
			)
			(layer "B.Fab")
		)
		(fp_text user "${REFERENCE}"
			(at -0.939 -4.599 90)
			(layer "B.Fab")
			(effects
				(font
					(size 0.7 0.7)
					(thickness 0.15)
				)
				(justify left bottom mirror)
			)
		)
		(pad "1" smd roundrect
			(at -0.48 0 270)
			(size 0.59 0.64)
			(layers "B.Cu" "B.Mask" "B.Paste")
			(roundrect_rratio 0.25)
			(net 28 "GND")
			(pintype "passive")
		)
		(pad "2" smd roundrect
			(at 0.48 0 270)
			(size 0.59 0.64)
			(layers "B.Cu" "B.Mask" "B.Paste")
			(roundrect_rratio 0.25)
			(net 255 "/Power/+3V3_OUT")
			(pintype "passive")
		)
	)
	(footprint "antmicro-footprints:C_0402_1005Metric"
		(layer "B.Cu")
		(at 81.45 106.93 90)
		(descr "Capacitor SMD 0402")
		(tags "capacitor SMD 0402")
		(property "Reference" "C145"
			(at -12.74 0.15 90)
			(layer "B.SilkS")
			(effects
				(font
					(size 0.7 0.7)
					(thickness 0.15)
				)
				(justify right top mirror)
			)
		)
		(property "Value" "C_1u_25V_0402"
			(at -1.022927 -2.155213 90)
			(layer "B.Fab")
			(hide yes)
			(effects
				(font
					(size 0.7 0.7)
					(thickness 0.15)
				)
				(justify right top mirror)
			)
		)
		(property "Datasheet" "https://www.murata.com/products/productdetail?partno=GRM155R61E105KE11%23"
			(at 0 0 90)
			(layer "B.Fab")
			(hide yes)
			(effects
				(font
					(size 1.27 1.27)
					(thickness 0.15)
				)
				(justify mirror)
			)
		)
		(property "Description" "SMD Multilayer Ceramic Capacitor, 1 µF, 25 V, 0402 [1005 Metric], ± 10%, X5R, GRM Series"
			(at 0 0 90)
			(layer "B.Fab")
			(hide yes)
			(effects
				(font
					(size 1.27 1.27)
					(thickness 0.15)
				)
				(justify mirror)
			)
		)
		(property "MPN" "GRM155R61E105KE11J"
			(at 0 0 90)
			(unlocked yes)
			(layer "B.Fab")
			(hide yes)
			(effects
				(font
					(size 1 1)
					(thickness 0.15)
				)
				(justify mirror)
			)
		)
		(property "Manufacturer" "Murata"
			(at 0 0 90)
			(unlocked yes)
			(layer "B.Fab")
			(hide yes)
			(effects
				(font
					(size 1 1)
					(thickness 0.15)
				)
				(justify mirror)
			)
		)
		(property "License" "Apache-2.0"
			(at 0 0 90)
			(unlocked yes)
			(layer "B.Fab")
			(hide yes)
			(effects
				(font
					(size 1 1)
					(thickness 0.15)
				)
				(justify mirror)
			)
		)
		(property "Author" "Antmicro"
			(at 0 0 90)
			(unlocked yes)
			(layer "B.Fab")
			(hide yes)
			(effects
				(font
					(size 1 1)
					(thickness 0.15)
				)
				(justify mirror)
			)
		)
		(property "Val" "1u"
			(at 0 0 90)
			(unlocked yes)
			(layer "B.Fab")
			(hide yes)
			(effects
				(font
					(size 1 1)
					(thickness 0.15)
				)
				(justify mirror)
			)
		)
		(property "Voltage" "25V"
			(at 0 0 90)
			(unlocked yes)
			(layer "B.Fab")
			(hide yes)
			(effects
				(font
					(size 1 1)
					(thickness 0.15)
				)
				(justify mirror)
			)
		)
		(property "Dielectric" "X5R"
			(at 0 0 90)
			(unlocked yes)
			(layer "B.Fab")
			(hide yes)
			(effects
				(font
					(size 1 1)
					(thickness 0.15)
				)
				(justify mirror)
			)
		)
		(sheetname "/X710-AT2 power/")
		(sheetfile "x710-at2-power.kicad_sch")
		(attr smd)
		(fp_rect
			(start -0.925 0.47)
			(end 0.925 -0.47)
			(stroke
				(width 0.05)
				(type default)
			)
			(fill no)
			(layer "B.CrtYd")
		)
		(fp_line
			(start 0.504 -0.248)
			(end -0.494 -0.248)
			(stroke
				(width 0.15)
				(type solid)
			)
			(layer "B.Fab")
		)
		(fp_line
			(start -0.494 -0.248)
			(end -0.494 0.25)
			(stroke
				(width 0.15)
				(type solid)
			)
			(layer "B.Fab")
		)
		(fp_line
			(start 0.504 0.25)
			(end 0.504 -0.248)
			(stroke
				(width 0.15)
				(type solid)
			)
			(layer "B.Fab")
		)
		(fp_line
			(start -0.494 0.25)
			(end 0.504 0.25)
			(stroke
				(width 0.15)
				(type solid)
			)
			(layer "B.Fab")
		)
		(pad "1" smd roundrect
			(at -0.48 0 90)
			(size 0.59 0.64)
			(layers "B.Cu" "B.Mask" "B.Paste")
			(roundrect_rratio 0.25)
			(net 28 "GND")
			(pintype "passive")
		)
		(pad "2" smd roundrect
			(at 0.48 0 90)
			(size 0.59 0.64)
			(layers "B.Cu" "B.Mask" "B.Paste")
			(roundrect_rratio 0.25)
			(net 10 "AVDDH")
			(pintype "passive")
		)
	)
	(footprint "antmicro-footprints:C_0402_1005Metric"
		(layer "B.Cu")
		(at 66 132.39)
		(descr "Capacitor SMD 0402")
		(tags "capacitor SMD 0402")
		(property "Reference" "C57"
			(at -3 -0.3 0)
			(layer "B.SilkS")
			(effects
				(font
					(size 0.7 0.7)
					(thickness 0.15)
				)
				(justify right top mirror)
			)
		)
		(property "Value" "C_1u_25V_0402"
			(at -1.022927 -2.155213 0)
			(layer "B.Fab")
			(hide yes)
			(effects
				(font
					(size 0.7 0.7)
					(thickness 0.15)
				)
				(justify right top mirror)
			)
		)
		(property "Datasheet" "https://www.murata.com/products/productdetail?partno=GRM155R61E105KE11%23"
			(at 0 0 0)
			(layer "B.Fab")
			(hide yes)
			(effects
				(font
					(size 1.27 1.27)
					(thickness 0.15)
				)
				(justify mirror)
			)
		)
		(property "Description" "SMD Multilayer Ceramic Capacitor, 1 µF, 25 V, 0402 [1005 Metric], ± 10%, X5R, GRM Series"
			(at 0 0 0)
			(layer "B.Fab")
			(hide yes)
			(effects
				(font
					(size 1.27 1.27)
					(thickness 0.15)
				)
				(justify mirror)
			)
		)
		(property "MPN" "GRM155R61E105KE11J"
			(at 0 0 0)
			(unlocked yes)
			(layer "B.Fab")
			(hide yes)
			(effects
				(font
					(size 1 1)
					(thickness 0.15)
				)
				(justify mirror)
			)
		)
		(property "Manufacturer" "Murata"
			(at 0 0 0)
			(unlocked yes)
			(layer "B.Fab")
			(hide yes)
			(effects
				(font
					(size 1 1)
					(thickness 0.15)
				)
				(justify mirror)
			)
		)
		(property "License" "Apache-2.0"
			(at 0 0 0)
			(unlocked yes)
			(layer "B.Fab")
			(hide yes)
			(effects
				(font
					(size 1 1)
					(thickness 0.15)
				)
				(justify mirror)
			)
		)
		(property "Author" "Antmicro"
			(at 0 0 0)
			(unlocked yes)
			(layer "B.Fab")
			(hide yes)
			(effects
				(font
					(size 1 1)
					(thickness 0.15)
				)
				(justify mirror)
			)
		)
		(property "Val" "1u"
			(at 0 0 0)
			(unlocked yes)
			(layer "B.Fab")
			(hide yes)
			(effects
				(font
					(size 1 1)
					(thickness 0.15)
				)
				(justify mirror)
			)
		)
		(property "Voltage" "25V"
			(at 0 0 0)
			(unlocked yes)
			(layer "B.Fab")
			(hide yes)
			(effects
				(font
					(size 1 1)
					(thickness 0.15)
				)
				(justify mirror)
			)
		)
		(property "Dielectric" "X5R"
			(at 0 0 0)
			(unlocked yes)
			(layer "B.Fab")
			(hide yes)
			(effects
				(font
					(size 1 1)
					(thickness 0.15)
				)
				(justify mirror)
			)
		)
		(sheetname "/2xRJ45/")
		(sheetfile "2xrj45.kicad_sch")
		(attr smd)
		(fp_rect
			(start -0.925 0.47)
			(end 0.925 -0.47)
			(stroke
				(width 0.05)
				(type default)
			)
			(fill no)
			(layer "B.CrtYd")
		)
		(fp_line
			(start -0.494 -0.248)
			(end -0.494 0.25)
			(stroke
				(width 0.15)
				(type solid)
			)
			(layer "B.Fab")
		)
		(fp_line
			(start -0.494 0.25)
			(end 0.504 0.25)
			(stroke
				(width 0.15)
				(type solid)
			)
			(layer "B.Fab")
		)
		(fp_line
			(start 0.504 -0.248)
			(end -0.494 -0.248)
			(stroke
				(width 0.15)
				(type solid)
			)
			(layer "B.Fab")
		)
		(fp_line
			(start 0.504 0.25)
			(end 0.504 -0.248)
			(stroke
				(width 0.15)
				(type solid)
			)
			(layer "B.Fab")
		)
		(pad "1" smd roundrect
			(at -0.48 0)
			(size 0.59 0.64)
			(layers "B.Cu" "B.Mask" "B.Paste")
			(roundrect_rratio 0.25)
			(net 28 "GND")
			(pintype "passive")
		)
		(pad "2" smd roundrect
			(at 0.48 0)
			(size 0.59 0.64)
			(layers "B.Cu" "B.Mask" "B.Paste")
			(roundrect_rratio 0.25)
			(net 299 "/2xRJ45/P0_CT")
			(pintype "passive")
		)
	)
	(footprint "antmicro-footprints:TP_SMD_1mm"
		(layer "B.Cu")
		(at 84.74 72.3 -90)
		(property "Reference" "TP36"
			(at -1.9 9.816204 90)
			(layer "B.SilkS")
			(effects
				(font
					(size 0.7 0.7)
					(thickness 0.15)
				)
				(justify left bottom mirror)
			)
		)
		(property "Value" "TP_1mm_SMD"
			(at 0 -1.4 90)
			(layer "B.Fab")
			(hide yes)
			(effects
				(font
					(size 0.7 0.7)
					(thickness 0.15)
				)
				(justify left bottom mirror)
			)
		)
		(property "Description" "Test point 1mm SMD"
			(at 0 0 90)
			(layer "B.Fab")
			(hide yes)
			(effects
				(font
					(size 1.27 1.27)
					(thickness 0.15)
				)
				(justify mirror)
			)
		)
		(property "MPN" ""
			(at 0 0 90)
			(unlocked yes)
			(layer "B.Fab")
			(hide yes)
			(effects
				(font
					(size 1 1)
					(thickness 0.15)
				)
				(justify mirror)
			)
		)
		(property "Manufacturer" ""
			(at 0 0 90)
			(unlocked yes)
			(layer "B.Fab")
			(hide yes)
			(effects
				(font
					(size 1 1)
					(thickness 0.15)
				)
				(justify mirror)
			)
		)
		(property "Author" "Antmicro"
			(at 0 0 90)
			(unlocked yes)
			(layer "B.Fab")
			(hide yes)
			(effects
				(font
					(size 1 1)
					(thickness 0.15)
				)
				(justify mirror)
			)
		)
		(property "License" "Apache-2.0"
			(at 0 0 90)
			(unlocked yes)
			(layer "B.Fab")
			(hide yes)
			(effects
				(font
					(size 1 1)
					(thickness 0.15)
				)
				(justify mirror)
			)
		)
		(sheetname "/Fan controller/")
		(sheetfile "fan-controller.kicad_sch")
		(attr exclude_from_pos_files exclude_from_bom dnp)
		(fp_circle
			(center 0 0)
			(end 0.6 0)
			(stroke
				(width 0.05)
				(type default)
			)
			(fill no)
			(layer "B.CrtYd")
		)
		(pad "1" smd circle
			(at 0 0 270)
			(size 1 1)
			(layers "B.Cu" "B.Mask")
			(net 388 "/Fan controller/+5V")
			(pinfunction "1")
			(pintype "passive")
		)
	)
	(footprint "antmicro-footprints:R_0402_1005Metric"
		(layer "B.Cu")
		(at 109.5 69.6 180)
		(descr "Resistor SMD 0402")
		(tags "resistor SMD 0402")
		(property "Reference" "R168"
			(at -1.44 5.61 0)
			(layer "B.SilkS")
			(effects
				(font
					(size 0.7 0.7)
					(thickness 0.15)
				)
				(justify left bottom mirror)
			)
		)
		(property "Value" "R_0R_0402"
			(at -1.011843 -1.772046 0)
			(layer "B.Fab")
			(hide yes)
			(effects
				(font
					(size 0.7 0.7)
					(thickness 0.15)
				)
				(justify left bottom mirror)
			)
		)
		(property "Datasheet" "https://industrial.panasonic.com/cdbs/www-data/pdf/RDA0000/AOA0000C301.pdf"
			(at 0 0 0)
			(layer "B.Fab")
			(hide yes)
			(effects
				(font
					(size 1.27 1.27)
					(thickness 0.15)
				)
				(justify mirror)
			)
		)
		(property "Description" "SMD Chip Resistor, Jumper, 0 ohm, 100 mW, 0402 [1005 Metric], Thick Film, General Purpose"
			(at 0 0 0)
			(layer "B.Fab")
			(hide yes)
			(effects
				(font
					(size 1.27 1.27)
					(thickness 0.15)
				)
				(justify mirror)
			)
		)
		(property "MPN" "ERJ2GE0R00X"
			(at 0 0 180)
			(unlocked yes)
			(layer "B.Fab")
			(hide yes)
			(effects
				(font
					(size 1 1)
					(thickness 0.15)
				)
				(justify mirror)
			)
		)
		(property "Manufacturer" "Panasonic"
			(at 0 0 180)
			(unlocked yes)
			(layer "B.Fab")
			(hide yes)
			(effects
				(font
					(size 1 1)
					(thickness 0.15)
				)
				(justify mirror)
			)
		)
		(property "License" "Apache-2.0"
			(at 0 0 180)
			(unlocked yes)
			(layer "B.Fab")
			(hide yes)
			(effects
				(font
					(size 1 1)
					(thickness 0.15)
				)
				(justify mirror)
			)
		)
		(property "Author" "Antmicro"
			(at 0 0 180)
			(unlocked yes)
			(layer "B.Fab")
			(hide yes)
			(effects
				(font
					(size 1 1)
					(thickness 0.15)
				)
				(justify mirror)
			)
		)
		(property "Val" "0R"
			(at 0 0 180)
			(unlocked yes)
			(layer "B.Fab")
			(hide yes)
			(effects
				(font
					(size 1 1)
					(thickness 0.15)
				)
				(justify mirror)
			)
		)
		(property "Tolerance" "~"
			(at 0 0 180)
			(unlocked yes)
			(layer "B.Fab")
			(hide yes)
			(effects
				(font
					(size 1 1)
					(thickness 0.15)
				)
				(justify mirror)
			)
		)
		(property "Current" "1A"
			(at 0 0 180)
			(unlocked yes)
			(layer "B.Fab")
			(hide yes)
			(effects
				(font
					(size 1 1)
					(thickness 0.15)
				)
				(justify mirror)
			)
		)
		(sheetname "/OCuLink/")
		(sheetfile "oculink.kicad_sch")
		(attr smd)
		(fp_rect
			(start -0.925 0.47)
			(end 0.925 -0.47)
			(stroke
				(width 0.05)
				(type default)
			)
			(fill no)
			(layer "B.CrtYd")
		)
		(fp_rect
			(start -0.5 0.25)
			(end 0.5 -0.25)
			(stroke
				(width 0.15)
				(type solid)
			)
			(fill no)
			(layer "B.Fab")
		)
		(pad "1" smd roundrect
			(at -0.48 0 180)
			(size 0.59 0.64)
			(layers "B.Cu" "B.Mask" "B.Paste")
			(roundrect_rratio 0.25)
			(net 321 "/OCuLink/~{CPRSNT}_R")
			(pintype "passive")
		)
		(pad "2" smd roundrect
			(at 0.48 0 180)
			(size 0.59 0.64)
			(layers "B.Cu" "B.Mask" "B.Paste")
			(roundrect_rratio 0.25)
			(net 393 "/OCuLink/~{CPRSNT}")
			(pintype "passive")
		)
	)
	(footprint "antmicro-footprints:C_0402_1005Metric"
		(layer "B.Cu")
		(at 78.22 103.23 90)
		(descr "Capacitor SMD 0402")
		(tags "capacitor SMD 0402")
		(property "Reference" "C182"
			(at -11.62 -0.04 90)
			(layer "B.SilkS")
			(effects
				(font
					(size 0.7 0.7)
					(thickness 0.15)
				)
				(justify right top mirror)
			)
		)
		(property "Value" "C_1u_25V_0402"
			(at -1.022927 -2.155213 90)
			(layer "B.Fab")
			(hide yes)
			(effects
				(font
					(size 0.7 0.7)
					(thickness 0.15)
				)
				(justify right top mirror)
			)
		)
		(property "Datasheet" "https://www.murata.com/products/productdetail?partno=GRM155R61E105KE11%23"
			(at 0 0 90)
			(layer "B.Fab")
			(hide yes)
			(effects
				(font
					(size 1.27 1.27)
					(thickness 0.15)
				)
				(justify mirror)
			)
		)
		(property "Description" "SMD Multilayer Ceramic Capacitor, 1 µF, 25 V, 0402 [1005 Metric], ± 10%, X5R, GRM Series"
			(at 0 0 90)
			(layer "B.Fab")
			(hide yes)
			(effects
				(font
					(size 1.27 1.27)
					(thickness 0.15)
				)
				(justify mirror)
			)
		)
		(property "MPN" "GRM155R61E105KE11J"
			(at 0 0 90)
			(unlocked yes)
			(layer "B.Fab")
			(hide yes)
			(effects
				(font
					(size 1 1)
					(thickness 0.15)
				)
				(justify mirror)
			)
		)
		(property "Manufacturer" "Murata"
			(at 0 0 90)
			(unlocked yes)
			(layer "B.Fab")
			(hide yes)
			(effects
				(font
					(size 1 1)
					(thickness 0.15)
				)
				(justify mirror)
			)
		)
		(property "License" "Apache-2.0"
			(at 0 0 90)
			(unlocked yes)
			(layer "B.Fab")
			(hide yes)
			(effects
				(font
					(size 1 1)
					(thickness 0.15)
				)
				(justify mirror)
			)
		)
		(property "Author" "Antmicro"
			(at 0 0 90)
			(unlocked yes)
			(layer "B.Fab")
			(hide yes)
			(effects
				(font
					(size 1 1)
					(thickness 0.15)
				)
				(justify mirror)
			)
		)
		(property "Val" "1u"
			(at 0 0 90)
			(unlocked yes)
			(layer "B.Fab")
			(hide yes)
			(effects
				(font
					(size 1 1)
					(thickness 0.15)
				)
				(justify mirror)
			)
		)
		(property "Voltage" "25V"
			(at 0 0 90)
			(unlocked yes)
			(layer "B.Fab")
			(hide yes)
			(effects
				(font
					(size 1 1)
					(thickness 0.15)
				)
				(justify mirror)
			)
		)
		(property "Dielectric" "X5R"
			(at 0 0 90)
			(unlocked yes)
			(layer "B.Fab")
			(hide yes)
			(effects
				(font
					(size 1 1)
					(thickness 0.15)
				)
				(justify mirror)
			)
		)
		(sheetname "/X710-AT2 power/")
		(sheetfile "x710-at2-power.kicad_sch")
		(attr smd)
		(fp_rect
			(start -0.925 0.47)
			(end 0.925 -0.47)
			(stroke
				(width 0.05)
				(type default)
			)
			(fill no)
			(layer "B.CrtYd")
		)
		(fp_line
			(start 0.504 -0.248)
			(end -0.494 -0.248)
			(stroke
				(width 0.15)
				(type solid)
			)
			(layer "B.Fab")
		)
		(fp_line
			(start -0.494 -0.248)
			(end -0.494 0.25)
			(stroke
				(width 0.15)
				(type solid)
			)
			(layer "B.Fab")
		)
		(fp_line
			(start 0.504 0.25)
			(end 0.504 -0.248)
			(stroke
				(width 0.15)
				(type solid)
			)
			(layer "B.Fab")
		)
		(fp_line
			(start -0.494 0.25)
			(end 0.504 0.25)
			(stroke
				(width 0.15)
				(type solid)
			)
			(layer "B.Fab")
		)
		(pad "1" smd roundrect
			(at -0.48 0 90)
			(size 0.59 0.64)
			(layers "B.Cu" "B.Mask" "B.Paste")
			(roundrect_rratio 0.25)
			(net 28 "GND")
			(pintype "passive")
		)
		(pad "2" smd roundrect
			(at 0.48 0 90)
			(size 0.59 0.64)
			(layers "B.Cu" "B.Mask" "B.Paste")
			(roundrect_rratio 0.25)
			(net 12 "XFI_VDD")
			(pintype "passive")
		)
	)
	(footprint "antmicro-footprints:C_0402_1005Metric"
		(layer "B.Cu")
		(at 86.225 100.15 90)
		(descr "Capacitor SMD 0402")
		(tags "capacitor SMD 0402")
		(property "Reference" "C114"
			(at 9.87 -0.43151 90)
			(layer "B.SilkS")
			(effects
				(font
					(size 0.7 0.7)
					(thickness 0.15)
				)
				(justify right top mirror)
			)
		)
		(property "Value" "C_1u_25V_0402"
			(at -1.022927 -2.155213 90)
			(layer "B.Fab")
			(hide yes)
			(effects
				(font
					(size 0.7 0.7)
					(thickness 0.15)
				)
				(justify right top mirror)
			)
		)
		(property "Datasheet" "https://www.murata.com/products/productdetail?partno=GRM155R61E105KE11%23"
			(at 0 0 90)
			(layer "B.Fab")
			(hide yes)
			(effects
				(font
					(size 1.27 1.27)
					(thickness 0.15)
				)
				(justify mirror)
			)
		)
		(property "Description" "SMD Multilayer Ceramic Capacitor, 1 µF, 25 V, 0402 [1005 Metric], ± 10%, X5R, GRM Series"
			(at 0 0 90)
			(layer "B.Fab")
			(hide yes)
			(effects
				(font
					(size 1.27 1.27)
					(thickness 0.15)
				)
				(justify mirror)
			)
		)
		(property "MPN" "GRM155R61E105KE11J"
			(at 0 0 90)
			(unlocked yes)
			(layer "B.Fab")
			(hide yes)
			(effects
				(font
					(size 1 1)
					(thickness 0.15)
				)
				(justify mirror)
			)
		)
		(property "Manufacturer" "Murata"
			(at 0 0 90)
			(unlocked yes)
			(layer "B.Fab")
			(hide yes)
			(effects
				(font
					(size 1 1)
					(thickness 0.15)
				)
				(justify mirror)
			)
		)
		(property "License" "Apache-2.0"
			(at 0 0 90)
			(unlocked yes)
			(layer "B.Fab")
			(hide yes)
			(effects
				(font
					(size 1 1)
					(thickness 0.15)
				)
				(justify mirror)
			)
		)
		(property "Author" "Antmicro"
			(at 0 0 90)
			(unlocked yes)
			(layer "B.Fab")
			(hide yes)
			(effects
				(font
					(size 1 1)
					(thickness 0.15)
				)
				(justify mirror)
			)
		)
		(property "Val" "1u"
			(at 0 0 90)
			(unlocked yes)
			(layer "B.Fab")
			(hide yes)
			(effects
				(font
					(size 1 1)
					(thickness 0.15)
				)
				(justify mirror)
			)
		)
		(property "Voltage" "25V"
			(at 0 0 90)
			(unlocked yes)
			(layer "B.Fab")
			(hide yes)
			(effects
				(font
					(size 1 1)
					(thickness 0.15)
				)
				(justify mirror)
			)
		)
		(property "Dielectric" "X5R"
			(at 0 0 90)
			(unlocked yes)
			(layer "B.Fab")
			(hide yes)
			(effects
				(font
					(size 1 1)
					(thickness 0.15)
				)
				(justify mirror)
			)
		)
		(sheetname "/X710-AT2 power/")
		(sheetfile "x710-at2-power.kicad_sch")
		(attr smd)
		(fp_rect
			(start -0.925 0.47)
			(end 0.925 -0.47)
			(stroke
				(width 0.05)
				(type default)
			)
			(fill no)
			(layer "B.CrtYd")
		)
		(fp_line
			(start 0.504 -0.248)
			(end -0.494 -0.248)
			(stroke
				(width 0.15)
				(type solid)
			)
			(layer "B.Fab")
		)
		(fp_line
			(start -0.494 -0.248)
			(end -0.494 0.25)
			(stroke
				(width 0.15)
				(type solid)
			)
			(layer "B.Fab")
		)
		(fp_line
			(start 0.504 0.25)
			(end 0.504 -0.248)
			(stroke
				(width 0.15)
				(type solid)
			)
			(layer "B.Fab")
		)
		(fp_line
			(start -0.494 0.25)
			(end 0.504 0.25)
			(stroke
				(width 0.15)
				(type solid)
			)
			(layer "B.Fab")
		)
		(pad "1" smd roundrect
			(at -0.48 0 90)
			(size 0.59 0.64)
			(layers "B.Cu" "B.Mask" "B.Paste")
			(roundrect_rratio 0.25)
			(net 28 "GND")
			(pintype "passive")
		)
		(pad "2" smd roundrect
			(at 0.48 0 90)
			(size 0.59 0.64)
			(layers "B.Cu" "B.Mask" "B.Paste")
			(roundrect_rratio 0.25)
			(net 9 "VCCD")
			(pintype "passive")
		)
	)
	(footprint "antmicro-footprints:USON-10_2.5x1mm_P0.5mm"
		(layer "B.Cu")
		(at 99.75 55.88366 90)
		(descr "USON-10 2.5x1mm_ Pitch 0.5mm")
		(tags "USON-10 2.5x1mm Pitch 0.5mm")
		(property "Reference" "D9"
			(at -0.90134 -0.75 180)
			(layer "B.SilkS")
			(effects
				(font
					(size 0.7 0.7)
					(thickness 0.15)
				)
				(justify right top mirror)
			)
		)
		(property "Value" "ESD204DQAR"
			(at 0.018 -2.499 90)
			(layer "B.Fab")
			(hide yes)
			(effects
				(font
					(size 0.7 0.7)
					(thickness 0.15)
				)
				(justify right top mirror)
			)
		)
		(property "Datasheet" "https://www.ti.com/lit/ds/symlink/esd204.pdf?ts=1706004844383&ref_url=https%253A%252F%252Fwww.ti.com%252Finterface%252Fdiodes%252Fesd-protection-diodes%252Fproducts.html"
			(at 0 0 90)
			(layer "B.Fab")
			(hide yes)
			(effects
				(font
					(size 1.27 1.27)
					(thickness 0.15)
				)
				(justify mirror)
			)
		)
		(property "Description" "TVS diode array, 30 kV, USON-10, 3.6 V, 0.55 pF"
			(at 0 0 90)
			(layer "B.Fab")
			(hide yes)
			(effects
				(font
					(size 1.27 1.27)
					(thickness 0.15)
				)
				(justify mirror)
			)
		)
		(property "MPN" "ESD204DQAR"
			(at 0 0 90)
			(unlocked yes)
			(layer "B.Fab")
			(hide yes)
			(effects
				(font
					(size 1 1)
					(thickness 0.15)
				)
				(justify mirror)
			)
		)
		(property "Manufacturer" "Texas Instruments"
			(at 0 0 90)
			(unlocked yes)
			(layer "B.Fab")
			(hide yes)
			(effects
				(font
					(size 1 1)
					(thickness 0.15)
				)
				(justify mirror)
			)
		)
		(property "Author" "Antmicro"
			(at 0 0 90)
			(unlocked yes)
			(layer "B.Fab")
			(hide yes)
			(effects
				(font
					(size 1 1)
					(thickness 0.15)
				)
				(justify mirror)
			)
		)
		(property "License" "Apache-2.0"
			(at 0 0 90)
			(unlocked yes)
			(layer "B.Fab")
			(hide yes)
			(effects
				(font
					(size 1 1)
					(thickness 0.15)
				)
				(justify mirror)
			)
		)
		(sheetname "/OCuLink/")
		(sheetfile "oculink.kicad_sch")
		(attr smd)
		(fp_line
			(start 0.498 -1.398)
			(end -0.5 -1.398)
			(stroke
				(width 0.15)
				(type solid)
			)
			(layer "B.SilkS")
		)
		(fp_line
			(start 0.498 1.401)
			(end -0.5 1.401)
			(stroke
				(width 0.15)
				(type solid)
			)
			(layer "B.SilkS")
		)
		(fp_circle
			(center -0.68 1.27)
			(end -0.63 1.27)
			(stroke
				(width 0.15)
				(type solid)
			)
			(fill yes)
			(layer "B.SilkS")
		)
		(fp_rect
			(start -0.8 1.5)
			(end 0.8 -1.499)
			(stroke
				(width 0.05)
				(type solid)
			)
			(fill no)
			(layer "B.CrtYd")
		)
		(fp_line
			(start -0.5 -1.249)
			(end 0.498 -1.249)
			(stroke
				(width 0.15)
				(type solid)
			)
			(layer "B.Fab")
		)
		(fp_line
			(start -0.5 1)
			(end -0.5 -1.249)
			(stroke
				(width 0.15)
				(type solid)
			)
			(layer "B.Fab")
		)
		(fp_line
			(start 0.498 1.25)
			(end 0.498 -1.249)
			(stroke
				(width 0.15)
				(type solid)
			)
			(layer "B.Fab")
		)
		(fp_line
			(start 0.498 1.25)
			(end -0.25 1.25)
			(stroke
				(width 0.15)
				(type solid)
			)
			(layer "B.Fab")
		)
		(fp_line
			(start -0.25 1.25)
			(end -0.5 1)
			(stroke
				(width 0.15)
				(type solid)
			)
			(layer "B.Fab")
		)
		(pad "1" smd roundrect
			(at -0.387 1 180)
			(size 0.25 0.55)
			(layers "B.Cu" "B.Mask" "B.Paste")
			(roundrect_rratio 0.25)
			(net 304 "/OCuLink/SCL")
			(pintype "passive")
		)
		(pad "2" smd roundrect
			(at -0.387 0.5 180)
			(size 0.25 0.55)
			(layers "B.Cu" "B.Mask" "B.Paste")
			(roundrect_rratio 0.25)
			(net 226 "/OCuLink/SDA")
			(pintype "passive")
		)
		(pad "3" smd roundrect
			(at -0.387 0 180)
			(size 0.4 0.55)
			(layers "B.Cu" "B.Mask" "B.Paste")
			(roundrect_rratio 0.25)
			(net 28 "GND")
			(pintype "power_in")
		)
		(pad "4" smd roundrect
			(at -0.387 -0.498 180)
			(size 0.25 0.55)
			(layers "B.Cu" "B.Mask" "B.Paste")
			(roundrect_rratio 0.25)
			(net 319 "/OCuLink/~{PE_ RST}_R")
			(pintype "passive")
		)
		(pad "5" smd roundrect
			(at -0.387 -0.998 180)
			(size 0.25 0.55)
			(layers "B.Cu" "B.Mask" "B.Paste")
			(roundrect_rratio 0.25)
			(net 321 "/OCuLink/~{CPRSNT}_R")
			(pintype "passive")
		)
		(pad "6" smd roundrect
			(at 0.385 -0.998 180)
			(size 0.25 0.55)
			(layers "B.Cu" "B.Mask" "B.Paste")
			(roundrect_rratio 0.25)
			(net 321 "/OCuLink/~{CPRSNT}_R")
			(pintype "passive")
		)
		(pad "7" smd roundrect
			(at 0.385 -0.498 180)
			(size 0.25 0.55)
			(layers "B.Cu" "B.Mask" "B.Paste")
			(roundrect_rratio 0.25)
			(net 319 "/OCuLink/~{PE_ RST}_R")
			(pintype "passive")
		)
		(pad "8" smd roundrect
			(at 0.385 0 180)
			(size 0.4 0.55)
			(layers "B.Cu" "B.Mask" "B.Paste")
			(roundrect_rratio 0.25)
			(net 28 "GND")
			(pintype "passive")
		)
		(pad "9" smd roundrect
			(at 0.385 0.5 180)
			(size 0.25 0.55)
			(layers "B.Cu" "B.Mask" "B.Paste")
			(roundrect_rratio 0.25)
			(net 226 "/OCuLink/SDA")
			(pintype "passive")
		)
		(pad "10" smd roundrect
			(at 0.385 1 180)
			(size 0.25 0.55)
			(layers "B.Cu" "B.Mask" "B.Paste")
			(roundrect_rratio 0.25)
			(net 304 "/OCuLink/SCL")
			(pintype "passive")
		)
	)
	(footprint "antmicro-footprints:SOT-416"
		(layer "B.Cu")
		(at 56.25 125.1)
		(descr "SOT-416")
		(tags "SOT-416")
		(property "Reference" "Q5"
			(at 1.169999 0.8 90)
			(layer "B.SilkS")
			(effects
				(font
					(size 0.7 0.7)
					(thickness 0.15)
				)
				(justify right top mirror)
			)
		)
		(property "Value" "DTC014T_SOT-416"
			(at 0 -2.000001 0)
			(layer "B.Fab")
			(hide yes)
			(effects
				(font
					(size 0.7 0.7)
					(thickness 0.15)
				)
				(justify right top mirror)
			)
		)
		(property "Datasheet" "https://www.rohm.com/datasheet?p=DTC014TEB&dist=Mouser&media=referral&source=mouser.com&campaign=Mouser"
			(at 0 0 0)
			(layer "B.Fab")
			(hide yes)
			(effects
				(font
					(size 1.27 1.27)
					(thickness 0.15)
				)
				(justify mirror)
			)
		)
		(property "Description" "Bipolar (BJT) Single Transistor with built-in base resistor, NPN, 50V, 100mA, 150mW, SOT-416FL, Surface Mount"
			(at 0 0 0)
			(layer "B.Fab")
			(hide yes)
			(effects
				(font
					(size 1.27 1.27)
					(thickness 0.15)
				)
				(justify mirror)
			)
		)
		(property "Manufacturer" "ROHM Semiconductor"
			(at 0 0 180)
			(unlocked yes)
			(layer "B.Fab")
			(hide yes)
			(effects
				(font
					(size 1 1)
					(thickness 0.15)
				)
				(justify mirror)
			)
		)
		(property "MPN" "DTC014TEBTL"
			(at 0 0 180)
			(unlocked yes)
			(layer "B.Fab")
			(hide yes)
			(effects
				(font
					(size 1 1)
					(thickness 0.15)
				)
				(justify mirror)
			)
		)
		(property "Author" "Antmicro"
			(at 0 0 180)
			(unlocked yes)
			(layer "B.Fab")
			(hide yes)
			(effects
				(font
					(size 1 1)
					(thickness 0.15)
				)
				(justify mirror)
			)
		)
		(property "License" "Apache-2.0"
			(at 0 0 180)
			(unlocked yes)
			(layer "B.Fab")
			(hide yes)
			(effects
				(font
					(size 1 1)
					(thickness 0.15)
				)
				(justify mirror)
			)
		)
		(sheetname "/Power/")
		(sheetfile "power.kicad_sch")
		(attr smd)
		(fp_line
			(start -0.5 0.15)
			(end -0.5 -0.15)
			(stroke
				(width 0.15)
				(type solid)
			)
			(layer "B.SilkS")
		)
		(fp_line
			(start 0.5 -0.9)
			(end -0.5 -0.9)
			(stroke
				(width 0.15)
				(type solid)
			)
			(layer "B.SilkS")
		)
		(fp_line
			(start 0.5 -0.9)
			(end 0.5 -0.7)
			(stroke
				(width 0.15)
				(type solid)
			)
			(layer "B.SilkS")
		)
		(fp_line
			(start 0.508 0.9)
			(end -0.5 0.9)
			(stroke
				(width 0.15)
				(type solid)
			)
			(layer "B.SilkS")
		)
		(fp_line
			(start 0.508 0.9)
			(end 0.508 0.592)
			(stroke
				(width 0.15)
				(type solid)
			)
			(layer "B.SilkS")
		)
		(fp_rect
			(start -1 1.05)
			(end 1 -1.05)
			(stroke
				(width 0.05)
				(type solid)
			)
			(fill no)
			(layer "B.CrtYd")
		)
		(fp_line
			(start -0.05 0.9)
			(end -0.45 0.5)
			(stroke
				(width 0.15)
				(type solid)
			)
			(layer "B.Fab")
		)
		(fp_rect
			(start 0.45 -0.9)
			(end -0.45 0.9)
			(stroke
				(width 0.15)
				(type solid)
			)
			(fill no)
			(layer "B.Fab")
		)
		(fp_text user "${REFERENCE}"
			(at -1 -3.4 180)
			(layer "B.Fab")
			(effects
				(font
					(size 0.7 0.7)
					(thickness 0.15)
				)
				(justify left bottom mirror)
			)
		)
		(fp_text user "Author: Antmicro"
			(at -1 -4.602 180)
			(layer "B.Fab")
			(effects
				(font
					(size 0.7 0.7)
					(thickness 0.15)
				)
				(justify left bottom mirror)
			)
		)
		(fp_text user "License: Apache-2.0"
			(at -1 -5.802 180)
			(layer "B.Fab")
			(effects
				(font
					(size 0.7 0.7)
					(thickness 0.15)
				)
				(justify left bottom mirror)
			)
		)
		(pad "1" smd rect
			(at -0.652 0.5)
			(size 0.6 0.5)
			(layers "B.Cu" "B.Mask" "B.Paste")
			(net 303 "/Power/+VCCD_OUT")
			(pinfunction "B")
			(pintype "input")
		)
		(pad "2" smd rect
			(at -0.652 -0.498)
			(size 0.6 0.5)
			(layers "B.Cu" "B.Mask" "B.Paste")
			(net 28 "GND")
			(pinfunction "E")
			(pintype "passive")
		)
		(pad "3" smd rect
			(at 0.65 0)
			(size 0.6 0.5)
			(layers "B.Cu" "B.Mask" "B.Paste")
			(net 416 "Net-(Q5-C)")
			(pinfunction "C")
			(pintype "passive")
		)
	)
	(footprint "antmicro-footprints:C_0402_1005Metric"
		(layer "B.Cu")
		(at 93.48 145.34 -90)
		(descr "Capacitor SMD 0402")
		(tags "capacitor SMD 0402")
		(property "Reference" "C62"
			(at -2.91 -0.47 90)
			(layer "B.SilkS")
			(effects
				(font
					(size 0.7 0.7)
					(thickness 0.15)
				)
				(justify left bottom mirror)
			)
		)
		(property "Value" "C_470p_0402"
			(at -1.022927 -2.155213 90)
			(layer "B.Fab")
			(hide yes)
			(effects
				(font
					(size 0.7 0.7)
					(thickness 0.15)
				)
				(justify left bottom mirror)
			)
		)
		(property "Datasheet" "https://www.passivecomponent.com/wp-content/uploads/datasheet/WTC_MLCC_General_Purpose.pdf"
			(at 0 0 90)
			(layer "B.Fab")
			(hide yes)
			(effects
				(font
					(size 1.27 1.27)
					(thickness 0.15)
				)
				(justify mirror)
			)
		)
		(property "Description" "SMD Multilayer Ceramic Capacitor, General Purpose, 470 pF, 25 V, 0402 [1005 Metric], ± 10%, X7R"
			(at 0 0 90)
			(layer "B.Fab")
			(hide yes)
			(effects
				(font
					(size 1.27 1.27)
					(thickness 0.15)
				)
				(justify mirror)
			)
		)
		(property "MPN" "0402B471K250CT"
			(at 0 0 270)
			(unlocked yes)
			(layer "B.Fab")
			(hide yes)
			(effects
				(font
					(size 1 1)
					(thickness 0.15)
				)
				(justify mirror)
			)
		)
		(property "Manufacturer" "Walsin"
			(at 0 0 270)
			(unlocked yes)
			(layer "B.Fab")
			(hide yes)
			(effects
				(font
					(size 1 1)
					(thickness 0.15)
				)
				(justify mirror)
			)
		)
		(property "License" "Apache-2.0"
			(at 0 0 270)
			(unlocked yes)
			(layer "B.Fab")
			(hide yes)
			(effects
				(font
					(size 1 1)
					(thickness 0.15)
				)
				(justify mirror)
			)
		)
		(property "Author" "Antmicro"
			(at 0 0 270)
			(unlocked yes)
			(layer "B.Fab")
			(hide yes)
			(effects
				(font
					(size 1 1)
					(thickness 0.15)
				)
				(justify mirror)
			)
		)
		(property "Val" "470p"
			(at 0 0 270)
			(unlocked yes)
			(layer "B.Fab")
			(hide yes)
			(effects
				(font
					(size 1 1)
					(thickness 0.15)
				)
				(justify mirror)
			)
		)
		(property "Voltage" "25V"
			(at 0 0 270)
			(unlocked yes)
			(layer "B.Fab")
			(hide yes)
			(effects
				(font
					(size 1 1)
					(thickness 0.15)
				)
				(justify mirror)
			)
		)
		(property "Dielectric" "X7R"
			(at 0 0 270)
			(unlocked yes)
			(layer "B.Fab")
			(hide yes)
			(effects
				(font
					(size 1 1)
					(thickness 0.15)
				)
				(justify mirror)
			)
		)
		(sheetname "/2xRJ45/")
		(sheetfile "2xrj45.kicad_sch")
		(attr smd)
		(fp_rect
			(start -0.925 0.47)
			(end 0.925 -0.47)
			(stroke
				(width 0.05)
				(type default)
			)
			(fill no)
			(layer "B.CrtYd")
		)
		(fp_line
			(start -0.494 0.25)
			(end 0.504 0.25)
			(stroke
				(width 0.15)
				(type solid)
			)
			(layer "B.Fab")
		)
		(fp_line
			(start 0.504 0.25)
			(end 0.504 -0.248)
			(stroke
				(width 0.15)
				(type solid)
			)
			(layer "B.Fab")
		)
		(fp_line
			(start -0.494 -0.248)
			(end -0.494 0.25)
			(stroke
				(width 0.15)
				(type solid)
			)
			(layer "B.Fab")
		)
		(fp_line
			(start 0.504 -0.248)
			(end -0.494 -0.248)
			(stroke
				(width 0.15)
				(type solid)
			)
			(layer "B.Fab")
		)
		(pad "1" smd roundrect
			(at -0.48 0 270)
			(size 0.59 0.64)
			(layers "B.Cu" "B.Mask" "B.Paste")
			(roundrect_rratio 0.25)
			(net 28 "GND")
			(pintype "passive")
		)
		(pad "2" smd roundrect
			(at 0.48 0 270)
			(size 0.59 0.64)
			(layers "B.Cu" "B.Mask" "B.Paste")
			(roundrect_rratio 0.25)
			(net 66 "Net-(J6-LED_GRN-)")
			(pintype "passive")
		)
	)
	(footprint "antmicro-footprints:R_0402_1005Metric"
		(layer "B.Cu")
		(at 109.5 70.6 180)
		(descr "Resistor SMD 0402")
		(tags "resistor SMD 0402")
		(property "Reference" "R166"
			(at -1.44 5.61 0)
			(layer "B.SilkS")
			(effects
				(font
					(size 0.7 0.7)
					(thickness 0.15)
				)
				(justify left bottom mirror)
			)
		)
		(property "Value" "R_10k_0402"
			(at -1.011843 -1.772046 0)
			(layer "B.Fab")
			(hide yes)
			(effects
				(font
					(size 0.7 0.7)
					(thickness 0.15)
				)
				(justify left bottom mirror)
			)
		)
		(property "Datasheet" "https://www.bourns.com/docs/product-datasheets/cr.pdf"
			(at 0 0 0)
			(layer "B.Fab")
			(hide yes)
			(effects
				(font
					(size 1.27 1.27)
					(thickness 0.15)
				)
				(justify mirror)
			)
		)
		(property "Description" "SMD Chip Resistor, 10 kohm, ± 1%, 62.5 mW, 0402 [1005 Metric], Thick Film, General Purpose"
			(at 0 0 0)
			(layer "B.Fab")
			(hide yes)
			(effects
				(font
					(size 1.27 1.27)
					(thickness 0.15)
				)
				(justify mirror)
			)
		)
		(property "MPN" "CR0402-FX-1002GLF"
			(at 0 0 180)
			(unlocked yes)
			(layer "B.Fab")
			(hide yes)
			(effects
				(font
					(size 1 1)
					(thickness 0.15)
				)
				(justify mirror)
			)
		)
		(property "Manufacturer" "Bourns"
			(at 0 0 180)
			(unlocked yes)
			(layer "B.Fab")
			(hide yes)
			(effects
				(font
					(size 1 1)
					(thickness 0.15)
				)
				(justify mirror)
			)
		)
		(property "License" "Apache-2.0"
			(at 0 0 180)
			(unlocked yes)
			(layer "B.Fab")
			(hide yes)
			(effects
				(font
					(size 1 1)
					(thickness 0.15)
				)
				(justify mirror)
			)
		)
		(property "Author" "Antmicro"
			(at 0 0 180)
			(unlocked yes)
			(layer "B.Fab")
			(hide yes)
			(effects
				(font
					(size 1 1)
					(thickness 0.15)
				)
				(justify mirror)
			)
		)
		(property "Val" "10k"
			(at 0 0 180)
			(unlocked yes)
			(layer "B.Fab")
			(hide yes)
			(effects
				(font
					(size 1 1)
					(thickness 0.15)
				)
				(justify mirror)
			)
		)
		(property "Tolerance" "1%"
			(at 0 0 180)
			(unlocked yes)
			(layer "B.Fab")
			(hide yes)
			(effects
				(font
					(size 1 1)
					(thickness 0.15)
				)
				(justify mirror)
			)
		)
		(sheetname "/OCuLink/")
		(sheetfile "oculink.kicad_sch")
		(attr smd exclude_from_pos_files exclude_from_bom dnp)
		(fp_rect
			(start -0.925 0.47)
			(end 0.925 -0.47)
			(stroke
				(width 0.05)
				(type default)
			)
			(fill no)
			(layer "B.CrtYd")
		)
		(fp_rect
			(start -0.5 0.25)
			(end 0.5 -0.25)
			(stroke
				(width 0.15)
				(type solid)
			)
			(fill no)
			(layer "B.Fab")
		)
		(pad "1" smd roundrect
			(at -0.48 0 180)
			(size 0.59 0.64)
			(layers "B.Cu" "B.Mask" "B.Paste")
			(roundrect_rratio 0.25)
			(net 320 "/OCuLink/~{CWAKE}_R")
			(pintype "passive")
		)
		(pad "2" smd roundrect
			(at 0.48 0 180)
			(size 0.59 0.64)
			(layers "B.Cu" "B.Mask" "B.Paste")
			(roundrect_rratio 0.25)
			(net 7 "+3V3")
			(pintype "passive")
		)
	)
	(footprint "antmicro-footprints:R_0402_1005Metric"
		(layer "B.Cu")
		(at 96.45 98.1)
		(descr "Resistor SMD 0402")
		(tags "resistor SMD 0402")
		(property "Reference" "R63"
			(at 0.9 -0.35 0)
			(layer "B.SilkS")
			(effects
				(font
					(size 0.7 0.7)
					(thickness 0.15)
				)
				(justify right top mirror)
			)
		)
		(property "Value" "R_3k3_0402"
			(at -1.011843 -1.772046 0)
			(layer "B.Fab")
			(hide yes)
			(effects
				(font
					(size 0.7 0.7)
					(thickness 0.15)
				)
				(justify right top mirror)
			)
		)
		(property "Datasheet" "https://www.bourns.com/docs/product-datasheets/cr.pdf"
			(at 0 0 0)
			(layer "B.Fab")
			(hide yes)
			(effects
				(font
					(size 1.27 1.27)
					(thickness 0.15)
				)
				(justify mirror)
			)
		)
		(property "Description" "SMD Chip Resistor, 3.3 kohm, ± 1%, 63 mW, 0402 [1005 Metric], Thick Film, General Purpose"
			(at 0 0 0)
			(layer "B.Fab")
			(hide yes)
			(effects
				(font
					(size 1.27 1.27)
					(thickness 0.15)
				)
				(justify mirror)
			)
		)
		(property "MPN" "CR0402-FX-3301GLF"
			(at 0 0 0)
			(unlocked yes)
			(layer "B.Fab")
			(hide yes)
			(effects
				(font
					(size 1 1)
					(thickness 0.15)
				)
				(justify mirror)
			)
		)
		(property "Manufacturer" "Bourns"
			(at 0 0 0)
			(unlocked yes)
			(layer "B.Fab")
			(hide yes)
			(effects
				(font
					(size 1 1)
					(thickness 0.15)
				)
				(justify mirror)
			)
		)
		(property "License" "Apache-2.0"
			(at 0 0 0)
			(unlocked yes)
			(layer "B.Fab")
			(hide yes)
			(effects
				(font
					(size 1 1)
					(thickness 0.15)
				)
				(justify mirror)
			)
		)
		(property "Author" "Antmicro"
			(at 0 0 0)
			(unlocked yes)
			(layer "B.Fab")
			(hide yes)
			(effects
				(font
					(size 1 1)
					(thickness 0.15)
				)
				(justify mirror)
			)
		)
		(property "Val" "3k3"
			(at 0 0 0)
			(unlocked yes)
			(layer "B.Fab")
			(hide yes)
			(effects
				(font
					(size 1 1)
					(thickness 0.15)
				)
				(justify mirror)
			)
		)
		(property "Tolerance" "1%"
			(at 0 0 0)
			(unlocked yes)
			(layer "B.Fab")
			(hide yes)
			(effects
				(font
					(size 1 1)
					(thickness 0.15)
				)
				(justify mirror)
			)
		)
		(sheetname "/X710-AT2 10GbE/")
		(sheetfile "x710-at2-10gbe.kicad_sch")
		(attr smd)
		(fp_rect
			(start -0.925 0.47)
			(end 0.925 -0.47)
			(stroke
				(width 0.05)
				(type default)
			)
			(fill no)
			(layer "B.CrtYd")
		)
		(fp_rect
			(start -0.5 0.25)
			(end 0.5 -0.25)
			(stroke
				(width 0.15)
				(type solid)
			)
			(fill no)
			(layer "B.Fab")
		)
		(pad "1" smd roundrect
			(at -0.48 0)
			(size 0.59 0.64)
			(layers "B.Cu" "B.Mask" "B.Paste")
			(roundrect_rratio 0.25)
			(net 102 "/X710-AT2 10GbE/MDC1_SCL1")
			(pintype "passive")
		)
		(pad "2" smd roundrect
			(at 0.48 0)
			(size 0.59 0.64)
			(layers "B.Cu" "B.Mask" "B.Paste")
			(roundrect_rratio 0.25)
			(net 7 "+3V3")
			(pintype "passive")
		)
	)
	(footprint "antmicro-footprints:C_0402_1005Metric"
		(layer "B.Cu")
		(at 107.285001 96.4 -90)
		(descr "Capacitor SMD 0402")
		(tags "capacitor SMD 0402")
		(property "Reference" "C77"
			(at -1.01 0.525001 90)
			(layer "B.SilkS")
			(effects
				(font
					(size 0.7 0.7)
					(thickness 0.15)
				)
				(justify left bottom mirror)
			)
		)
		(property "Value" "C_100n_0402"
			(at -1.022927 -2.155213 90)
			(layer "B.Fab")
			(hide yes)
			(effects
				(font
					(size 0.7 0.7)
					(thickness 0.15)
				)
				(justify left bottom mirror)
			)
		)
		(property "Datasheet" "https://www.murata.com/products/productdetail?partno=GRM155R61H104KE14%23"
			(at 0 0 90)
			(layer "B.Fab")
			(hide yes)
			(effects
				(font
					(size 1.27 1.27)
					(thickness 0.15)
				)
				(justify mirror)
			)
		)
		(property "Description" "SMD Multilayer Ceramic Capacitor, 0.1 µF, 50 V, 0402 [1005 Metric], ± 10%, X5R, GRM Series"
			(at 0 0 90)
			(layer "B.Fab")
			(hide yes)
			(effects
				(font
					(size 1.27 1.27)
					(thickness 0.15)
				)
				(justify mirror)
			)
		)
		(property "MPN" "GRM155R61H104KE14D"
			(at 0 0 270)
			(unlocked yes)
			(layer "B.Fab")
			(hide yes)
			(effects
				(font
					(size 1 1)
					(thickness 0.15)
				)
				(justify mirror)
			)
		)
		(property "Val" "100n"
			(at 0 0 270)
			(unlocked yes)
			(layer "B.Fab")
			(hide yes)
			(effects
				(font
					(size 1 1)
					(thickness 0.15)
				)
				(justify mirror)
			)
		)
		(property "Voltage" "50V"
			(at 0 0 270)
			(unlocked yes)
			(layer "B.Fab")
			(hide yes)
			(effects
				(font
					(size 1 1)
					(thickness 0.15)
				)
				(justify mirror)
			)
		)
		(property "Dielectric" "X5R"
			(at 0 0 270)
			(unlocked yes)
			(layer "B.Fab")
			(hide yes)
			(effects
				(font
					(size 1 1)
					(thickness 0.15)
				)
				(justify mirror)
			)
		)
		(property "Manufacturer" "Murata"
			(at 0 0 270)
			(unlocked yes)
			(layer "B.Fab")
			(hide yes)
			(effects
				(font
					(size 1 1)
					(thickness 0.15)
				)
				(justify mirror)
			)
		)
		(property "License" "Apache-2.0"
			(at 0 0 270)
			(unlocked yes)
			(layer "B.Fab")
			(hide yes)
			(effects
				(font
					(size 1 1)
					(thickness 0.15)
				)
				(justify mirror)
			)
		)
		(property "Author" "Antmicro"
			(at 0 0 270)
			(unlocked yes)
			(layer "B.Fab")
			(hide yes)
			(effects
				(font
					(size 1 1)
					(thickness 0.15)
				)
				(justify mirror)
			)
		)
		(sheetname "/X710-AT2 Misc/")
		(sheetfile "x710-at2-mics.kicad_sch")
		(attr smd)
		(fp_rect
			(start -0.925 0.47)
			(end 0.925 -0.47)
			(stroke
				(width 0.05)
				(type default)
			)
			(fill no)
			(layer "B.CrtYd")
		)
		(fp_line
			(start -0.494 0.25)
			(end 0.504 0.25)
			(stroke
				(width 0.15)
				(type solid)
			)
			(layer "B.Fab")
		)
		(fp_line
			(start 0.504 0.25)
			(end 0.504 -0.248)
			(stroke
				(width 0.15)
				(type solid)
			)
			(layer "B.Fab")
		)
		(fp_line
			(start -0.494 -0.248)
			(end -0.494 0.25)
			(stroke
				(width 0.15)
				(type solid)
			)
			(layer "B.Fab")
		)
		(fp_line
			(start 0.504 -0.248)
			(end -0.494 -0.248)
			(stroke
				(width 0.15)
				(type solid)
			)
			(layer "B.Fab")
		)
		(pad "1" smd roundrect
			(at -0.48 0 270)
			(size 0.59 0.64)
			(layers "B.Cu" "B.Mask" "B.Paste")
			(roundrect_rratio 0.25)
			(net 28 "GND")
			(pintype "passive")
		)
		(pad "2" smd roundrect
			(at 0.48 0 270)
			(size 0.59 0.64)
			(layers "B.Cu" "B.Mask" "B.Paste")
			(roundrect_rratio 0.25)
			(net 7 "+3V3")
			(pintype "passive")
		)
	)
	(footprint "antmicro-footprints:C_1206_3216Metric"
		(layer "B.Cu")
		(at 85 131.45 90)
		(descr "Capacitor SMD 1206")
		(tags "capacitor SMD 1206")
		(property "Reference" "C54"
			(at -4.33 -0.38 90)
			(layer "B.SilkS")
			(effects
				(font
					(size 0.7 0.7)
					(thickness 0.15)
				)
				(justify right top mirror)
			)
		)
		(property "Value" "C_220u_1206_6V3"
			(at 0 -2.101 90)
			(layer "B.Fab")
			(hide yes)
			(effects
				(font
					(size 0.7 0.7)
					(thickness 0.15)
				)
				(justify right top mirror)
			)
		)
		(property "Datasheet" "https://www.murata.com/products/productdetail?partno=GRM31CR60J227ME11%23"
			(at 0 0 90)
			(layer "B.Fab")
			(hide yes)
			(effects
				(font
					(size 1.27 1.27)
					(thickness 0.15)
				)
				(justify mirror)
			)
		)
		(property "Description" "SMD Multilayer Ceramic Capacitor, 220 µF, 6.3 V, 1206 [3216 Metric], ± 20%, X5R, GRM Series"
			(at 0 0 90)
			(layer "B.Fab")
			(hide yes)
			(effects
				(font
					(size 1.27 1.27)
					(thickness 0.15)
				)
				(justify mirror)
			)
		)
		(property "MPN" "GRM31CR60J227ME11L"
			(at 0 0 90)
			(unlocked yes)
			(layer "B.Fab")
			(hide yes)
			(effects
				(font
					(size 1 1)
					(thickness 0.15)
				)
				(justify mirror)
			)
		)
		(property "Manufacturer" "Murata"
			(at 0 0 90)
			(unlocked yes)
			(layer "B.Fab")
			(hide yes)
			(effects
				(font
					(size 1 1)
					(thickness 0.15)
				)
				(justify mirror)
			)
		)
		(property "License" "Apache-2.0"
			(at 0 0 90)
			(unlocked yes)
			(layer "B.Fab")
			(hide yes)
			(effects
				(font
					(size 1 1)
					(thickness 0.15)
				)
				(justify mirror)
			)
		)
		(property "Author" "Antmicro"
			(at 0 0 90)
			(unlocked yes)
			(layer "B.Fab")
			(hide yes)
			(effects
				(font
					(size 1 1)
					(thickness 0.15)
				)
				(justify mirror)
			)
		)
		(property "Val" "220u"
			(at 0 0 90)
			(unlocked yes)
			(layer "B.Fab")
			(hide yes)
			(effects
				(font
					(size 1 1)
					(thickness 0.15)
				)
				(justify mirror)
			)
		)
		(property "Voltage" ""
			(at 0 0 90)
			(unlocked yes)
			(layer "B.Fab")
			(hide yes)
			(effects
				(font
					(size 1 1)
					(thickness 0.15)
				)
				(justify mirror)
			)
		)
		(property "Dielectric" ""
			(at 0 0 90)
			(unlocked yes)
			(layer "B.Fab")
			(hide yes)
			(effects
				(font
					(size 1 1)
					(thickness 0.15)
				)
				(justify mirror)
			)
		)
		(property "Public" "False"
			(at 0 0 90)
			(unlocked yes)
			(layer "B.Fab")
			(hide yes)
			(effects
				(font
					(size 1 1)
					(thickness 0.15)
				)
				(justify mirror)
			)
		)
		(sheetname "/2xRJ45/")
		(sheetfile "2xrj45.kicad_sch")
		(attr smd)
		(fp_line
			(start 0.8 -0.901)
			(end -0.8 -0.901)
			(stroke
				(width 0.15)
				(type solid)
			)
			(layer "B.SilkS")
		)
		(fp_line
			(start 0.8 0.899)
			(end -0.8 0.899)
			(stroke
				(width 0.15)
				(type solid)
			)
			(layer "B.SilkS")
		)
		(fp_rect
			(start -2.325 1.15)
			(end 2.325 -1.15)
			(stroke
				(width 0.05)
				(type default)
			)
			(fill no)
			(layer "B.CrtYd")
		)
		(fp_rect
			(start -1.6 0.799)
			(end 1.6 -0.801)
			(stroke
				(width 0.15)
				(type solid)
			)
			(fill no)
			(layer "B.Fab")
		)
		(pad "1" smd roundrect
			(at -1.5 -0.001 90)
			(size 1.15 1.8)
			(layers "B.Cu" "B.Mask" "B.Paste")
			(roundrect_rratio 0.25)
			(net 28 "GND")
			(pintype "passive")
		)
		(pad "2" smd roundrect
			(at 1.5 -0.001 90)
			(size 1.15 1.8)
			(layers "B.Cu" "B.Mask" "B.Paste")
			(roundrect_rratio 0.25)
			(net 301 "+1V88_CT")
			(pintype "passive")
		)
	)
	(footprint "antmicro-footprints:TP_SMD_0.75mm"
		(layer "B.Cu")
		(at 93.725 107.355 180)
		(property "Reference" "TP25"
			(at -2.395 -1.365 0)
			(layer "B.SilkS")
			(effects
				(font
					(size 0.7 0.7)
					(thickness 0.15)
				)
				(justify left bottom mirror)
			)
		)
		(property "Value" "TP_0.75mm_SMD"
			(at 0 -1.2 0)
			(layer "B.Fab")
			(hide yes)
			(effects
				(font
					(size 0.7 0.7)
					(thickness 0.15)
				)
				(justify left bottom mirror)
			)
		)
		(property "Description" "SMT test point"
			(at 0 0 0)
			(layer "B.Fab")
			(hide yes)
			(effects
				(font
					(size 1.27 1.27)
					(thickness 0.15)
				)
				(justify mirror)
			)
		)
		(property "MPN" ""
			(at 0 0 180)
			(unlocked yes)
			(layer "B.Fab")
			(hide yes)
			(effects
				(font
					(size 1 1)
					(thickness 0.15)
				)
				(justify mirror)
			)
		)
		(property "Manufacturer" ""
			(at 0 0 180)
			(unlocked yes)
			(layer "B.Fab")
			(hide yes)
			(effects
				(font
					(size 1 1)
					(thickness 0.15)
				)
				(justify mirror)
			)
		)
		(property "Author" "Antmicro"
			(at 0 0 180)
			(unlocked yes)
			(layer "B.Fab")
			(hide yes)
			(effects
				(font
					(size 1 1)
					(thickness 0.15)
				)
				(justify mirror)
			)
		)
		(property "License" "Apache-2.0"
			(at 0 0 180)
			(unlocked yes)
			(layer "B.Fab")
			(hide yes)
			(effects
				(font
					(size 1 1)
					(thickness 0.15)
				)
				(justify mirror)
			)
		)
		(sheetname "/X710-AT2 Misc/")
		(sheetfile "x710-at2-mics.kicad_sch")
		(attr exclude_from_pos_files exclude_from_bom)
		(fp_circle
			(center 0 0)
			(end 0.475 0)
			(stroke
				(width 0.05)
				(type default)
			)
			(fill no)
			(layer "B.CrtYd")
		)
		(pad "1" smd circle
			(at 0 0 180)
			(size 0.75 0.75)
			(layers "B.Cu" "B.Mask")
			(net 383 "/X710-AT2 Misc/REFCLK_SEL")
			(pinfunction "1")
			(pintype "passive")
		)
	)
	(footprint "antmicro-footprints:R_0402_1005Metric"
		(layer "B.Cu")
		(at 96.45 102.1)
		(descr "Resistor SMD 0402")
		(tags "resistor SMD 0402")
		(property "Reference" "R60"
			(at 0.9 -0.305556 0)
			(layer "B.SilkS")
			(effects
				(font
					(size 0.7 0.7)
					(thickness 0.15)
				)
				(justify right top mirror)
			)
		)
		(property "Value" "R_3k3_0402"
			(at -1.011843 -1.772046 0)
			(layer "B.Fab")
			(hide yes)
			(effects
				(font
					(size 0.7 0.7)
					(thickness 0.15)
				)
				(justify right top mirror)
			)
		)
		(property "Datasheet" "https://www.bourns.com/docs/product-datasheets/cr.pdf"
			(at 0 0 0)
			(layer "B.Fab")
			(hide yes)
			(effects
				(font
					(size 1.27 1.27)
					(thickness 0.15)
				)
				(justify mirror)
			)
		)
		(property "Description" "SMD Chip Resistor, 3.3 kohm, ± 1%, 63 mW, 0402 [1005 Metric], Thick Film, General Purpose"
			(at 0 0 0)
			(layer "B.Fab")
			(hide yes)
			(effects
				(font
					(size 1.27 1.27)
					(thickness 0.15)
				)
				(justify mirror)
			)
		)
		(property "MPN" "CR0402-FX-3301GLF"
			(at 0 0 0)
			(unlocked yes)
			(layer "B.Fab")
			(hide yes)
			(effects
				(font
					(size 1 1)
					(thickness 0.15)
				)
				(justify mirror)
			)
		)
		(property "Manufacturer" "Bourns"
			(at 0 0 0)
			(unlocked yes)
			(layer "B.Fab")
			(hide yes)
			(effects
				(font
					(size 1 1)
					(thickness 0.15)
				)
				(justify mirror)
			)
		)
		(property "License" "Apache-2.0"
			(at 0 0 0)
			(unlocked yes)
			(layer "B.Fab")
			(hide yes)
			(effects
				(font
					(size 1 1)
					(thickness 0.15)
				)
				(justify mirror)
			)
		)
		(property "Author" "Antmicro"
			(at 0 0 0)
			(unlocked yes)
			(layer "B.Fab")
			(hide yes)
			(effects
				(font
					(size 1 1)
					(thickness 0.15)
				)
				(justify mirror)
			)
		)
		(property "Val" "3k3"
			(at 0 0 0)
			(unlocked yes)
			(layer "B.Fab")
			(hide yes)
			(effects
				(font
					(size 1 1)
					(thickness 0.15)
				)
				(justify mirror)
			)
		)
		(property "Tolerance" "1%"
			(at 0 0 0)
			(unlocked yes)
			(layer "B.Fab")
			(hide yes)
			(effects
				(font
					(size 1 1)
					(thickness 0.15)
				)
				(justify mirror)
			)
		)
		(sheetname "/X710-AT2 10GbE/")
		(sheetfile "x710-at2-10gbe.kicad_sch")
		(attr smd)
		(fp_rect
			(start -0.925 0.47)
			(end 0.925 -0.47)
			(stroke
				(width 0.05)
				(type default)
			)
			(fill no)
			(layer "B.CrtYd")
		)
		(fp_rect
			(start -0.5 0.25)
			(end 0.5 -0.25)
			(stroke
				(width 0.15)
				(type solid)
			)
			(fill no)
			(layer "B.Fab")
		)
		(pad "1" smd roundrect
			(at -0.48 0)
			(size 0.59 0.64)
			(layers "B.Cu" "B.Mask" "B.Paste")
			(roundrect_rratio 0.25)
			(net 95 "/X710-AT2 10GbE/MDIO3_SDA3")
			(pintype "passive")
		)
		(pad "2" smd roundrect
			(at 0.48 0)
			(size 0.59 0.64)
			(layers "B.Cu" "B.Mask" "B.Paste")
			(roundrect_rratio 0.25)
			(net 7 "+3V3")
			(pintype "passive")
		)
	)
	(footprint "antmicro-footprints:C_0402_1005Metric"
		(layer "B.Cu")
		(at 85.225 94.6 90)
		(descr "Capacitor SMD 0402")
		(tags "capacitor SMD 0402")
		(property "Reference" "C96"
			(at 12.5 -0.462343 90)
			(layer "B.SilkS")
			(effects
				(font
					(size 0.7 0.7)
					(thickness 0.15)
				)
				(justify right top mirror)
			)
		)
		(property "Value" "C_1u_25V_0402"
			(at -1.022927 -2.155213 90)
			(layer "B.Fab")
			(hide yes)
			(effects
				(font
					(size 0.7 0.7)
					(thickness 0.15)
				)
				(justify right top mirror)
			)
		)
		(property "Datasheet" "https://www.murata.com/products/productdetail?partno=GRM155R61E105KE11%23"
			(at 0 0 90)
			(layer "B.Fab")
			(hide yes)
			(effects
				(font
					(size 1.27 1.27)
					(thickness 0.15)
				)
				(justify mirror)
			)
		)
		(property "Description" "SMD Multilayer Ceramic Capacitor, 1 µF, 25 V, 0402 [1005 Metric], ± 10%, X5R, GRM Series"
			(at 0 0 90)
			(layer "B.Fab")
			(hide yes)
			(effects
				(font
					(size 1.27 1.27)
					(thickness 0.15)
				)
				(justify mirror)
			)
		)
		(property "MPN" "GRM155R61E105KE11J"
			(at 0 0 90)
			(unlocked yes)
			(layer "B.Fab")
			(hide yes)
			(effects
				(font
					(size 1 1)
					(thickness 0.15)
				)
				(justify mirror)
			)
		)
		(property "Manufacturer" "Murata"
			(at 0 0 90)
			(unlocked yes)
			(layer "B.Fab")
			(hide yes)
			(effects
				(font
					(size 1 1)
					(thickness 0.15)
				)
				(justify mirror)
			)
		)
		(property "License" "Apache-2.0"
			(at 0 0 90)
			(unlocked yes)
			(layer "B.Fab")
			(hide yes)
			(effects
				(font
					(size 1 1)
					(thickness 0.15)
				)
				(justify mirror)
			)
		)
		(property "Author" "Antmicro"
			(at 0 0 90)
			(unlocked yes)
			(layer "B.Fab")
			(hide yes)
			(effects
				(font
					(size 1 1)
					(thickness 0.15)
				)
				(justify mirror)
			)
		)
		(property "Val" "1u"
			(at 0 0 90)
			(unlocked yes)
			(layer "B.Fab")
			(hide yes)
			(effects
				(font
					(size 1 1)
					(thickness 0.15)
				)
				(justify mirror)
			)
		)
		(property "Voltage" "25V"
			(at 0 0 90)
			(unlocked yes)
			(layer "B.Fab")
			(hide yes)
			(effects
				(font
					(size 1 1)
					(thickness 0.15)
				)
				(justify mirror)
			)
		)
		(property "Dielectric" "X5R"
			(at 0 0 90)
			(unlocked yes)
			(layer "B.Fab")
			(hide yes)
			(effects
				(font
					(size 1 1)
					(thickness 0.15)
				)
				(justify mirror)
			)
		)
		(sheetname "/X710-AT2 power/")
		(sheetfile "x710-at2-power.kicad_sch")
		(attr smd)
		(fp_rect
			(start -0.925 0.47)
			(end 0.925 -0.47)
			(stroke
				(width 0.05)
				(type default)
			)
			(fill no)
			(layer "B.CrtYd")
		)
		(fp_line
			(start 0.504 -0.248)
			(end -0.494 -0.248)
			(stroke
				(width 0.15)
				(type solid)
			)
			(layer "B.Fab")
		)
		(fp_line
			(start -0.494 -0.248)
			(end -0.494 0.25)
			(stroke
				(width 0.15)
				(type solid)
			)
			(layer "B.Fab")
		)
		(fp_line
			(start 0.504 0.25)
			(end 0.504 -0.248)
			(stroke
				(width 0.15)
				(type solid)
			)
			(layer "B.Fab")
		)
		(fp_line
			(start -0.494 0.25)
			(end 0.504 0.25)
			(stroke
				(width 0.15)
				(type solid)
			)
			(layer "B.Fab")
		)
		(pad "1" smd roundrect
			(at -0.48 0 90)
			(size 0.59 0.64)
			(layers "B.Cu" "B.Mask" "B.Paste")
			(roundrect_rratio 0.25)
			(net 28 "GND")
			(pintype "passive")
		)
		(pad "2" smd roundrect
			(at 0.48 0 90)
			(size 0.59 0.64)
			(layers "B.Cu" "B.Mask" "B.Paste")
			(roundrect_rratio 0.25)
			(net 1 "VCCA")
			(pintype "passive")
		)
	)
	(footprint "antmicro-footprints:R_0402_1005Metric"
		(layer "B.Cu")
		(at 84.25 102 90)
		(descr "Resistor SMD 0402")
		(tags "resistor SMD 0402")
		(property "Reference" "R143"
			(at 9.09 -0.447343 90)
			(layer "B.SilkS")
			(effects
				(font
					(size 0.7 0.7)
					(thickness 0.15)
				)
				(justify right top mirror)
			)
		)
		(property "Value" "R_1k_0402"
			(at -1.011843 -1.772046 90)
			(layer "B.Fab")
			(hide yes)
			(effects
				(font
					(size 0.7 0.7)
					(thickness 0.15)
				)
				(justify right top mirror)
			)
		)
		(property "Datasheet" "https://www.bourns.com/docs/product-datasheets/cr.pdf"
			(at 0 0 90)
			(layer "B.Fab")
			(hide yes)
			(effects
				(font
					(size 1.27 1.27)
					(thickness 0.15)
				)
				(justify mirror)
			)
		)
		(property "Description" "SMD Chip Resistor, 1 kohm, ± 1%, 63 mW, 0402 [1005 Metric], Thick Film, General Purpose"
			(at 0 0 90)
			(layer "B.Fab")
			(hide yes)
			(effects
				(font
					(size 1.27 1.27)
					(thickness 0.15)
				)
				(justify mirror)
			)
		)
		(property "MPN" "CR0402-FX-1001GLF"
			(at 0 0 90)
			(unlocked yes)
			(layer "B.Fab")
			(hide yes)
			(effects
				(font
					(size 1 1)
					(thickness 0.15)
				)
				(justify mirror)
			)
		)
		(property "Manufacturer" "Bourns"
			(at 0 0 90)
			(unlocked yes)
			(layer "B.Fab")
			(hide yes)
			(effects
				(font
					(size 1 1)
					(thickness 0.15)
				)
				(justify mirror)
			)
		)
		(property "License" "Apache-2.0"
			(at 0 0 90)
			(unlocked yes)
			(layer "B.Fab")
			(hide yes)
			(effects
				(font
					(size 1 1)
					(thickness 0.15)
				)
				(justify mirror)
			)
		)
		(property "Author" "Antmicro"
			(at 0 0 90)
			(unlocked yes)
			(layer "B.Fab")
			(hide yes)
			(effects
				(font
					(size 1 1)
					(thickness 0.15)
				)
				(justify mirror)
			)
		)
		(property "Val" "1k"
			(at 0 0 90)
			(unlocked yes)
			(layer "B.Fab")
			(hide yes)
			(effects
				(font
					(size 1 1)
					(thickness 0.15)
				)
				(justify mirror)
			)
		)
		(property "Tolerance" "1%"
			(at 0 0 90)
			(unlocked yes)
			(layer "B.Fab")
			(hide yes)
			(effects
				(font
					(size 1 1)
					(thickness 0.15)
				)
				(justify mirror)
			)
		)
		(sheetname "/X710-AT2 RSVD/")
		(sheetfile "x710-at2-rsvd.kicad_sch")
		(attr smd)
		(fp_rect
			(start -0.925 0.47)
			(end 0.925 -0.47)
			(stroke
				(width 0.05)
				(type default)
			)
			(fill no)
			(layer "B.CrtYd")
		)
		(fp_rect
			(start -0.5 0.25)
			(end 0.5 -0.25)
			(stroke
				(width 0.15)
				(type solid)
			)
			(fill no)
			(layer "B.Fab")
		)
		(pad "1" smd roundrect
			(at -0.48 0 90)
			(size 0.59 0.64)
			(layers "B.Cu" "B.Mask" "B.Paste")
			(roundrect_rratio 0.25)
			(net 292 "/X710-AT2 RSVD/RSVDE19_1P88V")
			(pintype "passive")
		)
		(pad "2" smd roundrect
			(at 0.48 0 90)
			(size 0.59 0.64)
			(layers "B.Cu" "B.Mask" "B.Paste")
			(roundrect_rratio 0.25)
			(net 18 "+1V88")
			(pintype "passive")
		)
	)
	(footprint "antmicro-footprints:R_0402_1005Metric"
		(layer "B.Cu")
		(at 96.45 104.1 180)
		(descr "Resistor SMD 0402")
		(tags "resistor SMD 0402")
		(property "Reference" "R85"
			(at -0.9 0.283333 0)
			(layer "B.SilkS")
			(effects
				(font
					(size 0.7 0.7)
					(thickness 0.15)
				)
				(justify right top mirror)
			)
		)
		(property "Value" "R_22R_0402"
			(at -1.011843 -1.772047 0)
			(layer "B.Fab")
			(hide yes)
			(effects
				(font
					(size 0.7 0.7)
					(thickness 0.15)
				)
				(justify left bottom mirror)
			)
		)
		(property "Datasheet" "https://www.bourns.com/docs/product-datasheets/cr.pdf"
			(at 0 0 0)
			(layer "B.Fab")
			(hide yes)
			(effects
				(font
					(size 1.27 1.27)
					(thickness 0.15)
				)
				(justify mirror)
			)
		)
		(property "Description" "SMD Chip Resistor, 22 ohm, ± 1%, 62.5 mW, 0402 [1005 Metric], Thick Film, General Purpose"
			(at 0 0 0)
			(layer "B.Fab")
			(hide yes)
			(effects
				(font
					(size 1.27 1.27)
					(thickness 0.15)
				)
				(justify mirror)
			)
		)
		(property "MPN" "CR0402-FX-22R0GLF"
			(at 0 0 180)
			(unlocked yes)
			(layer "B.Fab")
			(hide yes)
			(effects
				(font
					(size 1 1)
					(thickness 0.15)
				)
				(justify mirror)
			)
		)
		(property "Manufacturer" "Bourns"
			(at 0 0 180)
			(unlocked yes)
			(layer "B.Fab")
			(hide yes)
			(effects
				(font
					(size 1 1)
					(thickness 0.15)
				)
				(justify mirror)
			)
		)
		(property "License" "Apache-2.0"
			(at 0 0 180)
			(unlocked yes)
			(layer "B.Fab")
			(hide yes)
			(effects
				(font
					(size 1 1)
					(thickness 0.15)
				)
				(justify mirror)
			)
		)
		(property "Author" "Antmicro"
			(at 0 0 180)
			(unlocked yes)
			(layer "B.Fab")
			(hide yes)
			(effects
				(font
					(size 1 1)
					(thickness 0.15)
				)
				(justify mirror)
			)
		)
		(property "Val" "22R"
			(at 0 0 180)
			(unlocked yes)
			(layer "B.Fab")
			(hide yes)
			(effects
				(font
					(size 1 1)
					(thickness 0.15)
				)
				(justify mirror)
			)
		)
		(property "Tolerance" "1%"
			(at 0 0 180)
			(unlocked yes)
			(layer "B.Fab")
			(hide yes)
			(effects
				(font
					(size 1 1)
					(thickness 0.15)
				)
				(justify mirror)
			)
		)
		(sheetname "/X710-AT2 Misc/")
		(sheetfile "x710-at2-mics.kicad_sch")
		(attr smd)
		(fp_rect
			(start -0.925 0.47)
			(end 0.925 -0.47)
			(stroke
				(width 0.05)
				(type default)
			)
			(fill no)
			(layer "B.CrtYd")
		)
		(fp_rect
			(start -0.5 0.25)
			(end 0.5 -0.25)
			(stroke
				(width 0.15)
				(type solid)
			)
			(fill no)
			(layer "B.Fab")
		)
		(pad "1" smd roundrect
			(at -0.48 0 180)
			(size 0.59 0.64)
			(layers "B.Cu" "B.Mask" "B.Paste")
			(roundrect_rratio 0.25)
			(net 362 "/X710-AT2 Misc/NCSI.RXD_0")
			(pintype "passive")
		)
		(pad "2" smd roundrect
			(at 0.48 0 180)
			(size 0.59 0.64)
			(layers "B.Cu" "B.Mask" "B.Paste")
			(roundrect_rratio 0.25)
			(net 161 "Net-(U9D-NCSI_RXD_0)")
			(pintype "passive")
		)
	)
	(footprint "antmicro-footprints:R_0402_1005Metric"
		(layer "B.Cu")
		(at 96.45 103.1)
		(descr "Resistor SMD 0402")
		(tags "resistor SMD 0402")
		(property "Reference" "R59"
			(at 0.9 -0.294444 0)
			(layer "B.SilkS")
			(effects
				(font
					(size 0.7 0.7)
					(thickness 0.15)
				)
				(justify right top mirror)
			)
		)
		(property "Value" "R_3k3_0402"
			(at -1.011843 -1.772046 0)
			(layer "B.Fab")
			(hide yes)
			(effects
				(font
					(size 0.7 0.7)
					(thickness 0.15)
				)
				(justify right top mirror)
			)
		)
		(property "Datasheet" "https://www.bourns.com/docs/product-datasheets/cr.pdf"
			(at 0 0 0)
			(layer "B.Fab")
			(hide yes)
			(effects
				(font
					(size 1.27 1.27)
					(thickness 0.15)
				)
				(justify mirror)
			)
		)
		(property "Description" "SMD Chip Resistor, 3.3 kohm, ± 1%, 63 mW, 0402 [1005 Metric], Thick Film, General Purpose"
			(at 0 0 0)
			(layer "B.Fab")
			(hide yes)
			(effects
				(font
					(size 1.27 1.27)
					(thickness 0.15)
				)
				(justify mirror)
			)
		)
		(property "MPN" "CR0402-FX-3301GLF"
			(at 0 0 0)
			(unlocked yes)
			(layer "B.Fab")
			(hide yes)
			(effects
				(font
					(size 1 1)
					(thickness 0.15)
				)
				(justify mirror)
			)
		)
		(property "Manufacturer" "Bourns"
			(at 0 0 0)
			(unlocked yes)
			(layer "B.Fab")
			(hide yes)
			(effects
				(font
					(size 1 1)
					(thickness 0.15)
				)
				(justify mirror)
			)
		)
		(property "License" "Apache-2.0"
			(at 0 0 0)
			(unlocked yes)
			(layer "B.Fab")
			(hide yes)
			(effects
				(font
					(size 1 1)
					(thickness 0.15)
				)
				(justify mirror)
			)
		)
		(property "Author" "Antmicro"
			(at 0 0 0)
			(unlocked yes)
			(layer "B.Fab")
			(hide yes)
			(effects
				(font
					(size 1 1)
					(thickness 0.15)
				)
				(justify mirror)
			)
		)
		(property "Val" "3k3"
			(at 0 0 0)
			(unlocked yes)
			(layer "B.Fab")
			(hide yes)
			(effects
				(font
					(size 1 1)
					(thickness 0.15)
				)
				(justify mirror)
			)
		)
		(property "Tolerance" "1%"
			(at 0 0 0)
			(unlocked yes)
			(layer "B.Fab")
			(hide yes)
			(effects
				(font
					(size 1 1)
					(thickness 0.15)
				)
				(justify mirror)
			)
		)
		(sheetname "/X710-AT2 10GbE/")
		(sheetfile "x710-at2-10gbe.kicad_sch")
		(attr smd)
		(fp_rect
			(start -0.925 0.47)
			(end 0.925 -0.47)
			(stroke
				(width 0.05)
				(type default)
			)
			(fill no)
			(layer "B.CrtYd")
		)
		(fp_rect
			(start -0.5 0.25)
			(end 0.5 -0.25)
			(stroke
				(width 0.15)
				(type solid)
			)
			(fill no)
			(layer "B.Fab")
		)
		(pad "1" smd roundrect
			(at -0.48 0)
			(size 0.59 0.64)
			(layers "B.Cu" "B.Mask" "B.Paste")
			(roundrect_rratio 0.25)
			(net 94 "/X710-AT2 10GbE/MDC3_SCL3")
			(pintype "passive")
		)
		(pad "2" smd roundrect
			(at 0.48 0)
			(size 0.59 0.64)
			(layers "B.Cu" "B.Mask" "B.Paste")
			(roundrect_rratio 0.25)
			(net 7 "+3V3")
			(pintype "passive")
		)
	)
	(footprint "antmicro-footprints:TP_SMD_1mm"
		(layer "B.Cu")
		(at 82.49 74.55 -90)
		(property "Reference" "TP32"
			(at -1.1 8.48 90)
			(layer "B.SilkS")
			(effects
				(font
					(size 0.7 0.7)
					(thickness 0.15)
				)
				(justify left bottom mirror)
			)
		)
		(property "Value" "TP_1mm_SMD"
			(at 0 -1.4 90)
			(layer "B.Fab")
			(hide yes)
			(effects
				(font
					(size 0.7 0.7)
					(thickness 0.15)
				)
				(justify left bottom mirror)
			)
		)
		(property "Description" "Test point 1mm SMD"
			(at 0 0 90)
			(layer "B.Fab")
			(hide yes)
			(effects
				(font
					(size 1.27 1.27)
					(thickness 0.15)
				)
				(justify mirror)
			)
		)
		(property "MPN" ""
			(at 0 0 90)
			(unlocked yes)
			(layer "B.Fab")
			(hide yes)
			(effects
				(font
					(size 1 1)
					(thickness 0.15)
				)
				(justify mirror)
			)
		)
		(property "Manufacturer" ""
			(at 0 0 90)
			(unlocked yes)
			(layer "B.Fab")
			(hide yes)
			(effects
				(font
					(size 1 1)
					(thickness 0.15)
				)
				(justify mirror)
			)
		)
		(property "Author" "Antmicro"
			(at 0 0 90)
			(unlocked yes)
			(layer "B.Fab")
			(hide yes)
			(effects
				(font
					(size 1 1)
					(thickness 0.15)
				)
				(justify mirror)
			)
		)
		(property "License" "Apache-2.0"
			(at 0 0 90)
			(unlocked yes)
			(layer "B.Fab")
			(hide yes)
			(effects
				(font
					(size 1 1)
					(thickness 0.15)
				)
				(justify mirror)
			)
		)
		(sheetname "/Power/")
		(sheetfile "power.kicad_sch")
		(attr exclude_from_pos_files exclude_from_bom)
		(fp_circle
			(center 0 0)
			(end 0.6 0)
			(stroke
				(width 0.05)
				(type default)
			)
			(fill no)
			(layer "B.CrtYd")
		)
		(pad "1" smd circle
			(at 0 0 270)
			(size 1 1)
			(layers "B.Cu" "B.Mask")
			(net 18 "+1V88")
			(pinfunction "1")
			(pintype "passive")
		)
	)
	(footprint "antmicro-footprints:TP_SMD_0.75mm"
		(layer "B.Cu")
		(at 102.05 108.7)
		(property "Reference" "TP9"
			(at -0.31 2.58 90)
			(layer "B.SilkS")
			(effects
				(font
					(size 0.7 0.7)
					(thickness 0.15)
				)
				(justify right top mirror)
			)
		)
		(property "Value" "TP_0.75mm_SMD"
			(at 0 -1.2 0)
			(layer "B.Fab")
			(hide yes)
			(effects
				(font
					(size 0.7 0.7)
					(thickness 0.15)
				)
				(justify right top mirror)
			)
		)
		(property "Description" "SMT test point"
			(at 0 0 0)
			(layer "B.Fab")
			(hide yes)
			(effects
				(font
					(size 1.27 1.27)
					(thickness 0.15)
				)
				(justify mirror)
			)
		)
		(property "MPN" ""
			(at 0 0 0)
			(unlocked yes)
			(layer "B.Fab")
			(hide yes)
			(effects
				(font
					(size 1 1)
					(thickness 0.15)
				)
				(justify mirror)
			)
		)
		(property "Manufacturer" ""
			(at 0 0 0)
			(unlocked yes)
			(layer "B.Fab")
			(hide yes)
			(effects
				(font
					(size 1 1)
					(thickness 0.15)
				)
				(justify mirror)
			)
		)
		(property "Author" "Antmicro"
			(at 0 0 0)
			(unlocked yes)
			(layer "B.Fab")
			(hide yes)
			(effects
				(font
					(size 1 1)
					(thickness 0.15)
				)
				(justify mirror)
			)
		)
		(property "License" "Apache-2.0"
			(at 0 0 0)
			(unlocked yes)
			(layer "B.Fab")
			(hide yes)
			(effects
				(font
					(size 1 1)
					(thickness 0.15)
				)
				(justify mirror)
			)
		)
		(sheetname "/X710-AT2 Misc/")
		(sheetfile "x710-at2-mics.kicad_sch")
		(attr exclude_from_pos_files exclude_from_bom)
		(fp_circle
			(center 0 0)
			(end 0.475 0)
			(stroke
				(width 0.05)
				(type default)
			)
			(fill no)
			(layer "B.CrtYd")
		)
		(pad "1" smd circle
			(at 0 0)
			(size 0.75 0.75)
			(layers "B.Cu" "B.Mask")
			(net 360 "/X710-AT2 Misc/NCSI.RXD_1")
			(pinfunction "1")
			(pintype "passive")
		)
	)
	(footprint "antmicro-footprints:C_0402_1005Metric"
		(layer "B.Cu")
		(at 92.25 102 90)
		(descr "Capacitor SMD 0402")
		(tags "capacitor SMD 0402")
		(property "Reference" "C136"
			(at 9.09 -0.447343 90)
			(layer "B.SilkS")
			(effects
				(font
					(size 0.7 0.7)
					(thickness 0.15)
				)
				(justify right top mirror)
			)
		)
		(property "Value" "C_1u_25V_0402"
			(at -1.022927 -2.155213 90)
			(layer "B.Fab")
			(hide yes)
			(effects
				(font
					(size 0.7 0.7)
					(thickness 0.15)
				)
				(justify right top mirror)
			)
		)
		(property "Datasheet" "https://www.murata.com/products/productdetail?partno=GRM155R61E105KE11%23"
			(at 0 0 90)
			(layer "B.Fab")
			(hide yes)
			(effects
				(font
					(size 1.27 1.27)
					(thickness 0.15)
				)
				(justify mirror)
			)
		)
		(property "Description" "SMD Multilayer Ceramic Capacitor, 1 µF, 25 V, 0402 [1005 Metric], ± 10%, X5R, GRM Series"
			(at 0 0 90)
			(layer "B.Fab")
			(hide yes)
			(effects
				(font
					(size 1.27 1.27)
					(thickness 0.15)
				)
				(justify mirror)
			)
		)
		(property "MPN" "GRM155R61E105KE11J"
			(at 0 0 90)
			(unlocked yes)
			(layer "B.Fab")
			(hide yes)
			(effects
				(font
					(size 1 1)
					(thickness 0.15)
				)
				(justify mirror)
			)
		)
		(property "Manufacturer" "Murata"
			(at 0 0 90)
			(unlocked yes)
			(layer "B.Fab")
			(hide yes)
			(effects
				(font
					(size 1 1)
					(thickness 0.15)
				)
				(justify mirror)
			)
		)
		(property "License" "Apache-2.0"
			(at 0 0 90)
			(unlocked yes)
			(layer "B.Fab")
			(hide yes)
			(effects
				(font
					(size 1 1)
					(thickness 0.15)
				)
				(justify mirror)
			)
		)
		(property "Author" "Antmicro"
			(at 0 0 90)
			(unlocked yes)
			(layer "B.Fab")
			(hide yes)
			(effects
				(font
					(size 1 1)
					(thickness 0.15)
				)
				(justify mirror)
			)
		)
		(property "Val" "1u"
			(at 0 0 90)
			(unlocked yes)
			(layer "B.Fab")
			(hide yes)
			(effects
				(font
					(size 1 1)
					(thickness 0.15)
				)
				(justify mirror)
			)
		)
		(property "Voltage" "25V"
			(at 0 0 90)
			(unlocked yes)
			(layer "B.Fab")
			(hide yes)
			(effects
				(font
					(size 1 1)
					(thickness 0.15)
				)
				(justify mirror)
			)
		)
		(property "Dielectric" "X5R"
			(at 0 0 90)
			(unlocked yes)
			(layer "B.Fab")
			(hide yes)
			(effects
				(font
					(size 1 1)
					(thickness 0.15)
				)
				(justify mirror)
			)
		)
		(sheetname "/X710-AT2 power/")
		(sheetfile "x710-at2-power.kicad_sch")
		(attr smd)
		(fp_rect
			(start -0.925 0.47)
			(end 0.925 -0.47)
			(stroke
				(width 0.05)
				(type default)
			)
			(fill no)
			(layer "B.CrtYd")
		)
		(fp_line
			(start 0.504 -0.248)
			(end -0.494 -0.248)
			(stroke
				(width 0.15)
				(type solid)
			)
			(layer "B.Fab")
		)
		(fp_line
			(start -0.494 -0.248)
			(end -0.494 0.25)
			(stroke
				(width 0.15)
				(type solid)
			)
			(layer "B.Fab")
		)
		(fp_line
			(start 0.504 0.25)
			(end 0.504 -0.248)
			(stroke
				(width 0.15)
				(type solid)
			)
			(layer "B.Fab")
		)
		(fp_line
			(start -0.494 0.25)
			(end 0.504 0.25)
			(stroke
				(width 0.15)
				(type solid)
			)
			(layer "B.Fab")
		)
		(pad "1" smd roundrect
			(at -0.48 0 90)
			(size 0.59 0.64)
			(layers "B.Cu" "B.Mask" "B.Paste")
			(roundrect_rratio 0.25)
			(net 28 "GND")
			(pintype "passive")
		)
		(pad "2" smd roundrect
			(at 0.48 0 90)
			(size 0.59 0.64)
			(layers "B.Cu" "B.Mask" "B.Paste")
			(roundrect_rratio 0.25)
			(net 7 "+3V3")
			(pintype "passive")
		)
	)
	(footprint "antmicro-footprints:R_0402_1005Metric"
		(layer "B.Cu")
		(at 99.16 90.164 180)
		(descr "Resistor SMD 0402")
		(tags "resistor SMD 0402")
		(property "Reference" "R120"
			(at 0.85 -0.456 0)
			(layer "B.SilkS")
			(effects
				(font
					(size 0.7 0.7)
					(thickness 0.15)
				)
				(justify left bottom mirror)
			)
		)
		(property "Value" "R_0R_0402"
			(at -1.011843 -1.772047 0)
			(layer "B.Fab")
			(hide yes)
			(effects
				(font
					(size 0.7 0.7)
					(thickness 0.15)
				)
				(justify left bottom mirror)
			)
		)
		(property "Datasheet" "https://industrial.panasonic.com/cdbs/www-data/pdf/RDA0000/AOA0000C301.pdf"
			(at 0 0 0)
			(layer "B.Fab")
			(hide yes)
			(effects
				(font
					(size 1.27 1.27)
					(thickness 0.15)
				)
				(justify mirror)
			)
		)
		(property "Description" "SMD Chip Resistor, Jumper, 0 ohm, 100 mW, 0402 [1005 Metric], Thick Film, General Purpose"
			(at 0 0 0)
			(layer "B.Fab")
			(hide yes)
			(effects
				(font
					(size 1.27 1.27)
					(thickness 0.15)
				)
				(justify mirror)
			)
		)
		(property "MPN" "ERJ2GE0R00X"
			(at 0 0 0)
			(unlocked yes)
			(layer "B.Fab")
			(hide yes)
			(effects
				(font
					(size 1 1)
					(thickness 0.15)
				)
				(justify mirror)
			)
		)
		(property "Manufacturer" "Panasonic"
			(at 0 0 0)
			(unlocked yes)
			(layer "B.Fab")
			(hide yes)
			(effects
				(font
					(size 1 1)
					(thickness 0.15)
				)
				(justify mirror)
			)
		)
		(property "License" "Apache-2.0"
			(at 0 0 0)
			(unlocked yes)
			(layer "B.Fab")
			(hide yes)
			(effects
				(font
					(size 1 1)
					(thickness 0.15)
				)
				(justify mirror)
			)
		)
		(property "Author" "Antmicro"
			(at 0 0 0)
			(unlocked yes)
			(layer "B.Fab")
			(hide yes)
			(effects
				(font
					(size 1 1)
					(thickness 0.15)
				)
				(justify mirror)
			)
		)
		(property "Val" "0R"
			(at 0 0 0)
			(unlocked yes)
			(layer "B.Fab")
			(hide yes)
			(effects
				(font
					(size 1 1)
					(thickness 0.15)
				)
				(justify mirror)
			)
		)
		(property "Tolerance" "~"
			(at 0 0 0)
			(unlocked yes)
			(layer "B.Fab")
			(hide yes)
			(effects
				(font
					(size 1 1)
					(thickness 0.15)
				)
				(justify mirror)
			)
		)
		(property "Current" "1A"
			(at 0 0 0)
			(unlocked yes)
			(layer "B.Fab")
			(hide yes)
			(effects
				(font
					(size 1 1)
					(thickness 0.15)
				)
				(justify mirror)
			)
		)
		(sheetname "/X710-AT2 PCIe/")
		(sheetfile "x710-at2-pcie.kicad_sch")
		(attr smd exclude_from_pos_files exclude_from_bom dnp)
		(fp_rect
			(start -0.925 0.47)
			(end 0.925 -0.47)
			(stroke
				(width 0.05)
				(type default)
			)
			(fill no)
			(layer "B.CrtYd")
		)
		(fp_rect
			(start -0.5 0.25)
			(end 0.5 -0.25)
			(stroke
				(width 0.15)
				(type solid)
			)
			(fill no)
			(layer "B.Fab")
		)
		(pad "1" smd roundrect
			(at -0.48 0 180)
			(size 0.59 0.64)
			(layers "B.Cu" "B.Mask" "B.Paste")
			(roundrect_rratio 0.25)
			(net 405 "/X710-AT2 PCIe/GEN_F_CLK+")
			(pintype "passive")
		)
		(pad "2" smd roundrect
			(at 0.48 0 180)
			(size 0.59 0.64)
			(layers "B.Cu" "B.Mask" "B.Paste")
			(roundrect_rratio 0.25)
			(net 402 "/X710-AT2 PCIe/CLK+")
			(pintype "passive")
		)
	)
	(footprint "antmicro-footprints:C_0402_1005Metric"
		(layer "B.Cu")
		(at 85.225 102 90)
		(descr "Capacitor SMD 0402")
		(tags "capacitor SMD 0402")
		(property "Reference" "C120"
			(at 9.09 -0.447343 90)
			(layer "B.SilkS")
			(effects
				(font
					(size 0.7 0.7)
					(thickness 0.15)
				)
				(justify right top mirror)
			)
		)
		(property "Value" "C_1u_25V_0402"
			(at -1.022927 -2.155213 90)
			(layer "B.Fab")
			(hide yes)
			(effects
				(font
					(size 0.7 0.7)
					(thickness 0.15)
				)
				(justify right top mirror)
			)
		)
		(property "Datasheet" "https://www.murata.com/products/productdetail?partno=GRM155R61E105KE11%23"
			(at 0 0 90)
			(layer "B.Fab")
			(hide yes)
			(effects
				(font
					(size 1.27 1.27)
					(thickness 0.15)
				)
				(justify mirror)
			)
		)
		(property "Description" "SMD Multilayer Ceramic Capacitor, 1 µF, 25 V, 0402 [1005 Metric], ± 10%, X5R, GRM Series"
			(at 0 0 90)
			(layer "B.Fab")
			(hide yes)
			(effects
				(font
					(size 1.27 1.27)
					(thickness 0.15)
				)
				(justify mirror)
			)
		)
		(property "MPN" "GRM155R61E105KE11J"
			(at 0 0 90)
			(unlocked yes)
			(layer "B.Fab")
			(hide yes)
			(effects
				(font
					(size 1 1)
					(thickness 0.15)
				)
				(justify mirror)
			)
		)
		(property "Manufacturer" "Murata"
			(at 0 0 90)
			(unlocked yes)
			(layer "B.Fab")
			(hide yes)
			(effects
				(font
					(size 1 1)
					(thickness 0.15)
				)
				(justify mirror)
			)
		)
		(property "License" "Apache-2.0"
			(at 0 0 90)
			(unlocked yes)
			(layer "B.Fab")
			(hide yes)
			(effects
				(font
					(size 1 1)
					(thickness 0.15)
				)
				(justify mirror)
			)
		)
		(property "Author" "Antmicro"
			(at 0 0 90)
			(unlocked yes)
			(layer "B.Fab")
			(hide yes)
			(effects
				(font
					(size 1 1)
					(thickness 0.15)
				)
				(justify mirror)
			)
		)
		(property "Val" "1u"
			(at 0 0 90)
			(unlocked yes)
			(layer "B.Fab")
			(hide yes)
			(effects
				(font
					(size 1 1)
					(thickness 0.15)
				)
				(justify mirror)
			)
		)
		(property "Voltage" "25V"
			(at 0 0 90)
			(unlocked yes)
			(layer "B.Fab")
			(hide yes)
			(effects
				(font
					(size 1 1)
					(thickness 0.15)
				)
				(justify mirror)
			)
		)
		(property "Dielectric" "X5R"
			(at 0 0 90)
			(unlocked yes)
			(layer "B.Fab")
			(hide yes)
			(effects
				(font
					(size 1 1)
					(thickness 0.15)
				)
				(justify mirror)
			)
		)
		(sheetname "/X710-AT2 power/")
		(sheetfile "x710-at2-power.kicad_sch")
		(attr smd)
		(fp_rect
			(start -0.925 0.47)
			(end 0.925 -0.47)
			(stroke
				(width 0.05)
				(type default)
			)
			(fill no)
			(layer "B.CrtYd")
		)
		(fp_line
			(start 0.504 -0.248)
			(end -0.494 -0.248)
			(stroke
				(width 0.15)
				(type solid)
			)
			(layer "B.Fab")
		)
		(fp_line
			(start -0.494 -0.248)
			(end -0.494 0.25)
			(stroke
				(width 0.15)
				(type solid)
			)
			(layer "B.Fab")
		)
		(fp_line
			(start 0.504 0.25)
			(end 0.504 -0.248)
			(stroke
				(width 0.15)
				(type solid)
			)
			(layer "B.Fab")
		)
		(fp_line
			(start -0.494 0.25)
			(end 0.504 0.25)
			(stroke
				(width 0.15)
				(type solid)
			)
			(layer "B.Fab")
		)
		(pad "1" smd roundrect
			(at -0.48 0 90)
			(size 0.59 0.64)
			(layers "B.Cu" "B.Mask" "B.Paste")
			(roundrect_rratio 0.25)
			(net 28 "GND")
			(pintype "passive")
		)
		(pad "2" smd roundrect
			(at 0.48 0 90)
			(size 0.59 0.64)
			(layers "B.Cu" "B.Mask" "B.Paste")
			(roundrect_rratio 0.25)
			(net 9 "VCCD")
			(pintype "passive")
		)
	)
	(footprint "antmicro-footprints:C_0402_1005Metric"
		(layer "B.Cu")
		(at 89.225 96.45 90)
		(descr "Capacitor SMD 0402")
		(tags "capacitor SMD 0402")
		(property "Reference" "C108"
			(at 11.58 -0.432343 90)
			(layer "B.SilkS")
			(effects
				(font
					(size 0.7 0.7)
					(thickness 0.15)
				)
				(justify right top mirror)
			)
		)
		(property "Value" "C_1u_25V_0402"
			(at -1.022927 -2.155213 90)
			(layer "B.Fab")
			(hide yes)
			(effects
				(font
					(size 0.7 0.7)
					(thickness 0.15)
				)
				(justify right top mirror)
			)
		)
		(property "Datasheet" "https://www.murata.com/products/productdetail?partno=GRM155R61E105KE11%23"
			(at 0 0 90)
			(layer "B.Fab")
			(hide yes)
			(effects
				(font
					(size 1.27 1.27)
					(thickness 0.15)
				)
				(justify mirror)
			)
		)
		(property "Description" "SMD Multilayer Ceramic Capacitor, 1 µF, 25 V, 0402 [1005 Metric], ± 10%, X5R, GRM Series"
			(at 0 0 90)
			(layer "B.Fab")
			(hide yes)
			(effects
				(font
					(size 1.27 1.27)
					(thickness 0.15)
				)
				(justify mirror)
			)
		)
		(property "MPN" "GRM155R61E105KE11J"
			(at 0 0 90)
			(unlocked yes)
			(layer "B.Fab")
			(hide yes)
			(effects
				(font
					(size 1 1)
					(thickness 0.15)
				)
				(justify mirror)
			)
		)
		(property "Manufacturer" "Murata"
			(at 0 0 90)
			(unlocked yes)
			(layer "B.Fab")
			(hide yes)
			(effects
				(font
					(size 1 1)
					(thickness 0.15)
				)
				(justify mirror)
			)
		)
		(property "License" "Apache-2.0"
			(at 0 0 90)
			(unlocked yes)
			(layer "B.Fab")
			(hide yes)
			(effects
				(font
					(size 1 1)
					(thickness 0.15)
				)
				(justify mirror)
			)
		)
		(property "Author" "Antmicro"
			(at 0 0 90)
			(unlocked yes)
			(layer "B.Fab")
			(hide yes)
			(effects
				(font
					(size 1 1)
					(thickness 0.15)
				)
				(justify mirror)
			)
		)
		(property "Val" "1u"
			(at 0 0 90)
			(unlocked yes)
			(layer "B.Fab")
			(hide yes)
			(effects
				(font
					(size 1 1)
					(thickness 0.15)
				)
				(justify mirror)
			)
		)
		(property "Voltage" "25V"
			(at 0 0 90)
			(unlocked yes)
			(layer "B.Fab")
			(hide yes)
			(effects
				(font
					(size 1 1)
					(thickness 0.15)
				)
				(justify mirror)
			)
		)
		(property "Dielectric" "X5R"
			(at 0 0 90)
			(unlocked yes)
			(layer "B.Fab")
			(hide yes)
			(effects
				(font
					(size 1 1)
					(thickness 0.15)
				)
				(justify mirror)
			)
		)
		(sheetname "/X710-AT2 power/")
		(sheetfile "x710-at2-power.kicad_sch")
		(attr smd)
		(fp_rect
			(start -0.925 0.47)
			(end 0.925 -0.47)
			(stroke
				(width 0.05)
				(type default)
			)
			(fill no)
			(layer "B.CrtYd")
		)
		(fp_line
			(start 0.504 -0.248)
			(end -0.494 -0.248)
			(stroke
				(width 0.15)
				(type solid)
			)
			(layer "B.Fab")
		)
		(fp_line
			(start -0.494 -0.248)
			(end -0.494 0.25)
			(stroke
				(width 0.15)
				(type solid)
			)
			(layer "B.Fab")
		)
		(fp_line
			(start 0.504 0.25)
			(end 0.504 -0.248)
			(stroke
				(width 0.15)
				(type solid)
			)
			(layer "B.Fab")
		)
		(fp_line
			(start -0.494 0.25)
			(end 0.504 0.25)
			(stroke
				(width 0.15)
				(type solid)
			)
			(layer "B.Fab")
		)
		(pad "1" smd roundrect
			(at -0.48 0 90)
			(size 0.59 0.64)
			(layers "B.Cu" "B.Mask" "B.Paste")
			(roundrect_rratio 0.25)
			(net 28 "GND")
			(pintype "passive")
		)
		(pad "2" smd roundrect
			(at 0.48 0 90)
			(size 0.59 0.64)
			(layers "B.Cu" "B.Mask" "B.Paste")
			(roundrect_rratio 0.25)
			(net 9 "VCCD")
			(pintype "passive")
		)
	)
	(footprint "antmicro-footprints:TP_SMD_0.75mm"
		(layer "B.Cu")
		(at 99.049999 108.7)
		(property "Reference" "TP2"
			(at -0.259999 2.53 90)
			(layer "B.SilkS")
			(effects
				(font
					(size 0.7 0.7)
					(thickness 0.15)
				)
				(justify right top mirror)
			)
		)
		(property "Value" "TP_0.75mm_SMD"
			(at 0 -1.2 0)
			(layer "B.Fab")
			(hide yes)
			(effects
				(font
					(size 0.7 0.7)
					(thickness 0.15)
				)
				(justify right top mirror)
			)
		)
		(property "Description" "SMT test point"
			(at 0 0 0)
			(layer "B.Fab")
			(hide yes)
			(effects
				(font
					(size 1.27 1.27)
					(thickness 0.15)
				)
				(justify mirror)
			)
		)
		(property "MPN" ""
			(at 0 0 0)
			(unlocked yes)
			(layer "B.Fab")
			(hide yes)
			(effects
				(font
					(size 1 1)
					(thickness 0.15)
				)
				(justify mirror)
			)
		)
		(property "Manufacturer" ""
			(at 0 0 0)
			(unlocked yes)
			(layer "B.Fab")
			(hide yes)
			(effects
				(font
					(size 1 1)
					(thickness 0.15)
				)
				(justify mirror)
			)
		)
		(property "Author" "Antmicro"
			(at 0 0 0)
			(unlocked yes)
			(layer "B.Fab")
			(hide yes)
			(effects
				(font
					(size 1 1)
					(thickness 0.15)
				)
				(justify mirror)
			)
		)
		(property "License" "Apache-2.0"
			(at 0 0 0)
			(unlocked yes)
			(layer "B.Fab")
			(hide yes)
			(effects
				(font
					(size 1 1)
					(thickness 0.15)
				)
				(justify mirror)
			)
		)
		(sheetname "/X710-AT2 Misc/")
		(sheetfile "x710-at2-mics.kicad_sch")
		(attr exclude_from_pos_files exclude_from_bom)
		(fp_circle
			(center 0 0)
			(end 0.475 0)
			(stroke
				(width 0.05)
				(type default)
			)
			(fill no)
			(layer "B.CrtYd")
		)
		(pad "1" smd circle
			(at 0 0)
			(size 0.75 0.75)
			(layers "B.Cu" "B.Mask")
			(net 364 "/X710-AT2 Misc/NCSI.ARB_OUT")
			(pinfunction "1")
			(pintype "passive")
		)
	)
	(footprint "antmicro-footprints:R_0402_1005Metric"
		(layer "B.Cu")
		(at 96.88 109.95)
		(descr "Resistor SMD 0402")
		(tags "resistor SMD 0402")
		(property "Reference" "R71"
			(at -2.96 -0.25 0)
			(layer "B.SilkS")
			(effects
				(font
					(size 0.7 0.7)
					(thickness 0.15)
				)
				(justify right top mirror)
			)
		)
		(property "Value" "R_0R_0402"
			(at -1.011843 -1.772046 0)
			(layer "B.Fab")
			(hide yes)
			(effects
				(font
					(size 0.7 0.7)
					(thickness 0.15)
				)
				(justify right top mirror)
			)
		)
		(property "Datasheet" "https://industrial.panasonic.com/cdbs/www-data/pdf/RDA0000/AOA0000C301.pdf"
			(at 0 0 0)
			(layer "B.Fab")
			(hide yes)
			(effects
				(font
					(size 1.27 1.27)
					(thickness 0.15)
				)
				(justify mirror)
			)
		)
		(property "Description" "SMD Chip Resistor, Jumper, 0 ohm, 100 mW, 0402 [1005 Metric], Thick Film, General Purpose"
			(at 0 0 0)
			(layer "B.Fab")
			(hide yes)
			(effects
				(font
					(size 1.27 1.27)
					(thickness 0.15)
				)
				(justify mirror)
			)
		)
		(property "MPN" "ERJ2GE0R00X"
			(at 0 0 0)
			(unlocked yes)
			(layer "B.Fab")
			(hide yes)
			(effects
				(font
					(size 1 1)
					(thickness 0.15)
				)
				(justify mirror)
			)
		)
		(property "Manufacturer" "Panasonic"
			(at 0 0 0)
			(unlocked yes)
			(layer "B.Fab")
			(hide yes)
			(effects
				(font
					(size 1 1)
					(thickness 0.15)
				)
				(justify mirror)
			)
		)
		(property "License" "Apache-2.0"
			(at 0 0 0)
			(unlocked yes)
			(layer "B.Fab")
			(hide yes)
			(effects
				(font
					(size 1 1)
					(thickness 0.15)
				)
				(justify mirror)
			)
		)
		(property "Author" "Antmicro"
			(at 0 0 0)
			(unlocked yes)
			(layer "B.Fab")
			(hide yes)
			(effects
				(font
					(size 1 1)
					(thickness 0.15)
				)
				(justify mirror)
			)
		)
		(property "Val" "0R"
			(at 0 0 0)
			(unlocked yes)
			(layer "B.Fab")
			(hide yes)
			(effects
				(font
					(size 1 1)
					(thickness 0.15)
				)
				(justify mirror)
			)
		)
		(property "Tolerance" "~"
			(at 0 0 0)
			(unlocked yes)
			(layer "B.Fab")
			(hide yes)
			(effects
				(font
					(size 1 1)
					(thickness 0.15)
				)
				(justify mirror)
			)
		)
		(property "Current" "1A"
			(at 0 0 0)
			(unlocked yes)
			(layer "B.Fab")
			(hide yes)
			(effects
				(font
					(size 1 1)
					(thickness 0.15)
				)
				(justify mirror)
			)
		)
		(sheetname "/X710-AT2 10GbE/")
		(sheetfile "x710-at2-10gbe.kicad_sch")
		(attr smd)
		(fp_rect
			(start -0.925 0.47)
			(end 0.925 -0.47)
			(stroke
				(width 0.05)
				(type default)
			)
			(fill no)
			(layer "B.CrtYd")
		)
		(fp_rect
			(start -0.5 0.25)
			(end 0.5 -0.25)
			(stroke
				(width 0.15)
				(type solid)
			)
			(fill no)
			(layer "B.Fab")
		)
		(pad "1" smd roundrect
			(at -0.48 0)
			(size 0.59 0.64)
			(layers "B.Cu" "B.Mask" "B.Paste")
			(roundrect_rratio 0.25)
			(net 287 "/X710-AT2 10GbE/~{P1_INT}")
			(pintype "passive")
		)
		(pad "2" smd roundrect
			(at 0.48 0)
			(size 0.59 0.64)
			(layers "B.Cu" "B.Mask" "B.Paste")
			(roundrect_rratio 0.25)
			(net 286 "/X710-AT2 10GbE/~{P1_INT_R}")
			(pintype "passive")
		)
	)
	(footprint "antmicro-footprints:C_0402_1005Metric"
		(layer "B.Cu")
		(at 74 98.65)
		(descr "Capacitor SMD 0402")
		(tags "capacitor SMD 0402")
		(property "Reference" "C211"
			(at -0.85 0.45 0)
			(layer "B.SilkS")
			(effects
				(font
					(size 0.7 0.7)
					(thickness 0.15)
				)
				(justify left bottom mirror)
			)
		)
		(property "Value" "C_1u_25V_0402"
			(at -1.022927 -2.155213 0)
			(layer "B.Fab")
			(hide yes)
			(effects
				(font
					(size 0.7 0.7)
					(thickness 0.15)
				)
				(justify right top mirror)
			)
		)
		(property "Datasheet" "https://www.murata.com/products/productdetail?partno=GRM155R61E105KE11%23"
			(at 0 0 0)
			(layer "B.Fab")
			(hide yes)
			(effects
				(font
					(size 1.27 1.27)
					(thickness 0.15)
				)
				(justify mirror)
			)
		)
		(property "Description" "SMD Multilayer Ceramic Capacitor, 1 µF, 25 V, 0402 [1005 Metric], ± 10%, X5R, GRM Series"
			(at 0 0 0)
			(layer "B.Fab")
			(hide yes)
			(effects
				(font
					(size 1.27 1.27)
					(thickness 0.15)
				)
				(justify mirror)
			)
		)
		(property "MPN" "GRM155R61E105KE11J"
			(at 0 0 0)
			(unlocked yes)
			(layer "B.Fab")
			(hide yes)
			(effects
				(font
					(size 1 1)
					(thickness 0.15)
				)
				(justify mirror)
			)
		)
		(property "Manufacturer" "Murata"
			(at 0 0 0)
			(unlocked yes)
			(layer "B.Fab")
			(hide yes)
			(effects
				(font
					(size 1 1)
					(thickness 0.15)
				)
				(justify mirror)
			)
		)
		(property "License" "Apache-2.0"
			(at 0 0 0)
			(unlocked yes)
			(layer "B.Fab")
			(hide yes)
			(effects
				(font
					(size 1 1)
					(thickness 0.15)
				)
				(justify mirror)
			)
		)
		(property "Author" "Antmicro"
			(at 0 0 0)
			(unlocked yes)
			(layer "B.Fab")
			(hide yes)
			(effects
				(font
					(size 1 1)
					(thickness 0.15)
				)
				(justify mirror)
			)
		)
		(property "Val" "1u"
			(at 0 0 0)
			(unlocked yes)
			(layer "B.Fab")
			(hide yes)
			(effects
				(font
					(size 1 1)
					(thickness 0.15)
				)
				(justify mirror)
			)
		)
		(property "Voltage" "25V"
			(at 0 0 0)
			(unlocked yes)
			(layer "B.Fab")
			(hide yes)
			(effects
				(font
					(size 1 1)
					(thickness 0.15)
				)
				(justify mirror)
			)
		)
		(property "Dielectric" "X5R"
			(at 0 0 0)
			(unlocked yes)
			(layer "B.Fab")
			(hide yes)
			(effects
				(font
					(size 1 1)
					(thickness 0.15)
				)
				(justify mirror)
			)
		)
		(sheetname "/X710-AT2 Misc/")
		(sheetfile "x710-at2-mics.kicad_sch")
		(attr smd)
		(fp_rect
			(start -0.925 0.47)
			(end 0.925 -0.47)
			(stroke
				(width 0.05)
				(type default)
			)
			(fill no)
			(layer "B.CrtYd")
		)
		(fp_line
			(start -0.494 -0.248)
			(end -0.494 0.25)
			(stroke
				(width 0.15)
				(type solid)
			)
			(layer "B.Fab")
		)
		(fp_line
			(start -0.494 0.25)
			(end 0.504 0.25)
			(stroke
				(width 0.15)
				(type solid)
			)
			(layer "B.Fab")
		)
		(fp_line
			(start 0.504 -0.248)
			(end -0.494 -0.248)
			(stroke
				(width 0.15)
				(type solid)
			)
			(layer "B.Fab")
		)
		(fp_line
			(start 0.504 0.25)
			(end 0.504 -0.248)
			(stroke
				(width 0.15)
				(type solid)
			)
			(layer "B.Fab")
		)
		(pad "1" smd roundrect
			(at -0.48 0)
			(size 0.59 0.64)
			(layers "B.Cu" "B.Mask" "B.Paste")
			(roundrect_rratio 0.25)
			(net 28 "GND")
			(pintype "passive")
		)
		(pad "2" smd roundrect
			(at 0.48 0)
			(size 0.59 0.64)
			(layers "B.Cu" "B.Mask" "B.Paste")
			(roundrect_rratio 0.25)
			(net 47 "/X710-AT2 Misc/POR_BYPASS")
			(pintype "passive")
		)
	)
	(footprint "antmicro-footprints:R_0402_1005Metric"
		(layer "B.Cu")
		(at 82.225 94.6 90)
		(descr "Resistor SMD 0402")
		(tags "resistor SMD 0402")
		(property "Reference" "R140"
			(at 12.5 -0.462343 90)
			(layer "B.SilkS")
			(effects
				(font
					(size 0.7 0.7)
					(thickness 0.15)
				)
				(justify right top mirror)
			)
		)
		(property "Value" "R_100R_0402"
			(at -1.011843 -1.772046 90)
			(layer "B.Fab")
			(hide yes)
			(effects
				(font
					(size 0.7 0.7)
					(thickness 0.15)
				)
				(justify right top mirror)
			)
		)
		(property "Datasheet" "https://www.bourns.com/docs/product-datasheets/cr.pdf"
			(at 0 0 90)
			(layer "B.Fab")
			(hide yes)
			(effects
				(font
					(size 1.27 1.27)
					(thickness 0.15)
				)
				(justify mirror)
			)
		)
		(property "Description" "SMD Chip Resistor, 100 ohm, ± 1%, 62.5 mW, 0402 [1005 Metric], Thick Film, General Purpose"
			(at 0 0 90)
			(layer "B.Fab")
			(hide yes)
			(effects
				(font
					(size 1.27 1.27)
					(thickness 0.15)
				)
				(justify mirror)
			)
		)
		(property "MPN" "CR0402-FX-1000GLF"
			(at 0 0 90)
			(unlocked yes)
			(layer "B.Fab")
			(hide yes)
			(effects
				(font
					(size 1 1)
					(thickness 0.15)
				)
				(justify mirror)
			)
		)
		(property "Manufacturer" "Bourns"
			(at 0 0 90)
			(unlocked yes)
			(layer "B.Fab")
			(hide yes)
			(effects
				(font
					(size 1 1)
					(thickness 0.15)
				)
				(justify mirror)
			)
		)
		(property "License" "Apache-2.0"
			(at 0 0 90)
			(unlocked yes)
			(layer "B.Fab")
			(hide yes)
			(effects
				(font
					(size 1 1)
					(thickness 0.15)
				)
				(justify mirror)
			)
		)
		(property "Author" "Antmicro"
			(at 0 0 90)
			(unlocked yes)
			(layer "B.Fab")
			(hide yes)
			(effects
				(font
					(size 1 1)
					(thickness 0.15)
				)
				(justify mirror)
			)
		)
		(property "Val" "100R"
			(at 0 0 90)
			(unlocked yes)
			(layer "B.Fab")
			(hide yes)
			(effects
				(font
					(size 1 1)
					(thickness 0.15)
				)
				(justify mirror)
			)
		)
		(property "Tolerance" "1%"
			(at 0 0 90)
			(unlocked yes)
			(layer "B.Fab")
			(hide yes)
			(effects
				(font
					(size 1 1)
					(thickness 0.15)
				)
				(justify mirror)
			)
		)
		(sheetname "/X710-AT2 RSVD/")
		(sheetfile "x710-at2-rsvd.kicad_sch")
		(attr smd)
		(fp_rect
			(start -0.925 0.47)
			(end 0.925 -0.47)
			(stroke
				(width 0.05)
				(type default)
			)
			(fill no)
			(layer "B.CrtYd")
		)
		(fp_rect
			(start -0.5 0.25)
			(end 0.5 -0.25)
			(stroke
				(width 0.15)
				(type solid)
			)
			(fill no)
			(layer "B.Fab")
		)
		(pad "1" smd roundrect
			(at -0.48 0 90)
			(size 0.59 0.64)
			(layers "B.Cu" "B.Mask" "B.Paste")
			(roundrect_rratio 0.25)
			(net 28 "GND")
			(pintype "passive")
		)
		(pad "2" smd roundrect
			(at 0.48 0 90)
			(size 0.59 0.64)
			(layers "B.Cu" "B.Mask" "B.Paste")
			(roundrect_rratio 0.25)
			(net 128 "/X710-AT2 RSVD/RSVDY18_VSS")
			(pintype "passive")
		)
	)
	(footprint "antmicro-footprints:R_0402_1005Metric"
		(layer "B.Cu")
		(at 100.62 88.734 -90)
		(descr "Resistor SMD 0402")
		(tags "resistor SMD 0402")
		(property "Reference" "R125"
			(at -0.834 -0.48 90)
			(layer "B.SilkS")
			(effects
				(font
					(size 0.7 0.7)
					(thickness 0.15)
				)
				(justify right bottom mirror)
			)
		)
		(property "Value" "R_49R9_0402"
			(at -1.011843 -1.772047 90)
			(layer "B.Fab")
			(hide yes)
			(effects
				(font
					(size 0.7 0.7)
					(thickness 0.15)
				)
				(justify left bottom mirror)
			)
		)
		(property "Datasheet" "https://www.bourns.com/docs/product-datasheets/cr.pdf"
			(at 0 0 90)
			(layer "B.Fab")
			(hide yes)
			(effects
				(font
					(size 1.27 1.27)
					(thickness 0.15)
				)
				(justify mirror)
			)
		)
		(property "Description" "SMD Chip Resistor, 49.9 ohm, ± 1%, 62.5 mW, 0402 [1005 Metric], Thick Film, General Purpose"
			(at 0 0 90)
			(layer "B.Fab")
			(hide yes)
			(effects
				(font
					(size 1.27 1.27)
					(thickness 0.15)
				)
				(justify mirror)
			)
		)
		(property "MPN" "CR0402-FX-49R9GLF"
			(at 0 0 90)
			(unlocked yes)
			(layer "B.Fab")
			(hide yes)
			(effects
				(font
					(size 1 1)
					(thickness 0.15)
				)
				(justify mirror)
			)
		)
		(property "Manufacturer" "Bourns"
			(at 0 0 90)
			(unlocked yes)
			(layer "B.Fab")
			(hide yes)
			(effects
				(font
					(size 1 1)
					(thickness 0.15)
				)
				(justify mirror)
			)
		)
		(property "License" "Apache-2.0"
			(at 0 0 90)
			(unlocked yes)
			(layer "B.Fab")
			(hide yes)
			(effects
				(font
					(size 1 1)
					(thickness 0.15)
				)
				(justify mirror)
			)
		)
		(property "Author" "Antmicro"
			(at 0 0 90)
			(unlocked yes)
			(layer "B.Fab")
			(hide yes)
			(effects
				(font
					(size 1 1)
					(thickness 0.15)
				)
				(justify mirror)
			)
		)
		(property "Val" "49R9"
			(at 0 0 90)
			(unlocked yes)
			(layer "B.Fab")
			(hide yes)
			(effects
				(font
					(size 1 1)
					(thickness 0.15)
				)
				(justify mirror)
			)
		)
		(property "Tolerance" "1%"
			(at 0 0 90)
			(unlocked yes)
			(layer "B.Fab")
			(hide yes)
			(effects
				(font
					(size 1 1)
					(thickness 0.15)
				)
				(justify mirror)
			)
		)
		(sheetname "/X710-AT2 PCIe/")
		(sheetfile "x710-at2-pcie.kicad_sch")
		(attr smd exclude_from_pos_files exclude_from_bom dnp)
		(fp_rect
			(start -0.925 0.47)
			(end 0.925 -0.47)
			(stroke
				(width 0.05)
				(type default)
			)
			(fill no)
			(layer "B.CrtYd")
		)
		(fp_rect
			(start -0.5 0.25)
			(end 0.5 -0.25)
			(stroke
				(width 0.15)
				(type solid)
			)
			(fill no)
			(layer "B.Fab")
		)
		(pad "1" smd roundrect
			(at -0.48 0 270)
			(size 0.59 0.64)
			(layers "B.Cu" "B.Mask" "B.Paste")
			(roundrect_rratio 0.25)
			(net 28 "GND")
			(pintype "passive")
		)
		(pad "2" smd roundrect
			(at 0.48 0 270)
			(size 0.59 0.64)
			(layers "B.Cu" "B.Mask" "B.Paste")
			(roundrect_rratio 0.25)
			(net 406 "/X710-AT2 PCIe/GEN_F_CLK-")
			(pintype "passive")
		)
	)
	(footprint "antmicro-footprints:R_0402_1005Metric"
		(layer "B.Cu")
		(at 96.45 99.1)
		(descr "Resistor SMD 0402")
		(tags "resistor SMD 0402")
		(property "Reference" "R64"
			(at 0.9 -0.338889 0)
			(layer "B.SilkS")
			(effects
				(font
					(size 0.7 0.7)
					(thickness 0.15)
				)
				(justify right top mirror)
			)
		)
		(property "Value" "R_3k3_0402"
			(at -1.011843 -1.772046 0)
			(layer "B.Fab")
			(hide yes)
			(effects
				(font
					(size 0.7 0.7)
					(thickness 0.15)
				)
				(justify right top mirror)
			)
		)
		(property "Datasheet" "https://www.bourns.com/docs/product-datasheets/cr.pdf"
			(at 0 0 0)
			(layer "B.Fab")
			(hide yes)
			(effects
				(font
					(size 1.27 1.27)
					(thickness 0.15)
				)
				(justify mirror)
			)
		)
		(property "Description" "SMD Chip Resistor, 3.3 kohm, ± 1%, 63 mW, 0402 [1005 Metric], Thick Film, General Purpose"
			(at 0 0 0)
			(layer "B.Fab")
			(hide yes)
			(effects
				(font
					(size 1.27 1.27)
					(thickness 0.15)
				)
				(justify mirror)
			)
		)
		(property "MPN" "CR0402-FX-3301GLF"
			(at 0 0 0)
			(unlocked yes)
			(layer "B.Fab")
			(hide yes)
			(effects
				(font
					(size 1 1)
					(thickness 0.15)
				)
				(justify mirror)
			)
		)
		(property "Manufacturer" "Bourns"
			(at 0 0 0)
			(unlocked yes)
			(layer "B.Fab")
			(hide yes)
			(effects
				(font
					(size 1 1)
					(thickness 0.15)
				)
				(justify mirror)
			)
		)
		(property "License" "Apache-2.0"
			(at 0 0 0)
			(unlocked yes)
			(layer "B.Fab")
			(hide yes)
			(effects
				(font
					(size 1 1)
					(thickness 0.15)
				)
				(justify mirror)
			)
		)
		(property "Author" "Antmicro"
			(at 0 0 0)
			(unlocked yes)
			(layer "B.Fab")
			(hide yes)
			(effects
				(font
					(size 1 1)
					(thickness 0.15)
				)
				(justify mirror)
			)
		)
		(property "Val" "3k3"
			(at 0 0 0)
			(unlocked yes)
			(layer "B.Fab")
			(hide yes)
			(effects
				(font
					(size 1 1)
					(thickness 0.15)
				)
				(justify mirror)
			)
		)
		(property "Tolerance" "1%"
			(at 0 0 0)
			(unlocked yes)
			(layer "B.Fab")
			(hide yes)
			(effects
				(font
					(size 1 1)
					(thickness 0.15)
				)
				(justify mirror)
			)
		)
		(sheetname "/X710-AT2 10GbE/")
		(sheetfile "x710-at2-10gbe.kicad_sch")
		(attr smd)
		(fp_rect
			(start -0.925 0.47)
			(end 0.925 -0.47)
			(stroke
				(width 0.05)
				(type default)
			)
			(fill no)
			(layer "B.CrtYd")
		)
		(fp_rect
			(start -0.5 0.25)
			(end 0.5 -0.25)
			(stroke
				(width 0.15)
				(type solid)
			)
			(fill no)
			(layer "B.Fab")
		)
		(pad "1" smd roundrect
			(at -0.48 0)
			(size 0.59 0.64)
			(layers "B.Cu" "B.Mask" "B.Paste")
			(roundrect_rratio 0.25)
			(net 103 "/X710-AT2 10GbE/MDIO1_SDA1")
			(pintype "passive")
		)
		(pad "2" smd roundrect
			(at 0.48 0)
			(size 0.59 0.64)
			(layers "B.Cu" "B.Mask" "B.Paste")
			(roundrect_rratio 0.25)
			(net 7 "+3V3")
			(pintype "passive")
		)
	)
	(footprint "antmicro-footprints:TP_SMD_0.75mm"
		(layer "B.Cu")
		(at 103.55 102.7 90)
		(property "Reference" "TP3"
			(at 0.432018 0.625533 180)
			(layer "B.SilkS")
			(effects
				(font
					(size 0.7 0.7)
					(thickness 0.15)
				)
				(justify right top mirror)
			)
		)
		(property "Value" "TP_0.75mm_SMD"
			(at 0 -1.2 90)
			(layer "B.Fab")
			(hide yes)
			(effects
				(font
					(size 0.7 0.7)
					(thickness 0.15)
				)
				(justify right top mirror)
			)
		)
		(property "Description" "SMT test point"
			(at 0 0 90)
			(layer "B.Fab")
			(hide yes)
			(effects
				(font
					(size 1.27 1.27)
					(thickness 0.15)
				)
				(justify mirror)
			)
		)
		(property "MPN" ""
			(at 0 0 90)
			(unlocked yes)
			(layer "B.Fab")
			(hide yes)
			(effects
				(font
					(size 1 1)
					(thickness 0.15)
				)
				(justify mirror)
			)
		)
		(property "Manufacturer" ""
			(at 0 0 90)
			(unlocked yes)
			(layer "B.Fab")
			(hide yes)
			(effects
				(font
					(size 1 1)
					(thickness 0.15)
				)
				(justify mirror)
			)
		)
		(property "Author" "Antmicro"
			(at 0 0 90)
			(unlocked yes)
			(layer "B.Fab")
			(hide yes)
			(effects
				(font
					(size 1 1)
					(thickness 0.15)
				)
				(justify mirror)
			)
		)
		(property "License" "Apache-2.0"
			(at 0 0 90)
			(unlocked yes)
			(layer "B.Fab")
			(hide yes)
			(effects
				(font
					(size 1 1)
					(thickness 0.15)
				)
				(justify mirror)
			)
		)
		(sheetname "/X710-AT2 Misc/")
		(sheetfile "x710-at2-mics.kicad_sch")
		(attr exclude_from_pos_files exclude_from_bom)
		(fp_circle
			(center 0 0)
			(end 0.475 0)
			(stroke
				(width 0.05)
				(type default)
			)
			(fill no)
			(layer "B.CrtYd")
		)
		(pad "1" smd circle
			(at 0 0 90)
			(size 0.75 0.75)
			(layers "B.Cu" "B.Mask")
			(net 367 "/X710-AT2 Misc/NCSI.REF_CLK")
			(pinfunction "1")
			(pintype "passive")
		)
	)
	(footprint "antmicro-footprints:R_0402_1005Metric"
		(layer "B.Cu")
		(at 111.49 88.86 90)
		(descr "Resistor SMD 0402")
		(tags "resistor SMD 0402")
		(property "Reference" "R132"
			(at -3.58 -0.38 90)
			(layer "B.SilkS")
			(effects
				(font
					(size 0.7 0.7)
					(thickness 0.15)
				)
				(justify right top mirror)
			)
		)
		(property "Value" "R_10k_0402"
			(at -1.011843 -1.772046 90)
			(layer "B.Fab")
			(hide yes)
			(effects
				(font
					(size 0.7 0.7)
					(thickness 0.15)
				)
				(justify right top mirror)
			)
		)
		(property "Datasheet" "https://www.bourns.com/docs/product-datasheets/cr.pdf"
			(at 0 0 90)
			(layer "B.Fab")
			(hide yes)
			(effects
				(font
					(size 1.27 1.27)
					(thickness 0.15)
				)
				(justify mirror)
			)
		)
		(property "Description" "SMD Chip Resistor, 10 kohm, ± 1%, 62.5 mW, 0402 [1005 Metric], Thick Film, General Purpose"
			(at 0 0 90)
			(layer "B.Fab")
			(hide yes)
			(effects
				(font
					(size 1.27 1.27)
					(thickness 0.15)
				)
				(justify mirror)
			)
		)
		(property "MPN" "CR0402-FX-1002GLF"
			(at 0 0 90)
			(unlocked yes)
			(layer "B.Fab")
			(hide yes)
			(effects
				(font
					(size 1 1)
					(thickness 0.15)
				)
				(justify mirror)
			)
		)
		(property "Manufacturer" "Bourns"
			(at 0 0 90)
			(unlocked yes)
			(layer "B.Fab")
			(hide yes)
			(effects
				(font
					(size 1 1)
					(thickness 0.15)
				)
				(justify mirror)
			)
		)
		(property "License" "Apache-2.0"
			(at 0 0 90)
			(unlocked yes)
			(layer "B.Fab")
			(hide yes)
			(effects
				(font
					(size 1 1)
					(thickness 0.15)
				)
				(justify mirror)
			)
		)
		(property "Author" "Antmicro"
			(at 0 0 90)
			(unlocked yes)
			(layer "B.Fab")
			(hide yes)
			(effects
				(font
					(size 1 1)
					(thickness 0.15)
				)
				(justify mirror)
			)
		)
		(property "Val" "10k"
			(at 0 0 90)
			(unlocked yes)
			(layer "B.Fab")
			(hide yes)
			(effects
				(font
					(size 1 1)
					(thickness 0.15)
				)
				(justify mirror)
			)
		)
		(property "Tolerance" "1%"
			(at 0 0 90)
			(unlocked yes)
			(layer "B.Fab")
			(hide yes)
			(effects
				(font
					(size 1 1)
					(thickness 0.15)
				)
				(justify mirror)
			)
		)
		(sheetname "/X710-AT2 RSVD/")
		(sheetfile "x710-at2-rsvd.kicad_sch")
		(attr smd)
		(fp_rect
			(start -0.925 0.47)
			(end 0.925 -0.47)
			(stroke
				(width 0.05)
				(type default)
			)
			(fill no)
			(layer "B.CrtYd")
		)
		(fp_rect
			(start -0.5 0.25)
			(end 0.5 -0.25)
			(stroke
				(width 0.15)
				(type solid)
			)
			(fill no)
			(layer "B.Fab")
		)
		(pad "1" smd roundrect
			(at -0.48 0 90)
			(size 0.59 0.64)
			(layers "B.Cu" "B.Mask" "B.Paste")
			(roundrect_rratio 0.25)
			(net 28 "GND")
			(pintype "passive")
		)
		(pad "2" smd roundrect
			(at 0.48 0 90)
			(size 0.59 0.64)
			(layers "B.Cu" "B.Mask" "B.Paste")
			(roundrect_rratio 0.25)
			(net 120 "/X710-AT2 RSVD/DEBUG_W7")
			(pintype "passive")
		)
	)
	(footprint "antmicro-footprints:C_0402_1005Metric"
		(layer "B.Cu")
		(at 79.58 108.93 120)
		(descr "Capacitor SMD 0402")
		(tags "capacitor SMD 0402")
		(property "Reference" "C166"
			(at -7.920805 -5.600763 120)
			(layer "B.SilkS")
			(effects
				(font
					(size 0.7 0.7)
					(thickness 0.15)
				)
				(justify right top mirror)
			)
		)
		(property "Value" "C_1u_25V_0402"
			(at -1.022927 -2.155212 120)
			(layer "B.Fab")
			(hide yes)
			(effects
				(font
					(size 0.7 0.7)
					(thickness 0.15)
				)
				(justify right top mirror)
			)
		)
		(property "Datasheet" "https://www.murata.com/products/productdetail?partno=GRM155R61E105KE11%23"
			(at 0 0 120)
			(layer "B.Fab")
			(hide yes)
			(effects
				(font
					(size 1.27 1.27)
					(thickness 0.15)
				)
				(justify mirror)
			)
		)
		(property "Description" "SMD Multilayer Ceramic Capacitor, 1 µF, 25 V, 0402 [1005 Metric], ± 10%, X5R, GRM Series"
			(at 0 0 120)
			(layer "B.Fab")
			(hide yes)
			(effects
				(font
					(size 1.27 1.27)
					(thickness 0.15)
				)
				(justify mirror)
			)
		)
		(property "MPN" "GRM155R61E105KE11J"
			(at 0 0 120)
			(unlocked yes)
			(layer "B.Fab")
			(hide yes)
			(effects
				(font
					(size 1 1)
					(thickness 0.15)
				)
				(justify mirror)
			)
		)
		(property "Manufacturer" "Murata"
			(at 0 0 120)
			(unlocked yes)
			(layer "B.Fab")
			(hide yes)
			(effects
				(font
					(size 1 1)
					(thickness 0.15)
				)
				(justify mirror)
			)
		)
		(property "License" "Apache-2.0"
			(at 0 0 120)
			(unlocked yes)
			(layer "B.Fab")
			(hide yes)
			(effects
				(font
					(size 1 1)
					(thickness 0.15)
				)
				(justify mirror)
			)
		)
		(property "Author" "Antmicro"
			(at 0 0 120)
			(unlocked yes)
			(layer "B.Fab")
			(hide yes)
			(effects
				(font
					(size 1 1)
					(thickness 0.15)
				)
				(justify mirror)
			)
		)
		(property "Val" "1u"
			(at 0 0 120)
			(unlocked yes)
			(layer "B.Fab")
			(hide yes)
			(effects
				(font
					(size 1 1)
					(thickness 0.15)
				)
				(justify mirror)
			)
		)
		(property "Voltage" "25V"
			(at 0 0 120)
			(unlocked yes)
			(layer "B.Fab")
			(hide yes)
			(effects
				(font
					(size 1 1)
					(thickness 0.15)
				)
				(justify mirror)
			)
		)
		(property "Dielectric" "X5R"
			(at 0 0 120)
			(unlocked yes)
			(layer "B.Fab")
			(hide yes)
			(effects
				(font
					(size 1 1)
					(thickness 0.15)
				)
				(justify mirror)
			)
		)
		(sheetname "/X710-AT2 power/")
		(sheetfile "x710-at2-power.kicad_sch")
		(attr smd)
		(fp_poly
			(pts
				(xy -0.925 0.47) (xy 0.925 0.47) (xy 0.925 -0.47) (xy -0.925 -0.47)
			)
			(stroke
				(width 0.05)
				(type default)
			)
			(fill no)
			(layer "B.CrtYd")
		)
		(fp_line
			(start 0.504 -0.248)
			(end -0.494001 -0.248)
			(stroke
				(width 0.15)
				(type solid)
			)
			(layer "B.Fab")
		)
		(fp_line
			(start 0.504 0.25)
			(end 0.504 -0.248)
			(stroke
				(width 0.15)
				(type solid)
			)
			(layer "B.Fab")
		)
		(fp_line
			(start -0.494001 -0.248)
			(end -0.494 0.249999)
			(stroke
				(width 0.15)
				(type solid)
			)
			(layer "B.Fab")
		)
		(fp_line
			(start -0.494 0.249999)
			(end 0.504 0.25)
			(stroke
				(width 0.15)
				(type solid)
			)
			(layer "B.Fab")
		)
		(pad "1" smd roundrect
			(at -0.48 0 120)
			(size 0.59 0.64)
			(layers "B.Cu" "B.Mask" "B.Paste")
			(roundrect_rratio 0.25)
			(net 28 "GND")
			(pintype "passive")
		)
		(pad "2" smd roundrect
			(at 0.48 0 120)
			(size 0.59 0.64)
			(layers "B.Cu" "B.Mask" "B.Paste")
			(roundrect_rratio 0.25)
			(net 5 "P0_AVDDL")
			(pintype "passive")
		)
	)
	(footprint "antmicro-footprints:C_0805_2012Metric"
		(layer "B.Cu")
		(at 66 134.7)
		(descr "Capacitor SMD 0805")
		(tags "capacitor SMD 0805")
		(property "Reference" "C55"
			(at -1 1.05 0)
			(layer "B.SilkS")
			(effects
				(font
					(size 0.7 0.7)
					(thickness 0.15)
				)
				(justify right top mirror)
			)
		)
		(property "Value" "C_100u_0805"
			(at -2.055717 -1.963153 0)
			(layer "B.Fab")
			(hide yes)
			(effects
				(font
					(size 0.7 0.7)
					(thickness 0.15)
				)
				(justify right top mirror)
			)
		)
		(property "Datasheet" "https://www.murata.com/products/productdetail?partno=GRM21BR60J107ME15%23"
			(at 0 0 0)
			(layer "B.Fab")
			(hide yes)
			(effects
				(font
					(size 1.27 1.27)
					(thickness 0.15)
				)
				(justify mirror)
			)
		)
		(property "Description" "SMD Multilayer Ceramic Capacitor, 100 µF, 6.3 V, 0805 [2012 Metric], ± 20%, X5R, GRM Series"
			(at 0 0 0)
			(layer "B.Fab")
			(hide yes)
			(effects
				(font
					(size 1.27 1.27)
					(thickness 0.15)
				)
				(justify mirror)
			)
		)
		(property "MPN" "GRM21BR60J107ME15L"
			(at 0 0 0)
			(unlocked yes)
			(layer "B.Fab")
			(hide yes)
			(effects
				(font
					(size 1 1)
					(thickness 0.15)
				)
				(justify mirror)
			)
		)
		(property "Manufacturer" "Murata"
			(at 0 0 0)
			(unlocked yes)
			(layer "B.Fab")
			(hide yes)
			(effects
				(font
					(size 1 1)
					(thickness 0.15)
				)
				(justify mirror)
			)
		)
		(property "License" "Apache-2.0"
			(at 0 0 0)
			(unlocked yes)
			(layer "B.Fab")
			(hide yes)
			(effects
				(font
					(size 1 1)
					(thickness 0.15)
				)
				(justify mirror)
			)
		)
		(property "Author" "Antmicro"
			(at 0 0 0)
			(unlocked yes)
			(layer "B.Fab")
			(hide yes)
			(effects
				(font
					(size 1 1)
					(thickness 0.15)
				)
				(justify mirror)
			)
		)
		(property "Val" "100u"
			(at 0 0 0)
			(unlocked yes)
			(layer "B.Fab")
			(hide yes)
			(effects
				(font
					(size 1 1)
					(thickness 0.15)
				)
				(justify mirror)
			)
		)
		(property "Voltage" ""
			(at 0 0 0)
			(unlocked yes)
			(layer "B.Fab")
			(hide yes)
			(effects
				(font
					(size 1 1)
					(thickness 0.15)
				)
				(justify mirror)
			)
		)
		(property "Dielectric" ""
			(at 0 0 0)
			(unlocked yes)
			(layer "B.Fab")
			(hide yes)
			(effects
				(font
					(size 1 1)
					(thickness 0.15)
				)
				(justify mirror)
			)
		)
		(property "Public" "False"
			(at 0 0 0)
			(unlocked yes)
			(layer "B.Fab")
			(hide yes)
			(effects
				(font
					(size 1 1)
					(thickness 0.15)
				)
				(justify mirror)
			)
		)
		(sheetname "/2xRJ45/")
		(sheetfile "2xrj45.kicad_sch")
		(attr smd)
		(fp_line
			(start -0.3 -0.7)
			(end 0.3 -0.7)
			(stroke
				(width 0.15)
				(type solid)
			)
			(layer "B.SilkS")
		)
		(fp_line
			(start -0.3 0.7)
			(end 0.3 0.7)
			(stroke
				(width 0.15)
				(type solid)
			)
			(layer "B.SilkS")
		)
		(fp_rect
			(start 1.95 0.9)
			(end -1.95 -0.9)
			(stroke
				(width 0.05)
				(type default)
			)
			(fill no)
			(layer "B.CrtYd")
		)
		(fp_rect
			(start -0.95 0.675)
			(end 0.95 -0.675)
			(stroke
				(width 0.15)
				(type solid)
			)
			(fill no)
			(layer "B.Fab")
		)
		(pad "1" smd roundrect
			(at -1.1 0)
			(size 1.2 1.3)
			(layers "B.Cu" "B.Mask" "B.Paste")
			(roundrect_rratio 0.25)
			(net 28 "GND")
			(pintype "passive")
		)
		(pad "2" smd roundrect
			(at 1.1 0)
			(size 1.2 1.3)
			(layers "B.Cu" "B.Mask" "B.Paste")
			(roundrect_rratio 0.25)
			(net 299 "/2xRJ45/P0_CT")
			(pintype "passive")
		)
	)
	(footprint "antmicro-footprints:TP_SMD_1mm"
		(layer "B.Cu")
		(at 75.74 74.55 -90)
		(property "Reference" "TP34"
			(at -1.06 4.51 90)
			(layer "B.SilkS")
			(effects
				(font
					(size 0.7 0.7)
					(thickness 0.15)
				)
				(justify left bottom mirror)
			)
		)
		(property "Value" "TP_1mm_SMD"
			(at 0 -1.4 90)
			(layer "B.Fab")
			(hide yes)
			(effects
				(font
					(size 0.7 0.7)
					(thickness 0.15)
				)
				(justify left bottom mirror)
			)
		)
		(property "Description" "Test point 1mm SMD"
			(at 0 0 90)
			(layer "B.Fab")
			(hide yes)
			(effects
				(font
					(size 1.27 1.27)
					(thickness 0.15)
				)
				(justify mirror)
			)
		)
		(property "MPN" ""
			(at 0 0 90)
			(unlocked yes)
			(layer "B.Fab")
			(hide yes)
			(effects
				(font
					(size 1 1)
					(thickness 0.15)
				)
				(justify mirror)
			)
		)
		(property "Manufacturer" ""
			(at 0 0 90)
			(unlocked yes)
			(layer "B.Fab")
			(hide yes)
			(effects
				(font
					(size 1 1)
					(thickness 0.15)
				)
				(justify mirror)
			)
		)
		(property "Author" "Antmicro"
			(at 0 0 90)
			(unlocked yes)
			(layer "B.Fab")
			(hide yes)
			(effects
				(font
					(size 1 1)
					(thickness 0.15)
				)
				(justify mirror)
			)
		)
		(property "License" "Apache-2.0"
			(at 0 0 90)
			(unlocked yes)
			(layer "B.Fab")
			(hide yes)
			(effects
				(font
					(size 1 1)
					(thickness 0.15)
				)
				(justify mirror)
			)
		)
		(sheetname "/Power/")
		(sheetfile "power.kicad_sch")
		(attr exclude_from_pos_files exclude_from_bom)
		(fp_circle
			(center 0 0)
			(end 0.6 0)
			(stroke
				(width 0.05)
				(type default)
			)
			(fill no)
			(layer "B.CrtYd")
		)
		(pad "1" smd circle
			(at 0 0 270)
			(size 1 1)
			(layers "B.Cu" "B.Mask")
			(net 6 "DVDD")
			(pinfunction "1")
			(pintype "passive")
		)
	)
	(footprint "antmicro-footprints:C_0402_1005Metric"
		(layer "B.Cu")
		(at 79.4 105.08 90)
		(descr "Capacitor SMD 0402")
		(tags "capacitor SMD 0402")
		(property "Reference" "C83"
			(at -11.81 0.0225 90)
			(layer "B.SilkS")
			(effects
				(font
					(size 0.7 0.7)
					(thickness 0.15)
				)
				(justify right top mirror)
			)
		)
		(property "Value" "C_1u_25V_0402"
			(at -1.022927 -2.155213 90)
			(layer "B.Fab")
			(hide yes)
			(effects
				(font
					(size 0.7 0.7)
					(thickness 0.15)
				)
				(justify right top mirror)
			)
		)
		(property "Datasheet" "https://www.murata.com/products/productdetail?partno=GRM155R61E105KE11%23"
			(at 0 0 90)
			(layer "B.Fab")
			(hide yes)
			(effects
				(font
					(size 1.27 1.27)
					(thickness 0.15)
				)
				(justify mirror)
			)
		)
		(property "Description" "SMD Multilayer Ceramic Capacitor, 1 µF, 25 V, 0402 [1005 Metric], ± 10%, X5R, GRM Series"
			(at 0 0 90)
			(layer "B.Fab")
			(hide yes)
			(effects
				(font
					(size 1.27 1.27)
					(thickness 0.15)
				)
				(justify mirror)
			)
		)
		(property "MPN" "GRM155R61E105KE11J"
			(at 0 0 90)
			(unlocked yes)
			(layer "B.Fab")
			(hide yes)
			(effects
				(font
					(size 1 1)
					(thickness 0.15)
				)
				(justify mirror)
			)
		)
		(property "Manufacturer" "Murata"
			(at 0 0 90)
			(unlocked yes)
			(layer "B.Fab")
			(hide yes)
			(effects
				(font
					(size 1 1)
					(thickness 0.15)
				)
				(justify mirror)
			)
		)
		(property "License" "Apache-2.0"
			(at 0 0 90)
			(unlocked yes)
			(layer "B.Fab")
			(hide yes)
			(effects
				(font
					(size 1 1)
					(thickness 0.15)
				)
				(justify mirror)
			)
		)
		(property "Author" "Antmicro"
			(at 0 0 90)
			(unlocked yes)
			(layer "B.Fab")
			(hide yes)
			(effects
				(font
					(size 1 1)
					(thickness 0.15)
				)
				(justify mirror)
			)
		)
		(property "Val" "1u"
			(at 0 0 90)
			(unlocked yes)
			(layer "B.Fab")
			(hide yes)
			(effects
				(font
					(size 1 1)
					(thickness 0.15)
				)
				(justify mirror)
			)
		)
		(property "Voltage" "25V"
			(at 0 0 90)
			(unlocked yes)
			(layer "B.Fab")
			(hide yes)
			(effects
				(font
					(size 1 1)
					(thickness 0.15)
				)
				(justify mirror)
			)
		)
		(property "Dielectric" "X5R"
			(at 0 0 90)
			(unlocked yes)
			(layer "B.Fab")
			(hide yes)
			(effects
				(font
					(size 1 1)
					(thickness 0.15)
				)
				(justify mirror)
			)
		)
		(sheetname "/X710-AT2 power/")
		(sheetfile "x710-at2-power.kicad_sch")
		(attr smd)
		(fp_rect
			(start -0.925 0.47)
			(end 0.925 -0.47)
			(stroke
				(width 0.05)
				(type default)
			)
			(fill no)
			(layer "B.CrtYd")
		)
		(fp_line
			(start 0.504 -0.248)
			(end -0.494 -0.248)
			(stroke
				(width 0.15)
				(type solid)
			)
			(layer "B.Fab")
		)
		(fp_line
			(start -0.494 -0.248)
			(end -0.494 0.25)
			(stroke
				(width 0.15)
				(type solid)
			)
			(layer "B.Fab")
		)
		(fp_line
			(start 0.504 0.25)
			(end 0.504 -0.248)
			(stroke
				(width 0.15)
				(type solid)
			)
			(layer "B.Fab")
		)
		(fp_line
			(start -0.494 0.25)
			(end 0.504 0.25)
			(stroke
				(width 0.15)
				(type solid)
			)
			(layer "B.Fab")
		)
		(pad "1" smd roundrect
			(at -0.48 0 90)
			(size 0.59 0.64)
			(layers "B.Cu" "B.Mask" "B.Paste")
			(roundrect_rratio 0.25)
			(net 28 "GND")
			(pintype "passive")
		)
		(pad "2" smd roundrect
			(at 0.48 0 90)
			(size 0.59 0.64)
			(layers "B.Cu" "B.Mask" "B.Paste")
			(roundrect_rratio 0.25)
			(net 6 "DVDD")
			(pintype "passive")
		)
	)
	(footprint "antmicro-footprints:C_0402_1005Metric"
		(layer "B.Cu")
		(at 75.79 107.9 -90)
		(descr "Capacitor SMD 0402")
		(tags "capacitor SMD 0402")
		(property "Reference" "C168"
			(at 0.84 -0.33 90)
			(layer "B.SilkS")
			(effects
				(font
					(size 0.7 0.7)
					(thickness 0.15)
				)
				(justify left bottom mirror)
			)
		)
		(property "Value" "C_1u_25V_0402"
			(at -1.022927 -2.155213 90)
			(layer "B.Fab")
			(hide yes)
			(effects
				(font
					(size 0.7 0.7)
					(thickness 0.15)
				)
				(justify left bottom mirror)
			)
		)
		(property "Datasheet" "https://www.murata.com/products/productdetail?partno=GRM155R61E105KE11%23"
			(at 0 0 90)
			(layer "B.Fab")
			(hide yes)
			(effects
				(font
					(size 1.27 1.27)
					(thickness 0.15)
				)
				(justify mirror)
			)
		)
		(property "Description" "SMD Multilayer Ceramic Capacitor, 1 µF, 25 V, 0402 [1005 Metric], ± 10%, X5R, GRM Series"
			(at 0 0 90)
			(layer "B.Fab")
			(hide yes)
			(effects
				(font
					(size 1.27 1.27)
					(thickness 0.15)
				)
				(justify mirror)
			)
		)
		(property "MPN" "GRM155R61E105KE11J"
			(at 0 0 270)
			(unlocked yes)
			(layer "B.Fab")
			(hide yes)
			(effects
				(font
					(size 1 1)
					(thickness 0.15)
				)
				(justify mirror)
			)
		)
		(property "Manufacturer" "Murata"
			(at 0 0 270)
			(unlocked yes)
			(layer "B.Fab")
			(hide yes)
			(effects
				(font
					(size 1 1)
					(thickness 0.15)
				)
				(justify mirror)
			)
		)
		(property "License" "Apache-2.0"
			(at 0 0 270)
			(unlocked yes)
			(layer "B.Fab")
			(hide yes)
			(effects
				(font
					(size 1 1)
					(thickness 0.15)
				)
				(justify mirror)
			)
		)
		(property "Author" "Antmicro"
			(at 0 0 270)
			(unlocked yes)
			(layer "B.Fab")
			(hide yes)
			(effects
				(font
					(size 1 1)
					(thickness 0.15)
				)
				(justify mirror)
			)
		)
		(property "Val" "1u"
			(at 0 0 270)
			(unlocked yes)
			(layer "B.Fab")
			(hide yes)
			(effects
				(font
					(size 1 1)
					(thickness 0.15)
				)
				(justify mirror)
			)
		)
		(property "Voltage" "25V"
			(at 0 0 270)
			(unlocked yes)
			(layer "B.Fab")
			(hide yes)
			(effects
				(font
					(size 1 1)
					(thickness 0.15)
				)
				(justify mirror)
			)
		)
		(property "Dielectric" "X5R"
			(at 0 0 270)
			(unlocked yes)
			(layer "B.Fab")
			(hide yes)
			(effects
				(font
					(size 1 1)
					(thickness 0.15)
				)
				(justify mirror)
			)
		)
		(sheetname "/X710-AT2 power/")
		(sheetfile "x710-at2-power.kicad_sch")
		(attr smd)
		(fp_rect
			(start -0.925 0.47)
			(end 0.925 -0.47)
			(stroke
				(width 0.05)
				(type default)
			)
			(fill no)
			(layer "B.CrtYd")
		)
		(fp_line
			(start -0.494 0.25)
			(end 0.504 0.25)
			(stroke
				(width 0.15)
				(type solid)
			)
			(layer "B.Fab")
		)
		(fp_line
			(start 0.504 0.25)
			(end 0.504 -0.248)
			(stroke
				(width 0.15)
				(type solid)
			)
			(layer "B.Fab")
		)
		(fp_line
			(start -0.494 -0.248)
			(end -0.494 0.25)
			(stroke
				(width 0.15)
				(type solid)
			)
			(layer "B.Fab")
		)
		(fp_line
			(start 0.504 -0.248)
			(end -0.494 -0.248)
			(stroke
				(width 0.15)
				(type solid)
			)
			(layer "B.Fab")
		)
		(pad "1" smd roundrect
			(at -0.48 0 270)
			(size 0.59 0.64)
			(layers "B.Cu" "B.Mask" "B.Paste")
			(roundrect_rratio 0.25)
			(net 28 "GND")
			(pintype "passive")
		)
		(pad "2" smd roundrect
			(at 0.48 0 270)
			(size 0.59 0.64)
			(layers "B.Cu" "B.Mask" "B.Paste")
			(roundrect_rratio 0.25)
			(net 5 "P0_AVDDL")
			(pintype "passive")
		)
	)
	(footprint "antmicro-footprints:TP_SMD_0.75mm"
		(layer "B.Cu")
		(at 100.55 108.7)
		(property "Reference" "TP4"
			(at -0.32 2.54 90)
			(layer "B.SilkS")
			(effects
				(font
					(size 0.7 0.7)
					(thickness 0.15)
				)
				(justify right top mirror)
			)
		)
		(property "Value" "TP_0.75mm_SMD"
			(at 0 -1.2 0)
			(layer "B.Fab")
			(hide yes)
			(effects
				(font
					(size 0.7 0.7)
					(thickness 0.15)
				)
				(justify right top mirror)
			)
		)
		(property "Description" "SMT test point"
			(at 0 0 0)
			(layer "B.Fab")
			(hide yes)
			(effects
				(font
					(size 1.27 1.27)
					(thickness 0.15)
				)
				(justify mirror)
			)
		)
		(property "MPN" ""
			(at 0 0 0)
			(unlocked yes)
			(layer "B.Fab")
			(hide yes)
			(effects
				(font
					(size 1 1)
					(thickness 0.15)
				)
				(justify mirror)
			)
		)
		(property "Manufacturer" ""
			(at 0 0 0)
			(unlocked yes)
			(layer "B.Fab")
			(hide yes)
			(effects
				(font
					(size 1 1)
					(thickness 0.15)
				)
				(justify mirror)
			)
		)
		(property "Author" "Antmicro"
			(at 0 0 0)
			(unlocked yes)
			(layer "B.Fab")
			(hide yes)
			(effects
				(font
					(size 1 1)
					(thickness 0.15)
				)
				(justify mirror)
			)
		)
		(property "License" "Apache-2.0"
			(at 0 0 0)
			(unlocked yes)
			(layer "B.Fab")
			(hide yes)
			(effects
				(font
					(size 1 1)
					(thickness 0.15)
				)
				(justify mirror)
			)
		)
		(sheetname "/X710-AT2 Misc/")
		(sheetfile "x710-at2-mics.kicad_sch")
		(attr exclude_from_pos_files exclude_from_bom)
		(fp_circle
			(center 0 0)
			(end 0.475 0)
			(stroke
				(width 0.05)
				(type default)
			)
			(fill no)
			(layer "B.CrtYd")
		)
		(pad "1" smd circle
			(at 0 0)
			(size 0.75 0.75)
			(layers "B.Cu" "B.Mask")
			(net 365 "/X710-AT2 Misc/NCSI.CRS_DV")
			(pinfunction "1")
			(pintype "passive")
		)
	)
	(footprint "antmicro-footprints:C_0402_1005Metric"
		(layer "B.Cu")
		(at 60.670003 103.849999)
		(descr "Capacitor SMD 0402")
		(tags "capacitor SMD 0402")
		(property "Reference" "C27"
			(at -1.010003 0.530001 0)
			(layer "B.SilkS")
			(effects
				(font
					(size 0.7 0.7)
					(thickness 0.15)
				)
				(justify right top mirror)
			)
		)
		(property "Value" "C_100n_0402"
			(at -1.022927 -2.155213 0)
			(layer "B.Fab")
			(hide yes)
			(effects
				(font
					(size 0.7 0.7)
					(thickness 0.15)
				)
				(justify right top mirror)
			)
		)
		(property "Datasheet" "https://www.murata.com/products/productdetail?partno=GRM155R61H104KE14%23"
			(at 0 0 0)
			(layer "B.Fab")
			(hide yes)
			(effects
				(font
					(size 1.27 1.27)
					(thickness 0.15)
				)
				(justify mirror)
			)
		)
		(property "Description" "SMD Multilayer Ceramic Capacitor, 0.1 µF, 50 V, 0402 [1005 Metric], ± 10%, X5R, GRM Series"
			(at 0 0 0)
			(layer "B.Fab")
			(hide yes)
			(effects
				(font
					(size 1.27 1.27)
					(thickness 0.15)
				)
				(justify mirror)
			)
		)
		(property "MPN" "GRM155R61H104KE14D"
			(at 0 0 0)
			(unlocked yes)
			(layer "B.Fab")
			(hide yes)
			(effects
				(font
					(size 1 1)
					(thickness 0.15)
				)
				(justify mirror)
			)
		)
		(property "Manufacturer" "Murata"
			(at 0 0 0)
			(unlocked yes)
			(layer "B.Fab")
			(hide yes)
			(effects
				(font
					(size 1 1)
					(thickness 0.15)
				)
				(justify mirror)
			)
		)
		(property "License" "Apache-2.0"
			(at 0 0 0)
			(unlocked yes)
			(layer "B.Fab")
			(hide yes)
			(effects
				(font
					(size 1 1)
					(thickness 0.15)
				)
				(justify mirror)
			)
		)
		(property "Author" "Antmicro"
			(at 0 0 0)
			(unlocked yes)
			(layer "B.Fab")
			(hide yes)
			(effects
				(font
					(size 1 1)
					(thickness 0.15)
				)
				(justify mirror)
			)
		)
		(property "Val" "100n"
			(at 0 0 0)
			(unlocked yes)
			(layer "B.Fab")
			(hide yes)
			(effects
				(font
					(size 1 1)
					(thickness 0.15)
				)
				(justify mirror)
			)
		)
		(property "Voltage" "50V"
			(at 0 0 0)
			(unlocked yes)
			(layer "B.Fab")
			(hide yes)
			(effects
				(font
					(size 1 1)
					(thickness 0.15)
				)
				(justify mirror)
			)
		)
		(property "Dielectric" "X5R"
			(at 0 0 0)
			(unlocked yes)
			(layer "B.Fab")
			(hide yes)
			(effects
				(font
					(size 1 1)
					(thickness 0.15)
				)
				(justify mirror)
			)
		)
		(sheetname "/Power/")
		(sheetfile "power.kicad_sch")
		(attr smd)
		(fp_rect
			(start -0.925 0.47)
			(end 0.925 -0.47)
			(stroke
				(width 0.05)
				(type default)
			)
			(fill no)
			(layer "B.CrtYd")
		)
		(fp_line
			(start -0.494 -0.248)
			(end -0.494 0.25)
			(stroke
				(width 0.15)
				(type solid)
			)
			(layer "B.Fab")
		)
		(fp_line
			(start -0.494 0.25)
			(end 0.504 0.25)
			(stroke
				(width 0.15)
				(type solid)
			)
			(layer "B.Fab")
		)
		(fp_line
			(start 0.504 -0.248)
			(end -0.494 -0.248)
			(stroke
				(width 0.15)
				(type solid)
			)
			(layer "B.Fab")
		)
		(fp_line
			(start 0.504 0.25)
			(end 0.504 -0.248)
			(stroke
				(width 0.15)
				(type solid)
			)
			(layer "B.Fab")
		)
		(pad "1" smd roundrect
			(at -0.48 0)
			(size 0.59 0.64)
			(layers "B.Cu" "B.Mask" "B.Paste")
			(roundrect_rratio 0.25)
			(net 28 "GND")
			(pintype "passive")
		)
		(pad "2" smd roundrect
			(at 0.48 0)
			(size 0.59 0.64)
			(layers "B.Cu" "B.Mask" "B.Paste")
			(roundrect_rratio 0.25)
			(net 310 "/Power/+1V88_OUT")
			(pintype "passive")
		)
	)
	(footprint "antmicro-footprints:R_0402_1005Metric"
		(layer "B.Cu")
		(at 95.225 94 -90)
		(descr "Resistor SMD 0402")
		(tags "resistor SMD 0402")
		(property "Reference" "R138"
			(at -1.4 -0.575 90)
			(layer "B.SilkS")
			(effects
				(font
					(size 0.7 0.7)
					(thickness 0.15)
				)
				(justify left top mirror)
			)
		)
		(property "Value" "R_100R_0402"
			(at -1.011843 -1.772046 90)
			(layer "B.Fab")
			(hide yes)
			(effects
				(font
					(size 0.7 0.7)
					(thickness 0.15)
				)
				(justify left bottom mirror)
			)
		)
		(property "Datasheet" "https://www.bourns.com/docs/product-datasheets/cr.pdf"
			(at 0 0 90)
			(layer "B.Fab")
			(hide yes)
			(effects
				(font
					(size 1.27 1.27)
					(thickness 0.15)
				)
				(justify mirror)
			)
		)
		(property "Description" "SMD Chip Resistor, 100 ohm, ± 1%, 62.5 mW, 0402 [1005 Metric], Thick Film, General Purpose"
			(at 0 0 90)
			(layer "B.Fab")
			(hide yes)
			(effects
				(font
					(size 1.27 1.27)
					(thickness 0.15)
				)
				(justify mirror)
			)
		)
		(property "MPN" "CR0402-FX-1000GLF"
			(at 0 0 270)
			(unlocked yes)
			(layer "B.Fab")
			(hide yes)
			(effects
				(font
					(size 1 1)
					(thickness 0.15)
				)
				(justify mirror)
			)
		)
		(property "Manufacturer" "Bourns"
			(at 0 0 270)
			(unlocked yes)
			(layer "B.Fab")
			(hide yes)
			(effects
				(font
					(size 1 1)
					(thickness 0.15)
				)
				(justify mirror)
			)
		)
		(property "License" "Apache-2.0"
			(at 0 0 270)
			(unlocked yes)
			(layer "B.Fab")
			(hide yes)
			(effects
				(font
					(size 1 1)
					(thickness 0.15)
				)
				(justify mirror)
			)
		)
		(property "Author" "Antmicro"
			(at 0 0 270)
			(unlocked yes)
			(layer "B.Fab")
			(hide yes)
			(effects
				(font
					(size 1 1)
					(thickness 0.15)
				)
				(justify mirror)
			)
		)
		(property "Val" "100R"
			(at 0 0 270)
			(unlocked yes)
			(layer "B.Fab")
			(hide yes)
			(effects
				(font
					(size 1 1)
					(thickness 0.15)
				)
				(justify mirror)
			)
		)
		(property "Tolerance" "1%"
			(at 0 0 270)
			(unlocked yes)
			(layer "B.Fab")
			(hide yes)
			(effects
				(font
					(size 1 1)
					(thickness 0.15)
				)
				(justify mirror)
			)
		)
		(sheetname "/X710-AT2 RSVD/")
		(sheetfile "x710-at2-rsvd.kicad_sch")
		(attr smd)
		(fp_rect
			(start -0.925 0.47)
			(end 0.925 -0.47)
			(stroke
				(width 0.05)
				(type default)
			)
			(fill no)
			(layer "B.CrtYd")
		)
		(fp_rect
			(start -0.5 0.25)
			(end 0.5 -0.25)
			(stroke
				(width 0.15)
				(type solid)
			)
			(fill no)
			(layer "B.Fab")
		)
		(pad "1" smd roundrect
			(at -0.48 0 270)
			(size 0.59 0.64)
			(layers "B.Cu" "B.Mask" "B.Paste")
			(roundrect_rratio 0.25)
			(net 28 "GND")
			(pintype "passive")
		)
		(pad "2" smd roundrect
			(at 0.48 0 270)
			(size 0.59 0.64)
			(layers "B.Cu" "B.Mask" "B.Paste")
			(roundrect_rratio 0.25)
			(net 126 "/X710-AT2 RSVD/RSVDW1_VSS")
			(pintype "passive")
		)
	)
	(footprint "antmicro-footprints:C_0402_1005Metric"
		(layer "B.Cu")
		(at 95.48 145.34 -90)
		(descr "Capacitor SMD 0402")
		(tags "capacitor SMD 0402")
		(property "Reference" "C61"
			(at -2.89 -0.44 90)
			(layer "B.SilkS")
			(effects
				(font
					(size 0.7 0.7)
					(thickness 0.15)
				)
				(justify left bottom mirror)
			)
		)
		(property "Value" "C_470p_0402"
			(at -1.022927 -2.155213 90)
			(layer "B.Fab")
			(hide yes)
			(effects
				(font
					(size 0.7 0.7)
					(thickness 0.15)
				)
				(justify left bottom mirror)
			)
		)
		(property "Datasheet" "https://www.passivecomponent.com/wp-content/uploads/datasheet/WTC_MLCC_General_Purpose.pdf"
			(at 0 0 90)
			(layer "B.Fab")
			(hide yes)
			(effects
				(font
					(size 1.27 1.27)
					(thickness 0.15)
				)
				(justify mirror)
			)
		)
		(property "Description" "SMD Multilayer Ceramic Capacitor, General Purpose, 470 pF, 25 V, 0402 [1005 Metric], ± 10%, X7R"
			(at 0 0 90)
			(layer "B.Fab")
			(hide yes)
			(effects
				(font
					(size 1.27 1.27)
					(thickness 0.15)
				)
				(justify mirror)
			)
		)
		(property "MPN" "0402B471K250CT"
			(at 0 0 270)
			(unlocked yes)
			(layer "B.Fab")
			(hide yes)
			(effects
				(font
					(size 1 1)
					(thickness 0.15)
				)
				(justify mirror)
			)
		)
		(property "Manufacturer" "Walsin"
			(at 0 0 270)
			(unlocked yes)
			(layer "B.Fab")
			(hide yes)
			(effects
				(font
					(size 1 1)
					(thickness 0.15)
				)
				(justify mirror)
			)
		)
		(property "License" "Apache-2.0"
			(at 0 0 270)
			(unlocked yes)
			(layer "B.Fab")
			(hide yes)
			(effects
				(font
					(size 1 1)
					(thickness 0.15)
				)
				(justify mirror)
			)
		)
		(property "Author" "Antmicro"
			(at 0 0 270)
			(unlocked yes)
			(layer "B.Fab")
			(hide yes)
			(effects
				(font
					(size 1 1)
					(thickness 0.15)
				)
				(justify mirror)
			)
		)
		(property "Val" "470p"
			(at 0 0 270)
			(unlocked yes)
			(layer "B.Fab")
			(hide yes)
			(effects
				(font
					(size 1 1)
					(thickness 0.15)
				)
				(justify mirror)
			)
		)
		(property "Voltage" "25V"
			(at 0 0 270)
			(unlocked yes)
			(layer "B.Fab")
			(hide yes)
			(effects
				(font
					(size 1 1)
					(thickness 0.15)
				)
				(justify mirror)
			)
		)
		(property "Dielectric" "X7R"
			(at 0 0 270)
			(unlocked yes)
			(layer "B.Fab")
			(hide yes)
			(effects
				(font
					(size 1 1)
					(thickness 0.15)
				)
				(justify mirror)
			)
		)
		(sheetname "/2xRJ45/")
		(sheetfile "2xrj45.kicad_sch")
		(attr smd)
		(fp_rect
			(start -0.925 0.47)
			(end 0.925 -0.47)
			(stroke
				(width 0.05)
				(type default)
			)
			(fill no)
			(layer "B.CrtYd")
		)
		(fp_line
			(start -0.494 0.25)
			(end 0.504 0.25)
			(stroke
				(width 0.15)
				(type solid)
			)
			(layer "B.Fab")
		)
		(fp_line
			(start 0.504 0.25)
			(end 0.504 -0.248)
			(stroke
				(width 0.15)
				(type solid)
			)
			(layer "B.Fab")
		)
		(fp_line
			(start -0.494 -0.248)
			(end -0.494 0.25)
			(stroke
				(width 0.15)
				(type solid)
			)
			(layer "B.Fab")
		)
		(fp_line
			(start 0.504 -0.248)
			(end -0.494 -0.248)
			(stroke
				(width 0.15)
				(type solid)
			)
			(layer "B.Fab")
		)
		(pad "1" smd roundrect
			(at -0.48 0 270)
			(size 0.59 0.64)
			(layers "B.Cu" "B.Mask" "B.Paste")
			(roundrect_rratio 0.25)
			(net 28 "GND")
			(pintype "passive")
		)
		(pad "2" smd roundrect
			(at 0.48 0 270)
			(size 0.59 0.64)
			(layers "B.Cu" "B.Mask" "B.Paste")
			(roundrect_rratio 0.25)
			(net 64 "Net-(J6-LED_YG_G-)")
			(pintype "passive")
		)
	)
	(footprint "antmicro-footprints:C_0402_1005Metric"
		(layer "B.Cu")
		(at 89.225 102 90)
		(descr "Capacitor SMD 0402")
		(tags "capacitor SMD 0402")
		(property "Reference" "C92"
			(at 9.09 -0.447343 90)
			(layer "B.SilkS")
			(effects
				(font
					(size 0.7 0.7)
					(thickness 0.15)
				)
				(justify right top mirror)
			)
		)
		(property "Value" "C_1u_25V_0402"
			(at -1.022927 -2.155213 90)
			(layer "B.Fab")
			(hide yes)
			(effects
				(font
					(size 0.7 0.7)
					(thickness 0.15)
				)
				(justify right top mirror)
			)
		)
		(property "Datasheet" "https://www.murata.com/products/productdetail?partno=GRM155R61E105KE11%23"
			(at 0 0 90)
			(layer "B.Fab")
			(hide yes)
			(effects
				(font
					(size 1.27 1.27)
					(thickness 0.15)
				)
				(justify mirror)
			)
		)
		(property "Description" "SMD Multilayer Ceramic Capacitor, 1 µF, 25 V, 0402 [1005 Metric], ± 10%, X5R, GRM Series"
			(at 0 0 90)
			(layer "B.Fab")
			(hide yes)
			(effects
				(font
					(size 1.27 1.27)
					(thickness 0.15)
				)
				(justify mirror)
			)
		)
		(property "MPN" "GRM155R61E105KE11J"
			(at 0 0 90)
			(unlocked yes)
			(layer "B.Fab")
			(hide yes)
			(effects
				(font
					(size 1 1)
					(thickness 0.15)
				)
				(justify mirror)
			)
		)
		(property "Manufacturer" "Murata"
			(at 0 0 90)
			(unlocked yes)
			(layer "B.Fab")
			(hide yes)
			(effects
				(font
					(size 1 1)
					(thickness 0.15)
				)
				(justify mirror)
			)
		)
		(property "License" "Apache-2.0"
			(at 0 0 90)
			(unlocked yes)
			(layer "B.Fab")
			(hide yes)
			(effects
				(font
					(size 1 1)
					(thickness 0.15)
				)
				(justify mirror)
			)
		)
		(property "Author" "Antmicro"
			(at 0 0 90)
			(unlocked yes)
			(layer "B.Fab")
			(hide yes)
			(effects
				(font
					(size 1 1)
					(thickness 0.15)
				)
				(justify mirror)
			)
		)
		(property "Val" "1u"
			(at 0 0 90)
			(unlocked yes)
			(layer "B.Fab")
			(hide yes)
			(effects
				(font
					(size 1 1)
					(thickness 0.15)
				)
				(justify mirror)
			)
		)
		(property "Voltage" "25V"
			(at 0 0 90)
			(unlocked yes)
			(layer "B.Fab")
			(hide yes)
			(effects
				(font
					(size 1 1)
					(thickness 0.15)
				)
				(justify mirror)
			)
		)
		(property "Dielectric" "X5R"
			(at 0 0 90)
			(unlocked yes)
			(layer "B.Fab")
			(hide yes)
			(effects
				(font
					(size 1 1)
					(thickness 0.15)
				)
				(justify mirror)
			)
		)
		(sheetname "/X710-AT2 power/")
		(sheetfile "x710-at2-power.kicad_sch")
		(attr smd)
		(fp_rect
			(start -0.925 0.47)
			(end 0.925 -0.47)
			(stroke
				(width 0.05)
				(type default)
			)
			(fill no)
			(layer "B.CrtYd")
		)
		(fp_line
			(start 0.504 -0.248)
			(end -0.494 -0.248)
			(stroke
				(width 0.15)
				(type solid)
			)
			(layer "B.Fab")
		)
		(fp_line
			(start -0.494 -0.248)
			(end -0.494 0.25)
			(stroke
				(width 0.15)
				(type solid)
			)
			(layer "B.Fab")
		)
		(fp_line
			(start 0.504 0.25)
			(end 0.504 -0.248)
			(stroke
				(width 0.15)
				(type solid)
			)
			(layer "B.Fab")
		)
		(fp_line
			(start -0.494 0.25)
			(end 0.504 0.25)
			(stroke
				(width 0.15)
				(type solid)
			)
			(layer "B.Fab")
		)
		(pad "1" smd roundrect
			(at -0.48 0 90)
			(size 0.59 0.64)
			(layers "B.Cu" "B.Mask" "B.Paste")
			(roundrect_rratio 0.25)
			(net 28 "GND")
			(pintype "passive")
		)
		(pad "2" smd roundrect
			(at 0.48 0 90)
			(size 0.59 0.64)
			(layers "B.Cu" "B.Mask" "B.Paste")
			(roundrect_rratio 0.25)
			(net 1 "VCCA")
			(pintype "passive")
		)
	)
	(footprint "antmicro-footprints:C_0402_1005Metric"
		(layer "B.Cu")
		(at 83.3 128.5)
		(descr "Capacitor SMD 0402")
		(tags "capacitor SMD 0402")
		(property "Reference" "C53"
			(at -0.85 0.45 0)
			(layer "B.SilkS")
			(effects
				(font
					(size 0.7 0.7)
					(thickness 0.15)
				)
				(justify left bottom mirror)
			)
		)
		(property "Value" "C_1u_25V_0402"
			(at -1.022927 -2.155213 0)
			(layer "B.Fab")
			(hide yes)
			(effects
				(font
					(size 0.7 0.7)
					(thickness 0.15)
				)
				(justify right top mirror)
			)
		)
		(property "Datasheet" "https://www.murata.com/products/productdetail?partno=GRM155R61E105KE11%23"
			(at 0 0 0)
			(layer "B.Fab")
			(hide yes)
			(effects
				(font
					(size 1.27 1.27)
					(thickness 0.15)
				)
				(justify mirror)
			)
		)
		(property "Description" "SMD Multilayer Ceramic Capacitor, 1 µF, 25 V, 0402 [1005 Metric], ± 10%, X5R, GRM Series"
			(at 0 0 0)
			(layer "B.Fab")
			(hide yes)
			(effects
				(font
					(size 1.27 1.27)
					(thickness 0.15)
				)
				(justify mirror)
			)
		)
		(property "MPN" "GRM155R61E105KE11J"
			(at 0 0 0)
			(unlocked yes)
			(layer "B.Fab")
			(hide yes)
			(effects
				(font
					(size 1 1)
					(thickness 0.15)
				)
				(justify mirror)
			)
		)
		(property "Manufacturer" "Murata"
			(at 0 0 0)
			(unlocked yes)
			(layer "B.Fab")
			(hide yes)
			(effects
				(font
					(size 1 1)
					(thickness 0.15)
				)
				(justify mirror)
			)
		)
		(property "License" "Apache-2.0"
			(at 0 0 0)
			(unlocked yes)
			(layer "B.Fab")
			(hide yes)
			(effects
				(font
					(size 1 1)
					(thickness 0.15)
				)
				(justify mirror)
			)
		)
		(property "Author" "Antmicro"
			(at 0 0 0)
			(unlocked yes)
			(layer "B.Fab")
			(hide yes)
			(effects
				(font
					(size 1 1)
					(thickness 0.15)
				)
				(justify mirror)
			)
		)
		(property "Val" "1u"
			(at 0 0 0)
			(unlocked yes)
			(layer "B.Fab")
			(hide yes)
			(effects
				(font
					(size 1 1)
					(thickness 0.15)
				)
				(justify mirror)
			)
		)
		(property "Voltage" "25V"
			(at 0 0 0)
			(unlocked yes)
			(layer "B.Fab")
			(hide yes)
			(effects
				(font
					(size 1 1)
					(thickness 0.15)
				)
				(justify mirror)
			)
		)
		(property "Dielectric" "X5R"
			(at 0 0 0)
			(unlocked yes)
			(layer "B.Fab")
			(hide yes)
			(effects
				(font
					(size 1 1)
					(thickness 0.15)
				)
				(justify mirror)
			)
		)
		(sheetname "/2xRJ45/")
		(sheetfile "2xrj45.kicad_sch")
		(attr smd)
		(fp_rect
			(start -0.925 0.47)
			(end 0.925 -0.47)
			(stroke
				(width 0.05)
				(type default)
			)
			(fill no)
			(layer "B.CrtYd")
		)
		(fp_line
			(start -0.494 -0.248)
			(end -0.494 0.25)
			(stroke
				(width 0.15)
				(type solid)
			)
			(layer "B.Fab")
		)
		(fp_line
			(start -0.494 0.25)
			(end 0.504 0.25)
			(stroke
				(width 0.15)
				(type solid)
			)
			(layer "B.Fab")
		)
		(fp_line
			(start 0.504 -0.248)
			(end -0.494 -0.248)
			(stroke
				(width 0.15)
				(type solid)
			)
			(layer "B.Fab")
		)
		(fp_line
			(start 0.504 0.25)
			(end 0.504 -0.248)
			(stroke
				(width 0.15)
				(type solid)
			)
			(layer "B.Fab")
		)
		(pad "1" smd roundrect
			(at -0.48 0)
			(size 0.59 0.64)
			(layers "B.Cu" "B.Mask" "B.Paste")
			(roundrect_rratio 0.25)
			(net 28 "GND")
			(pintype "passive")
		)
		(pad "2" smd roundrect
			(at 0.48 0)
			(size 0.59 0.64)
			(layers "B.Cu" "B.Mask" "B.Paste")
			(roundrect_rratio 0.25)
			(net 301 "+1V88_CT")
			(pintype "passive")
		)
	)
	(footprint "antmicro-footprints:R_0402_1005Metric"
		(layer "B.Cu")
		(at 109.5 67.6 180)
		(descr "Resistor SMD 0402")
		(tags "resistor SMD 0402")
		(property "Reference" "R167"
			(at -1.44 5.61 0)
			(layer "B.SilkS")
			(effects
				(font
					(size 0.7 0.7)
					(thickness 0.15)
				)
				(justify left bottom mirror)
			)
		)
		(property "Value" "R_0R_0402"
			(at -1.011843 -1.772046 0)
			(layer "B.Fab")
			(hide yes)
			(effects
				(font
					(size 0.7 0.7)
					(thickness 0.15)
				)
				(justify left bottom mirror)
			)
		)
		(property "Datasheet" "https://industrial.panasonic.com/cdbs/www-data/pdf/RDA0000/AOA0000C301.pdf"
			(at 0 0 0)
			(layer "B.Fab")
			(hide yes)
			(effects
				(font
					(size 1.27 1.27)
					(thickness 0.15)
				)
				(justify mirror)
			)
		)
		(property "Description" "SMD Chip Resistor, Jumper, 0 ohm, 100 mW, 0402 [1005 Metric], Thick Film, General Purpose"
			(at 0 0 0)
			(layer "B.Fab")
			(hide yes)
			(effects
				(font
					(size 1.27 1.27)
					(thickness 0.15)
				)
				(justify mirror)
			)
		)
		(property "MPN" "ERJ2GE0R00X"
			(at 0 0 180)
			(unlocked yes)
			(layer "B.Fab")
			(hide yes)
			(effects
				(font
					(size 1 1)
					(thickness 0.15)
				)
				(justify mirror)
			)
		)
		(property "Manufacturer" "Panasonic"
			(at 0 0 180)
			(unlocked yes)
			(layer "B.Fab")
			(hide yes)
			(effects
				(font
					(size 1 1)
					(thickness 0.15)
				)
				(justify mirror)
			)
		)
		(property "License" "Apache-2.0"
			(at 0 0 180)
			(unlocked yes)
			(layer "B.Fab")
			(hide yes)
			(effects
				(font
					(size 1 1)
					(thickness 0.15)
				)
				(justify mirror)
			)
		)
		(property "Author" "Antmicro"
			(at 0 0 180)
			(unlocked yes)
			(layer "B.Fab")
			(hide yes)
			(effects
				(font
					(size 1 1)
					(thickness 0.15)
				)
				(justify mirror)
			)
		)
		(property "Val" "0R"
			(at 0 0 180)
			(unlocked yes)
			(layer "B.Fab")
			(hide yes)
			(effects
				(font
					(size 1 1)
					(thickness 0.15)
				)
				(justify mirror)
			)
		)
		(property "Tolerance" "~"
			(at 0 0 180)
			(unlocked yes)
			(layer "B.Fab")
			(hide yes)
			(effects
				(font
					(size 1 1)
					(thickness 0.15)
				)
				(justify mirror)
			)
		)
		(property "Current" "1A"
			(at 0 0 180)
			(unlocked yes)
			(layer "B.Fab")
			(hide yes)
			(effects
				(font
					(size 1 1)
					(thickness 0.15)
				)
				(justify mirror)
			)
		)
		(sheetname "/OCuLink/")
		(sheetfile "oculink.kicad_sch")
		(attr smd)
		(fp_rect
			(start -0.925 0.47)
			(end 0.925 -0.47)
			(stroke
				(width 0.05)
				(type default)
			)
			(fill no)
			(layer "B.CrtYd")
		)
		(fp_rect
			(start -0.5 0.25)
			(end 0.5 -0.25)
			(stroke
				(width 0.15)
				(type solid)
			)
			(fill no)
			(layer "B.Fab")
		)
		(pad "1" smd roundrect
			(at -0.48 0 180)
			(size 0.59 0.64)
			(layers "B.Cu" "B.Mask" "B.Paste")
			(roundrect_rratio 0.25)
			(net 319 "/OCuLink/~{PE_ RST}_R")
			(pintype "passive")
		)
		(pad "2" smd roundrect
			(at 0.48 0 180)
			(size 0.59 0.64)
			(layers "B.Cu" "B.Mask" "B.Paste")
			(roundrect_rratio 0.25)
			(net 308 "/OCuLink/~{PE_RST}")
			(pintype "passive")
		)
	)
	(footprint "antmicro-footprints:R_0402_1005Metric"
		(layer "B.Cu")
		(at 78.85 101.65 180)
		(descr "Resistor SMD 0402")
		(tags "resistor SMD 0402")
		(property "Reference" "R116"
			(at -0.85 -0.45 0)
			(layer "B.SilkS")
			(effects
				(font
					(size 0.7 0.7)
					(thickness 0.15)
				)
				(justify right bottom mirror)
			)
		)
		(property "Value" "R_1k_0402"
			(at -1.011843 -1.772047 0)
			(layer "B.Fab")
			(hide yes)
			(effects
				(font
					(size 0.7 0.7)
					(thickness 0.15)
				)
				(justify left bottom mirror)
			)
		)
		(property "Datasheet" "https://www.bourns.com/docs/product-datasheets/cr.pdf"
			(at 0 0 0)
			(layer "B.Fab")
			(hide yes)
			(effects
				(font
					(size 1.27 1.27)
					(thickness 0.15)
				)
				(justify mirror)
			)
		)
		(property "Description" "SMD Chip Resistor, 1 kohm, ± 1%, 63 mW, 0402 [1005 Metric], Thick Film, General Purpose"
			(at 0 0 0)
			(layer "B.Fab")
			(hide yes)
			(effects
				(font
					(size 1.27 1.27)
					(thickness 0.15)
				)
				(justify mirror)
			)
		)
		(property "MPN" "CR0402-FX-1001GLF"
			(at 0 0 180)
			(unlocked yes)
			(layer "B.Fab")
			(hide yes)
			(effects
				(font
					(size 1 1)
					(thickness 0.15)
				)
				(justify mirror)
			)
		)
		(property "Manufacturer" "Bourns"
			(at 0 0 180)
			(unlocked yes)
			(layer "B.Fab")
			(hide yes)
			(effects
				(font
					(size 1 1)
					(thickness 0.15)
				)
				(justify mirror)
			)
		)
		(property "License" "Apache-2.0"
			(at 0 0 180)
			(unlocked yes)
			(layer "B.Fab")
			(hide yes)
			(effects
				(font
					(size 1 1)
					(thickness 0.15)
				)
				(justify mirror)
			)
		)
		(property "Author" "Antmicro"
			(at 0 0 180)
			(unlocked yes)
			(layer "B.Fab")
			(hide yes)
			(effects
				(font
					(size 1 1)
					(thickness 0.15)
				)
				(justify mirror)
			)
		)
		(property "Val" "1k"
			(at 0 0 180)
			(unlocked yes)
			(layer "B.Fab")
			(hide yes)
			(effects
				(font
					(size 1 1)
					(thickness 0.15)
				)
				(justify mirror)
			)
		)
		(property "Tolerance" "1%"
			(at 0 0 180)
			(unlocked yes)
			(layer "B.Fab")
			(hide yes)
			(effects
				(font
					(size 1 1)
					(thickness 0.15)
				)
				(justify mirror)
			)
		)
		(sheetname "/X710-AT2 Misc/")
		(sheetfile "x710-at2-mics.kicad_sch")
		(attr smd)
		(fp_rect
			(start -0.925 0.47)
			(end 0.925 -0.47)
			(stroke
				(width 0.05)
				(type default)
			)
			(fill no)
			(layer "B.CrtYd")
		)
		(fp_rect
			(start -0.5 0.25)
			(end 0.5 -0.25)
			(stroke
				(width 0.15)
				(type solid)
			)
			(fill no)
			(layer "B.Fab")
		)
		(pad "1" smd roundrect
			(at -0.48 0 180)
			(size 0.59 0.64)
			(layers "B.Cu" "B.Mask" "B.Paste")
			(roundrect_rratio 0.25)
			(net 112 "/X710-AT2 Misc/RSVDL33")
			(pintype "passive")
		)
		(pad "2" smd roundrect
			(at 0.48 0 180)
			(size 0.59 0.64)
			(layers "B.Cu" "B.Mask" "B.Paste")
			(roundrect_rratio 0.25)
			(net 18 "+1V88")
			(pintype "passive")
		)
	)
	(footprint "antmicro-footprints:TP_SMD_1mm"
		(layer "B.Cu")
		(at 82.49 72.3 -90)
		(property "Reference" "TP29"
			(at -1.87 8.478102 90)
			(layer "B.SilkS")
			(effects
				(font
					(size 0.7 0.7)
					(thickness 0.15)
				)
				(justify left bottom mirror)
			)
		)
		(property "Value" "TP_1mm_SMD"
			(at 0 -1.4 90)
			(layer "B.Fab")
			(hide yes)
			(effects
				(font
					(size 0.7 0.7)
					(thickness 0.15)
				)
				(justify left bottom mirror)
			)
		)
		(property "Description" "Test point 1mm SMD"
			(at 0 0 90)
			(layer "B.Fab")
			(hide yes)
			(effects
				(font
					(size 1.27 1.27)
					(thickness 0.15)
				)
				(justify mirror)
			)
		)
		(property "MPN" ""
			(at 0 0 90)
			(unlocked yes)
			(layer "B.Fab")
			(hide yes)
			(effects
				(font
					(size 1 1)
					(thickness 0.15)
				)
				(justify mirror)
			)
		)
		(property "Manufacturer" ""
			(at 0 0 90)
			(unlocked yes)
			(layer "B.Fab")
			(hide yes)
			(effects
				(font
					(size 1 1)
					(thickness 0.15)
				)
				(justify mirror)
			)
		)
		(property "Author" "Antmicro"
			(at 0 0 90)
			(unlocked yes)
			(layer "B.Fab")
			(hide yes)
			(effects
				(font
					(size 1 1)
					(thickness 0.15)
				)
				(justify mirror)
			)
		)
		(property "License" "Apache-2.0"
			(at 0 0 90)
			(unlocked yes)
			(layer "B.Fab")
			(hide yes)
			(effects
				(font
					(size 1 1)
					(thickness 0.15)
				)
				(justify mirror)
			)
		)
		(sheetname "/Power/")
		(sheetfile "power.kicad_sch")
		(attr exclude_from_pos_files exclude_from_bom)
		(fp_circle
			(center 0 0)
			(end 0.6 0)
			(stroke
				(width 0.05)
				(type default)
			)
			(fill no)
			(layer "B.CrtYd")
		)
		(pad "1" smd circle
			(at 0 0 270)
			(size 1 1)
			(layers "B.Cu" "B.Mask")
			(net 314 "VCC")
			(pinfunction "1")
			(pintype "passive")
		)
	)
	(footprint "antmicro-footprints:C_0402_1005Metric"
		(layer "B.Cu")
		(at 90.225 98.3 90)
		(descr "Capacitor SMD 0402")
		(tags "capacitor SMD 0402")
		(property "Reference" "C132"
			(at 10.69 -0.445 90)
			(layer "B.SilkS")
			(effects
				(font
					(size 0.7 0.7)
					(thickness 0.15)
				)
				(justify right top mirror)
			)
		)
		(property "Value" "C_1u_25V_0402"
			(at -1.022927 -2.155213 90)
			(layer "B.Fab")
			(hide yes)
			(effects
				(font
					(size 0.7 0.7)
					(thickness 0.15)
				)
				(justify right top mirror)
			)
		)
		(property "Datasheet" "https://www.murata.com/products/productdetail?partno=GRM155R61E105KE11%23"
			(at 0 0 90)
			(layer "B.Fab")
			(hide yes)
			(effects
				(font
					(size 1.27 1.27)
					(thickness 0.15)
				)
				(justify mirror)
			)
		)
		(property "Description" "SMD Multilayer Ceramic Capacitor, 1 µF, 25 V, 0402 [1005 Metric], ± 10%, X5R, GRM Series"
			(at 0 0 90)
			(layer "B.Fab")
			(hide yes)
			(effects
				(font
					(size 1.27 1.27)
					(thickness 0.15)
				)
				(justify mirror)
			)
		)
		(property "MPN" "GRM155R61E105KE11J"
			(at 0 0 90)
			(unlocked yes)
			(layer "B.Fab")
			(hide yes)
			(effects
				(font
					(size 1 1)
					(thickness 0.15)
				)
				(justify mirror)
			)
		)
		(property "Manufacturer" "Murata"
			(at 0 0 90)
			(unlocked yes)
			(layer "B.Fab")
			(hide yes)
			(effects
				(font
					(size 1 1)
					(thickness 0.15)
				)
				(justify mirror)
			)
		)
		(property "License" "Apache-2.0"
			(at 0 0 90)
			(unlocked yes)
			(layer "B.Fab")
			(hide yes)
			(effects
				(font
					(size 1 1)
					(thickness 0.15)
				)
				(justify mirror)
			)
		)
		(property "Author" "Antmicro"
			(at 0 0 90)
			(unlocked yes)
			(layer "B.Fab")
			(hide yes)
			(effects
				(font
					(size 1 1)
					(thickness 0.15)
				)
				(justify mirror)
			)
		)
		(property "Val" "1u"
			(at 0 0 90)
			(unlocked yes)
			(layer "B.Fab")
			(hide yes)
			(effects
				(font
					(size 1 1)
					(thickness 0.15)
				)
				(justify mirror)
			)
		)
		(property "Voltage" "25V"
			(at 0 0 90)
			(unlocked yes)
			(layer "B.Fab")
			(hide yes)
			(effects
				(font
					(size 1 1)
					(thickness 0.15)
				)
				(justify mirror)
			)
		)
		(property "Dielectric" "X5R"
			(at 0 0 90)
			(unlocked yes)
			(layer "B.Fab")
			(hide yes)
			(effects
				(font
					(size 1 1)
					(thickness 0.15)
				)
				(justify mirror)
			)
		)
		(sheetname "/X710-AT2 power/")
		(sheetfile "x710-at2-power.kicad_sch")
		(attr smd)
		(fp_rect
			(start -0.925 0.47)
			(end 0.925 -0.47)
			(stroke
				(width 0.05)
				(type default)
			)
			(fill no)
			(layer "B.CrtYd")
		)
		(fp_line
			(start 0.504 -0.248)
			(end -0.494 -0.248)
			(stroke
				(width 0.15)
				(type solid)
			)
			(layer "B.Fab")
		)
		(fp_line
			(start -0.494 -0.248)
			(end -0.494 0.25)
			(stroke
				(width 0.15)
				(type solid)
			)
			(layer "B.Fab")
		)
		(fp_line
			(start 0.504 0.25)
			(end 0.504 -0.248)
			(stroke
				(width 0.15)
				(type solid)
			)
			(layer "B.Fab")
		)
		(fp_line
			(start -0.494 0.25)
			(end 0.504 0.25)
			(stroke
				(width 0.15)
				(type solid)
			)
			(layer "B.Fab")
		)
		(pad "1" smd roundrect
			(at -0.48 0 90)
			(size 0.59 0.64)
			(layers "B.Cu" "B.Mask" "B.Paste")
			(roundrect_rratio 0.25)
			(net 28 "GND")
			(pintype "passive")
		)
		(pad "2" smd roundrect
			(at 0.48 0 90)
			(size 0.59 0.64)
			(layers "B.Cu" "B.Mask" "B.Paste")
			(roundrect_rratio 0.25)
			(net 7 "+3V3")
			(pintype "passive")
		)
	)
	(footprint "antmicro-footprints:C_0402_1005Metric"
		(layer "B.Cu")
		(at 88.225 98.3 90)
		(descr "Capacitor SMD 0402")
		(tags "capacitor SMD 0402")
		(property "Reference" "C112"
			(at 10.69 -0.490714 90)
			(layer "B.SilkS")
			(effects
				(font
					(size 0.7 0.7)
					(thickness 0.15)
				)
				(justify right top mirror)
			)
		)
		(property "Value" "C_1u_25V_0402"
			(at -1.022927 -2.155213 90)
			(layer "B.Fab")
			(hide yes)
			(effects
				(font
					(size 0.7 0.7)
					(thickness 0.15)
				)
				(justify right top mirror)
			)
		)
		(property "Datasheet" "https://www.murata.com/products/productdetail?partno=GRM155R61E105KE11%23"
			(at 0 0 90)
			(layer "B.Fab")
			(hide yes)
			(effects
				(font
					(size 1.27 1.27)
					(thickness 0.15)
				)
				(justify mirror)
			)
		)
		(property "Description" "SMD Multilayer Ceramic Capacitor, 1 µF, 25 V, 0402 [1005 Metric], ± 10%, X5R, GRM Series"
			(at 0 0 90)
			(layer "B.Fab")
			(hide yes)
			(effects
				(font
					(size 1.27 1.27)
					(thickness 0.15)
				)
				(justify mirror)
			)
		)
		(property "MPN" "GRM155R61E105KE11J"
			(at 0 0 90)
			(unlocked yes)
			(layer "B.Fab")
			(hide yes)
			(effects
				(font
					(size 1 1)
					(thickness 0.15)
				)
				(justify mirror)
			)
		)
		(property "Manufacturer" "Murata"
			(at 0 0 90)
			(unlocked yes)
			(layer "B.Fab")
			(hide yes)
			(effects
				(font
					(size 1 1)
					(thickness 0.15)
				)
				(justify mirror)
			)
		)
		(property "License" "Apache-2.0"
			(at 0 0 90)
			(unlocked yes)
			(layer "B.Fab")
			(hide yes)
			(effects
				(font
					(size 1 1)
					(thickness 0.15)
				)
				(justify mirror)
			)
		)
		(property "Author" "Antmicro"
			(at 0 0 90)
			(unlocked yes)
			(layer "B.Fab")
			(hide yes)
			(effects
				(font
					(size 1 1)
					(thickness 0.15)
				)
				(justify mirror)
			)
		)
		(property "Val" "1u"
			(at 0 0 90)
			(unlocked yes)
			(layer "B.Fab")
			(hide yes)
			(effects
				(font
					(size 1 1)
					(thickness 0.15)
				)
				(justify mirror)
			)
		)
		(property "Voltage" "25V"
			(at 0 0 90)
			(unlocked yes)
			(layer "B.Fab")
			(hide yes)
			(effects
				(font
					(size 1 1)
					(thickness 0.15)
				)
				(justify mirror)
			)
		)
		(property "Dielectric" "X5R"
			(at 0 0 90)
			(unlocked yes)
			(layer "B.Fab")
			(hide yes)
			(effects
				(font
					(size 1 1)
					(thickness 0.15)
				)
				(justify mirror)
			)
		)
		(sheetname "/X710-AT2 power/")
		(sheetfile "x710-at2-power.kicad_sch")
		(attr smd)
		(fp_rect
			(start -0.925 0.47)
			(end 0.925 -0.47)
			(stroke
				(width 0.05)
				(type default)
			)
			(fill no)
			(layer "B.CrtYd")
		)
		(fp_line
			(start 0.504 -0.248)
			(end -0.494 -0.248)
			(stroke
				(width 0.15)
				(type solid)
			)
			(layer "B.Fab")
		)
		(fp_line
			(start -0.494 -0.248)
			(end -0.494 0.25)
			(stroke
				(width 0.15)
				(type solid)
			)
			(layer "B.Fab")
		)
		(fp_line
			(start 0.504 0.25)
			(end 0.504 -0.248)
			(stroke
				(width 0.15)
				(type solid)
			)
			(layer "B.Fab")
		)
		(fp_line
			(start -0.494 0.25)
			(end 0.504 0.25)
			(stroke
				(width 0.15)
				(type solid)
			)
			(layer "B.Fab")
		)
		(pad "1" smd roundrect
			(at -0.48 0 90)
			(size 0.59 0.64)
			(layers "B.Cu" "B.Mask" "B.Paste")
			(roundrect_rratio 0.25)
			(net 28 "GND")
			(pintype "passive")
		)
		(pad "2" smd roundrect
			(at 0.48 0 90)
			(size 0.59 0.64)
			(layers "B.Cu" "B.Mask" "B.Paste")
			(roundrect_rratio 0.25)
			(net 9 "VCCD")
			(pintype "passive")
		)
	)
	(footprint "antmicro-footprints:R_0402_1005Metric"
		(layer "B.Cu")
		(at 76.48 145.34 90)
		(descr "Resistor SMD 0402")
		(tags "resistor SMD 0402")
		(property "Reference" "R36"
			(at 0.74 -0.35 90)
			(layer "B.SilkS")
			(effects
				(font
					(size 0.7 0.7)
					(thickness 0.15)
				)
				(justify right top mirror)
			)
		)
		(property "Value" "R_220R_0402"
			(at -1.011843 -1.772046 90)
			(layer "B.Fab")
			(hide yes)
			(effects
				(font
					(size 0.7 0.7)
					(thickness 0.15)
				)
				(justify right top mirror)
			)
		)
		(property "Datasheet" "https://www.bourns.com/docs/product-datasheets/cr.pdf"
			(at 0 0 90)
			(layer "B.Fab")
			(hide yes)
			(effects
				(font
					(size 1.27 1.27)
					(thickness 0.15)
				)
				(justify mirror)
			)
		)
		(property "Description" "SMD Chip Resistor, 220 ohm, ± 1%, 62.5 mW, 0402 [1005 Metric], Thick Film, General Purpose"
			(at 0 0 90)
			(layer "B.Fab")
			(hide yes)
			(effects
				(font
					(size 1.27 1.27)
					(thickness 0.15)
				)
				(justify mirror)
			)
		)
		(property "MPN" "CR0402-FX-2200GLF"
			(at 0 0 90)
			(unlocked yes)
			(layer "B.Fab")
			(hide yes)
			(effects
				(font
					(size 1 1)
					(thickness 0.15)
				)
				(justify mirror)
			)
		)
		(property "Manufacturer" "Bourns"
			(at 0 0 90)
			(unlocked yes)
			(layer "B.Fab")
			(hide yes)
			(effects
				(font
					(size 1 1)
					(thickness 0.15)
				)
				(justify mirror)
			)
		)
		(property "License" "Apache-2.0"
			(at 0 0 90)
			(unlocked yes)
			(layer "B.Fab")
			(hide yes)
			(effects
				(font
					(size 1 1)
					(thickness 0.15)
				)
				(justify mirror)
			)
		)
		(property "Author" "Antmicro"
			(at 0 0 90)
			(unlocked yes)
			(layer "B.Fab")
			(hide yes)
			(effects
				(font
					(size 1 1)
					(thickness 0.15)
				)
				(justify mirror)
			)
		)
		(property "Val" "220R"
			(at 0 0 90)
			(unlocked yes)
			(layer "B.Fab")
			(hide yes)
			(effects
				(font
					(size 1 1)
					(thickness 0.15)
				)
				(justify mirror)
			)
		)
		(property "Tolerance" "1%"
			(at 0 0 90)
			(unlocked yes)
			(layer "B.Fab")
			(hide yes)
			(effects
				(font
					(size 1 1)
					(thickness 0.15)
				)
				(justify mirror)
			)
		)
		(sheetname "/2xRJ45/")
		(sheetfile "2xrj45.kicad_sch")
		(attr smd)
		(fp_rect
			(start -0.925 0.47)
			(end 0.925 -0.47)
			(stroke
				(width 0.05)
				(type default)
			)
			(fill no)
			(layer "B.CrtYd")
		)
		(fp_rect
			(start -0.5 0.25)
			(end 0.5 -0.25)
			(stroke
				(width 0.15)
				(type solid)
			)
			(fill no)
			(layer "B.Fab")
		)
		(pad "1" smd roundrect
			(at -0.48 0 90)
			(size 0.59 0.64)
			(layers "B.Cu" "B.Mask" "B.Paste")
			(roundrect_rratio 0.25)
			(net 52 "Net-(J3-LED_YG_Y-)")
			(pintype "passive")
		)
		(pad "2" smd roundrect
			(at 0.48 0 90)
			(size 0.59 0.64)
			(layers "B.Cu" "B.Mask" "B.Paste")
			(roundrect_rratio 0.25)
			(net 291 "/2xRJ45/~{P0_LINK_LESS_THAN_10G}")
			(pintype "passive")
		)
	)
	(footprint "antmicro-footprints:C_0402_1005Metric"
		(layer "B.Cu")
		(at 85.225 98.3 90)
		(descr "Capacitor SMD 0402")
		(tags "capacitor SMD 0402")
		(property "Reference" "C118"
			(at 10.69 -0.559286 90)
			(layer "B.SilkS")
			(effects
				(font
					(size 0.7 0.7)
					(thickness 0.15)
				)
				(justify right top mirror)
			)
		)
		(property "Value" "C_1u_25V_0402"
			(at -1.022927 -2.155213 90)
			(layer "B.Fab")
			(hide yes)
			(effects
				(font
					(size 0.7 0.7)
					(thickness 0.15)
				)
				(justify right top mirror)
			)
		)
		(property "Datasheet" "https://www.murata.com/products/productdetail?partno=GRM155R61E105KE11%23"
			(at 0 0 90)
			(layer "B.Fab")
			(hide yes)
			(effects
				(font
					(size 1.27 1.27)
					(thickness 0.15)
				)
				(justify mirror)
			)
		)
		(property "Description" "SMD Multilayer Ceramic Capacitor, 1 µF, 25 V, 0402 [1005 Metric], ± 10%, X5R, GRM Series"
			(at 0 0 90)
			(layer "B.Fab")
			(hide yes)
			(effects
				(font
					(size 1.27 1.27)
					(thickness 0.15)
				)
				(justify mirror)
			)
		)
		(property "MPN" "GRM155R61E105KE11J"
			(at 0 0 90)
			(unlocked yes)
			(layer "B.Fab")
			(hide yes)
			(effects
				(font
					(size 1 1)
					(thickness 0.15)
				)
				(justify mirror)
			)
		)
		(property "Manufacturer" "Murata"
			(at 0 0 90)
			(unlocked yes)
			(layer "B.Fab")
			(hide yes)
			(effects
				(font
					(size 1 1)
					(thickness 0.15)
				)
				(justify mirror)
			)
		)
		(property "License" "Apache-2.0"
			(at 0 0 90)
			(unlocked yes)
			(layer "B.Fab")
			(hide yes)
			(effects
				(font
					(size 1 1)
					(thickness 0.15)
				)
				(justify mirror)
			)
		)
		(property "Author" "Antmicro"
			(at 0 0 90)
			(unlocked yes)
			(layer "B.Fab")
			(hide yes)
			(effects
				(font
					(size 1 1)
					(thickness 0.15)
				)
				(justify mirror)
			)
		)
		(property "Val" "1u"
			(at 0 0 90)
			(unlocked yes)
			(layer "B.Fab")
			(hide yes)
			(effects
				(font
					(size 1 1)
					(thickness 0.15)
				)
				(justify mirror)
			)
		)
		(property "Voltage" "25V"
			(at 0 0 90)
			(unlocked yes)
			(layer "B.Fab")
			(hide yes)
			(effects
				(font
					(size 1 1)
					(thickness 0.15)
				)
				(justify mirror)
			)
		)
		(property "Dielectric" "X5R"
			(at 0 0 90)
			(unlocked yes)
			(layer "B.Fab")
			(hide yes)
			(effects
				(font
					(size 1 1)
					(thickness 0.15)
				)
				(justify mirror)
			)
		)
		(sheetname "/X710-AT2 power/")
		(sheetfile "x710-at2-power.kicad_sch")
		(attr smd)
		(fp_rect
			(start -0.925 0.47)
			(end 0.925 -0.47)
			(stroke
				(width 0.05)
				(type default)
			)
			(fill no)
			(layer "B.CrtYd")
		)
		(fp_line
			(start 0.504 -0.248)
			(end -0.494 -0.248)
			(stroke
				(width 0.15)
				(type solid)
			)
			(layer "B.Fab")
		)
		(fp_line
			(start -0.494 -0.248)
			(end -0.494 0.25)
			(stroke
				(width 0.15)
				(type solid)
			)
			(layer "B.Fab")
		)
		(fp_line
			(start 0.504 0.25)
			(end 0.504 -0.248)
			(stroke
				(width 0.15)
				(type solid)
			)
			(layer "B.Fab")
		)
		(fp_line
			(start -0.494 0.25)
			(end 0.504 0.25)
			(stroke
				(width 0.15)
				(type solid)
			)
			(layer "B.Fab")
		)
		(pad "1" smd roundrect
			(at -0.48 0 90)
			(size 0.59 0.64)
			(layers "B.Cu" "B.Mask" "B.Paste")
			(roundrect_rratio 0.25)
			(net 28 "GND")
			(pintype "passive")
		)
		(pad "2" smd roundrect
			(at 0.48 0 90)
			(size 0.59 0.64)
			(layers "B.Cu" "B.Mask" "B.Paste")
			(roundrect_rratio 0.25)
			(net 9 "VCCD")
			(pintype "passive")
		)
	)
	(footprint "antmicro-footprints:C_0402_1005Metric"
		(layer "B.Cu")
		(at 90.225 96.45 90)
		(descr "Capacitor SMD 0402")
		(tags "capacitor SMD 0402")
		(property "Reference" "C109"
			(at 11.58 -0.432343 90)
			(layer "B.SilkS")
			(effects
				(font
					(size 0.7 0.7)
					(thickness 0.15)
				)
				(justify right top mirror)
			)
		)
		(property "Value" "C_1u_25V_0402"
			(at -1.022927 -2.155213 90)
			(layer "B.Fab")
			(hide yes)
			(effects
				(font
					(size 0.7 0.7)
					(thickness 0.15)
				)
				(justify right top mirror)
			)
		)
		(property "Datasheet" "https://www.murata.com/products/productdetail?partno=GRM155R61E105KE11%23"
			(at 0 0 90)
			(layer "B.Fab")
			(hide yes)
			(effects
				(font
					(size 1.27 1.27)
					(thickness 0.15)
				)
				(justify mirror)
			)
		)
		(property "Description" "SMD Multilayer Ceramic Capacitor, 1 µF, 25 V, 0402 [1005 Metric], ± 10%, X5R, GRM Series"
			(at 0 0 90)
			(layer "B.Fab")
			(hide yes)
			(effects
				(font
					(size 1.27 1.27)
					(thickness 0.15)
				)
				(justify mirror)
			)
		)
		(property "MPN" "GRM155R61E105KE11J"
			(at 0 0 90)
			(unlocked yes)
			(layer "B.Fab")
			(hide yes)
			(effects
				(font
					(size 1 1)
					(thickness 0.15)
				)
				(justify mirror)
			)
		)
		(property "Manufacturer" "Murata"
			(at 0 0 90)
			(unlocked yes)
			(layer "B.Fab")
			(hide yes)
			(effects
				(font
					(size 1 1)
					(thickness 0.15)
				)
				(justify mirror)
			)
		)
		(property "License" "Apache-2.0"
			(at 0 0 90)
			(unlocked yes)
			(layer "B.Fab")
			(hide yes)
			(effects
				(font
					(size 1 1)
					(thickness 0.15)
				)
				(justify mirror)
			)
		)
		(property "Author" "Antmicro"
			(at 0 0 90)
			(unlocked yes)
			(layer "B.Fab")
			(hide yes)
			(effects
				(font
					(size 1 1)
					(thickness 0.15)
				)
				(justify mirror)
			)
		)
		(property "Val" "1u"
			(at 0 0 90)
			(unlocked yes)
			(layer "B.Fab")
			(hide yes)
			(effects
				(font
					(size 1 1)
					(thickness 0.15)
				)
				(justify mirror)
			)
		)
		(property "Voltage" "25V"
			(at 0 0 90)
			(unlocked yes)
			(layer "B.Fab")
			(hide yes)
			(effects
				(font
					(size 1 1)
					(thickness 0.15)
				)
				(justify mirror)
			)
		)
		(property "Dielectric" "X5R"
			(at 0 0 90)
			(unlocked yes)
			(layer "B.Fab")
			(hide yes)
			(effects
				(font
					(size 1 1)
					(thickness 0.15)
				)
				(justify mirror)
			)
		)
		(sheetname "/X710-AT2 power/")
		(sheetfile "x710-at2-power.kicad_sch")
		(attr smd)
		(fp_rect
			(start -0.925 0.47)
			(end 0.925 -0.47)
			(stroke
				(width 0.05)
				(type default)
			)
			(fill no)
			(layer "B.CrtYd")
		)
		(fp_line
			(start 0.504 -0.248)
			(end -0.494 -0.248)
			(stroke
				(width 0.15)
				(type solid)
			)
			(layer "B.Fab")
		)
		(fp_line
			(start -0.494 -0.248)
			(end -0.494 0.25)
			(stroke
				(width 0.15)
				(type solid)
			)
			(layer "B.Fab")
		)
		(fp_line
			(start 0.504 0.25)
			(end 0.504 -0.248)
			(stroke
				(width 0.15)
				(type solid)
			)
			(layer "B.Fab")
		)
		(fp_line
			(start -0.494 0.25)
			(end 0.504 0.25)
			(stroke
				(width 0.15)
				(type solid)
			)
			(layer "B.Fab")
		)
		(pad "1" smd roundrect
			(at -0.48 0 90)
			(size 0.59 0.64)
			(layers "B.Cu" "B.Mask" "B.Paste")
			(roundrect_rratio 0.25)
			(net 28 "GND")
			(pintype "passive")
		)
		(pad "2" smd roundrect
			(at 0.48 0 90)
			(size 0.59 0.64)
			(layers "B.Cu" "B.Mask" "B.Paste")
			(roundrect_rratio 0.25)
			(net 9 "VCCD")
			(pintype "passive")
		)
	)
	(footprint "antmicro-footprints:C_0402_1005Metric"
		(layer "B.Cu")
		(at 75.479998 145.34 -90)
		(descr "Capacitor SMD 0402")
		(tags "capacitor SMD 0402")
		(property "Reference" "C48"
			(at -2.94 -0.490002 90)
			(layer "B.SilkS")
			(effects
				(font
					(size 0.7 0.7)
					(thickness 0.15)
				)
				(justify left bottom mirror)
			)
		)
		(property "Value" "C_470p_0402"
			(at -1.022927 -2.155213 90)
			(layer "B.Fab")
			(hide yes)
			(effects
				(font
					(size 0.7 0.7)
					(thickness 0.15)
				)
				(justify left bottom mirror)
			)
		)
		(property "Datasheet" "https://www.passivecomponent.com/wp-content/uploads/datasheet/WTC_MLCC_General_Purpose.pdf"
			(at 0 0 90)
			(layer "B.Fab")
			(hide yes)
			(effects
				(font
					(size 1.27 1.27)
					(thickness 0.15)
				)
				(justify mirror)
			)
		)
		(property "Description" "SMD Multilayer Ceramic Capacitor, General Purpose, 470 pF, 25 V, 0402 [1005 Metric], ± 10%, X7R"
			(at 0 0 90)
			(layer "B.Fab")
			(hide yes)
			(effects
				(font
					(size 1.27 1.27)
					(thickness 0.15)
				)
				(justify mirror)
			)
		)
		(property "MPN" "0402B471K250CT"
			(at 0 0 270)
			(unlocked yes)
			(layer "B.Fab")
			(hide yes)
			(effects
				(font
					(size 1 1)
					(thickness 0.15)
				)
				(justify mirror)
			)
		)
		(property "Manufacturer" "Walsin"
			(at 0 0 270)
			(unlocked yes)
			(layer "B.Fab")
			(hide yes)
			(effects
				(font
					(size 1 1)
					(thickness 0.15)
				)
				(justify mirror)
			)
		)
		(property "License" "Apache-2.0"
			(at 0 0 270)
			(unlocked yes)
			(layer "B.Fab")
			(hide yes)
			(effects
				(font
					(size 1 1)
					(thickness 0.15)
				)
				(justify mirror)
			)
		)
		(property "Author" "Antmicro"
			(at 0 0 270)
			(unlocked yes)
			(layer "B.Fab")
			(hide yes)
			(effects
				(font
					(size 1 1)
					(thickness 0.15)
				)
				(justify mirror)
			)
		)
		(property "Val" "470p"
			(at 0 0 270)
			(unlocked yes)
			(layer "B.Fab")
			(hide yes)
			(effects
				(font
					(size 1 1)
					(thickness 0.15)
				)
				(justify mirror)
			)
		)
		(property "Voltage" "25V"
			(at 0 0 270)
			(unlocked yes)
			(layer "B.Fab")
			(hide yes)
			(effects
				(font
					(size 1 1)
					(thickness 0.15)
				)
				(justify mirror)
			)
		)
		(property "Dielectric" "X7R"
			(at 0 0 270)
			(unlocked yes)
			(layer "B.Fab")
			(hide yes)
			(effects
				(font
					(size 1 1)
					(thickness 0.15)
				)
				(justify mirror)
			)
		)
		(sheetname "/2xRJ45/")
		(sheetfile "2xrj45.kicad_sch")
		(attr smd)
		(fp_rect
			(start -0.925 0.47)
			(end 0.925 -0.47)
			(stroke
				(width 0.05)
				(type default)
			)
			(fill no)
			(layer "B.CrtYd")
		)
		(fp_line
			(start -0.494 0.25)
			(end 0.504 0.25)
			(stroke
				(width 0.15)
				(type solid)
			)
			(layer "B.Fab")
		)
		(fp_line
			(start 0.504 0.25)
			(end 0.504 -0.248)
			(stroke
				(width 0.15)
				(type solid)
			)
			(layer "B.Fab")
		)
		(fp_line
			(start -0.494 -0.248)
			(end -0.494 0.25)
			(stroke
				(width 0.15)
				(type solid)
			)
			(layer "B.Fab")
		)
		(fp_line
			(start 0.504 -0.248)
			(end -0.494 -0.248)
			(stroke
				(width 0.15)
				(type solid)
			)
			(layer "B.Fab")
		)
		(pad "1" smd roundrect
			(at -0.48 0 270)
			(size 0.59 0.64)
			(layers "B.Cu" "B.Mask" "B.Paste")
			(roundrect_rratio 0.25)
			(net 28 "GND")
			(pintype "passive")
		)
		(pad "2" smd roundrect
			(at 0.48 0 270)
			(size 0.59 0.64)
			(layers "B.Cu" "B.Mask" "B.Paste")
			(roundrect_rratio 0.25)
			(net 52 "Net-(J3-LED_YG_Y-)")
			(pintype "passive")
		)
	)
	(footprint "antmicro-footprints:C_0402_1005Metric"
		(layer "B.Cu")
		(at 81.95 132.4 180)
		(descr "Capacitor SMD 0402")
		(tags "capacitor SMD 0402")
		(property "Reference" "C58"
			(at -0.721 -3.350999 0)
			(layer "B.SilkS")
			(effects
				(font
					(size 0.7 0.7)
					(thickness 0.15)
				)
				(justify left bottom mirror)
			)
		)
		(property "Value" "C_1u_25V_0402"
			(at -1.022927 -2.155213 0)
			(layer "B.Fab")
			(hide yes)
			(effects
				(font
					(size 0.7 0.7)
					(thickness 0.15)
				)
				(justify left bottom mirror)
			)
		)
		(property "Datasheet" "https://www.murata.com/products/productdetail?partno=GRM155R61E105KE11%23"
			(at 0 0 0)
			(layer "B.Fab")
			(hide yes)
			(effects
				(font
					(size 1.27 1.27)
					(thickness 0.15)
				)
				(justify mirror)
			)
		)
		(property "Description" "SMD Multilayer Ceramic Capacitor, 1 µF, 25 V, 0402 [1005 Metric], ± 10%, X5R, GRM Series"
			(at 0 0 0)
			(layer "B.Fab")
			(hide yes)
			(effects
				(font
					(size 1.27 1.27)
					(thickness 0.15)
				)
				(justify mirror)
			)
		)
		(property "MPN" "GRM155R61E105KE11J"
			(at 0 0 180)
			(unlocked yes)
			(layer "B.Fab")
			(hide yes)
			(effects
				(font
					(size 1 1)
					(thickness 0.15)
				)
				(justify mirror)
			)
		)
		(property "Manufacturer" "Murata"
			(at 0 0 180)
			(unlocked yes)
			(layer "B.Fab")
			(hide yes)
			(effects
				(font
					(size 1 1)
					(thickness 0.15)
				)
				(justify mirror)
			)
		)
		(property "License" "Apache-2.0"
			(at 0 0 180)
			(unlocked yes)
			(layer "B.Fab")
			(hide yes)
			(effects
				(font
					(size 1 1)
					(thickness 0.15)
				)
				(justify mirror)
			)
		)
		(property "Author" "Antmicro"
			(at 0 0 180)
			(unlocked yes)
			(layer "B.Fab")
			(hide yes)
			(effects
				(font
					(size 1 1)
					(thickness 0.15)
				)
				(justify mirror)
			)
		)
		(property "Val" "1u"
			(at 0 0 180)
			(unlocked yes)
			(layer "B.Fab")
			(hide yes)
			(effects
				(font
					(size 1 1)
					(thickness 0.15)
				)
				(justify mirror)
			)
		)
		(property "Voltage" "25V"
			(at 0 0 180)
			(unlocked yes)
			(layer "B.Fab")
			(hide yes)
			(effects
				(font
					(size 1 1)
					(thickness 0.15)
				)
				(justify mirror)
			)
		)
		(property "Dielectric" "X5R"
			(at 0 0 180)
			(unlocked yes)
			(layer "B.Fab")
			(hide yes)
			(effects
				(font
					(size 1 1)
					(thickness 0.15)
				)
				(justify mirror)
			)
		)
		(sheetname "/2xRJ45/")
		(sheetfile "2xrj45.kicad_sch")
		(attr smd)
		(fp_rect
			(start -0.925 0.47)
			(end 0.925 -0.47)
			(stroke
				(width 0.05)
				(type default)
			)
			(fill no)
			(layer "B.CrtYd")
		)
		(fp_line
			(start 0.504 0.25)
			(end 0.504 -0.248)
			(stroke
				(width 0.15)
				(type solid)
			)
			(layer "B.Fab")
		)
		(fp_line
			(start 0.504 -0.248)
			(end -0.494 -0.248)
			(stroke
				(width 0.15)
				(type solid)
			)
			(layer "B.Fab")
		)
		(fp_line
			(start -0.494 0.25)
			(end 0.504 0.25)
			(stroke
				(width 0.15)
				(type solid)
			)
			(layer "B.Fab")
		)
		(fp_line
			(start -0.494 -0.248)
			(end -0.494 0.25)
			(stroke
				(width 0.15)
				(type solid)
			)
			(layer "B.Fab")
		)
		(pad "1" smd roundrect
			(at -0.48 0 180)
			(size 0.59 0.64)
			(layers "B.Cu" "B.Mask" "B.Paste")
			(roundrect_rratio 0.25)
			(net 28 "GND")
			(pintype "passive")
		)
		(pad "2" smd roundrect
			(at 0.48 0 180)
			(size 0.59 0.64)
			(layers "B.Cu" "B.Mask" "B.Paste")
			(roundrect_rratio 0.25)
			(net 299 "/2xRJ45/P0_CT")
			(pintype "passive")
		)
	)
	(footprint "antmicro-footprints:C_0402_1005Metric"
		(layer "B.Cu")
		(at 88.225 102 90)
		(descr "Capacitor SMD 0402")
		(tags "capacitor SMD 0402")
		(property "Reference" "C89"
			(at 9.09 -0.447343 90)
			(layer "B.SilkS")
			(effects
				(font
					(size 0.7 0.7)
					(thickness 0.15)
				)
				(justify right top mirror)
			)
		)
		(property "Value" "C_1u_25V_0402"
			(at -1.022927 -2.155213 90)
			(layer "B.Fab")
			(hide yes)
			(effects
				(font
					(size 0.7 0.7)
					(thickness 0.15)
				)
				(justify right top mirror)
			)
		)
		(property "Datasheet" "https://www.murata.com/products/productdetail?partno=GRM155R61E105KE11%23"
			(at 0 0 90)
			(layer "B.Fab")
			(hide yes)
			(effects
				(font
					(size 1.27 1.27)
					(thickness 0.15)
				)
				(justify mirror)
			)
		)
		(property "Description" "SMD Multilayer Ceramic Capacitor, 1 µF, 25 V, 0402 [1005 Metric], ± 10%, X5R, GRM Series"
			(at 0 0 90)
			(layer "B.Fab")
			(hide yes)
			(effects
				(font
					(size 1.27 1.27)
					(thickness 0.15)
				)
				(justify mirror)
			)
		)
		(property "MPN" "GRM155R61E105KE11J"
			(at 0 0 90)
			(unlocked yes)
			(layer "B.Fab")
			(hide yes)
			(effects
				(font
					(size 1 1)
					(thickness 0.15)
				)
				(justify mirror)
			)
		)
		(property "Manufacturer" "Murata"
			(at 0 0 90)
			(unlocked yes)
			(layer "B.Fab")
			(hide yes)
			(effects
				(font
					(size 1 1)
					(thickness 0.15)
				)
				(justify mirror)
			)
		)
		(property "License" "Apache-2.0"
			(at 0 0 90)
			(unlocked yes)
			(layer "B.Fab")
			(hide yes)
			(effects
				(font
					(size 1 1)
					(thickness 0.15)
				)
				(justify mirror)
			)
		)
		(property "Author" "Antmicro"
			(at 0 0 90)
			(unlocked yes)
			(layer "B.Fab")
			(hide yes)
			(effects
				(font
					(size 1 1)
					(thickness 0.15)
				)
				(justify mirror)
			)
		)
		(property "Val" "1u"
			(at 0 0 90)
			(unlocked yes)
			(layer "B.Fab")
			(hide yes)
			(effects
				(font
					(size 1 1)
					(thickness 0.15)
				)
				(justify mirror)
			)
		)
		(property "Voltage" "25V"
			(at 0 0 90)
			(unlocked yes)
			(layer "B.Fab")
			(hide yes)
			(effects
				(font
					(size 1 1)
					(thickness 0.15)
				)
				(justify mirror)
			)
		)
		(property "Dielectric" "X5R"
			(at 0 0 90)
			(unlocked yes)
			(layer "B.Fab")
			(hide yes)
			(effects
				(font
					(size 1 1)
					(thickness 0.15)
				)
				(justify mirror)
			)
		)
		(sheetname "/X710-AT2 power/")
		(sheetfile "x710-at2-power.kicad_sch")
		(attr smd)
		(fp_rect
			(start -0.925 0.47)
			(end 0.925 -0.47)
			(stroke
				(width 0.05)
				(type default)
			)
			(fill no)
			(layer "B.CrtYd")
		)
		(fp_line
			(start 0.504 -0.248)
			(end -0.494 -0.248)
			(stroke
				(width 0.15)
				(type solid)
			)
			(layer "B.Fab")
		)
		(fp_line
			(start -0.494 -0.248)
			(end -0.494 0.25)
			(stroke
				(width 0.15)
				(type solid)
			)
			(layer "B.Fab")
		)
		(fp_line
			(start 0.504 0.25)
			(end 0.504 -0.248)
			(stroke
				(width 0.15)
				(type solid)
			)
			(layer "B.Fab")
		)
		(fp_line
			(start -0.494 0.25)
			(end 0.504 0.25)
			(stroke
				(width 0.15)
				(type solid)
			)
			(layer "B.Fab")
		)
		(pad "1" smd roundrect
			(at -0.48 0 90)
			(size 0.59 0.64)
			(layers "B.Cu" "B.Mask" "B.Paste")
			(roundrect_rratio 0.25)
			(net 28 "GND")
			(pintype "passive")
		)
		(pad "2" smd roundrect
			(at 0.48 0 90)
			(size 0.59 0.64)
			(layers "B.Cu" "B.Mask" "B.Paste")
			(roundrect_rratio 0.25)
			(net 1 "VCCA")
			(pintype "passive")
		)
	)
	(footprint "antmicro-footprints:R_0402_1005Metric"
		(layer "B.Cu")
		(at 96.45 105.1 180)
		(descr "Resistor SMD 0402")
		(tags "resistor SMD 0402")
		(property "Reference" "R86"
			(at -0.9 0.272222 0)
			(layer "B.SilkS")
			(effects
				(font
					(size 0.7 0.7)
					(thickness 0.15)
				)
				(justify right top mirror)
			)
		)
		(property "Value" "R_22R_0402"
			(at -1.011843 -1.772047 0)
			(layer "B.Fab")
			(hide yes)
			(effects
				(font
					(size 0.7 0.7)
					(thickness 0.15)
				)
				(justify left bottom mirror)
			)
		)
		(property "Datasheet" "https://www.bourns.com/docs/product-datasheets/cr.pdf"
			(at 0 0 0)
			(layer "B.Fab")
			(hide yes)
			(effects
				(font
					(size 1.27 1.27)
					(thickness 0.15)
				)
				(justify mirror)
			)
		)
		(property "Description" "SMD Chip Resistor, 22 ohm, ± 1%, 62.5 mW, 0402 [1005 Metric], Thick Film, General Purpose"
			(at 0 0 0)
			(layer "B.Fab")
			(hide yes)
			(effects
				(font
					(size 1.27 1.27)
					(thickness 0.15)
				)
				(justify mirror)
			)
		)
		(property "MPN" "CR0402-FX-22R0GLF"
			(at 0 0 180)
			(unlocked yes)
			(layer "B.Fab")
			(hide yes)
			(effects
				(font
					(size 1 1)
					(thickness 0.15)
				)
				(justify mirror)
			)
		)
		(property "Manufacturer" "Bourns"
			(at 0 0 180)
			(unlocked yes)
			(layer "B.Fab")
			(hide yes)
			(effects
				(font
					(size 1 1)
					(thickness 0.15)
				)
				(justify mirror)
			)
		)
		(property "License" "Apache-2.0"
			(at 0 0 180)
			(unlocked yes)
			(layer "B.Fab")
			(hide yes)
			(effects
				(font
					(size 1 1)
					(thickness 0.15)
				)
				(justify mirror)
			)
		)
		(property "Author" "Antmicro"
			(at 0 0 180)
			(unlocked yes)
			(layer "B.Fab")
			(hide yes)
			(effects
				(font
					(size 1 1)
					(thickness 0.15)
				)
				(justify mirror)
			)
		)
		(property "Val" "22R"
			(at 0 0 180)
			(unlocked yes)
			(layer "B.Fab")
			(hide yes)
			(effects
				(font
					(size 1 1)
					(thickness 0.15)
				)
				(justify mirror)
			)
		)
		(property "Tolerance" "1%"
			(at 0 0 180)
			(unlocked yes)
			(layer "B.Fab")
			(hide yes)
			(effects
				(font
					(size 1 1)
					(thickness 0.15)
				)
				(justify mirror)
			)
		)
		(sheetname "/X710-AT2 Misc/")
		(sheetfile "x710-at2-mics.kicad_sch")
		(attr smd)
		(fp_rect
			(start -0.925 0.47)
			(end 0.925 -0.47)
			(stroke
				(width 0.05)
				(type default)
			)
			(fill no)
			(layer "B.CrtYd")
		)
		(fp_rect
			(start -0.5 0.25)
			(end 0.5 -0.25)
			(stroke
				(width 0.15)
				(type solid)
			)
			(fill no)
			(layer "B.Fab")
		)
		(pad "1" smd roundrect
			(at -0.48 0 180)
			(size 0.59 0.64)
			(layers "B.Cu" "B.Mask" "B.Paste")
			(roundrect_rratio 0.25)
			(net 360 "/X710-AT2 Misc/NCSI.RXD_1")
			(pintype "passive")
		)
		(pad "2" smd roundrect
			(at 0.48 0 180)
			(size 0.59 0.64)
			(layers "B.Cu" "B.Mask" "B.Paste")
			(roundrect_rratio 0.25)
			(net 162 "Net-(U9D-NCSI_RXD_1)")
			(pintype "passive")
		)
	)
	(footprint "antmicro-footprints:R_0402_1005Metric"
		(layer "B.Cu")
		(at 84.225 98.3 -90)
		(descr "Resistor SMD 0402")
		(tags "resistor SMD 0402")
		(property "Reference" "R139"
			(at -13.44 -0.297657 90)
			(layer "B.SilkS")
			(effects
				(font
					(size 0.7 0.7)
					(thickness 0.15)
				)
				(justify left bottom mirror)
			)
		)
		(property "Value" "R_100R_0402"
			(at -1.011843 -1.772046 90)
			(layer "B.Fab")
			(hide yes)
			(effects
				(font
					(size 0.7 0.7)
					(thickness 0.15)
				)
				(justify left bottom mirror)
			)
		)
		(property "Datasheet" "https://www.bourns.com/docs/product-datasheets/cr.pdf"
			(at 0 0 90)
			(layer "B.Fab")
			(hide yes)
			(effects
				(font
					(size 1.27 1.27)
					(thickness 0.15)
				)
				(justify mirror)
			)
		)
		(property "Description" "SMD Chip Resistor, 100 ohm, ± 1%, 62.5 mW, 0402 [1005 Metric], Thick Film, General Purpose"
			(at 0 0 90)
			(layer "B.Fab")
			(hide yes)
			(effects
				(font
					(size 1.27 1.27)
					(thickness 0.15)
				)
				(justify mirror)
			)
		)
		(property "MPN" "CR0402-FX-1000GLF"
			(at 0 0 270)
			(unlocked yes)
			(layer "B.Fab")
			(hide yes)
			(effects
				(font
					(size 1 1)
					(thickness 0.15)
				)
				(justify mirror)
			)
		)
		(property "Manufacturer" "Bourns"
			(at 0 0 270)
			(unlocked yes)
			(layer "B.Fab")
			(hide yes)
			(effects
				(font
					(size 1 1)
					(thickness 0.15)
				)
				(justify mirror)
			)
		)
		(property "License" "Apache-2.0"
			(at 0 0 270)
			(unlocked yes)
			(layer "B.Fab")
			(hide yes)
			(effects
				(font
					(size 1 1)
					(thickness 0.15)
				)
				(justify mirror)
			)
		)
		(property "Author" "Antmicro"
			(at 0 0 270)
			(unlocked yes)
			(layer "B.Fab")
			(hide yes)
			(effects
				(font
					(size 1 1)
					(thickness 0.15)
				)
				(justify mirror)
			)
		)
		(property "Val" "100R"
			(at 0 0 270)
			(unlocked yes)
			(layer "B.Fab")
			(hide yes)
			(effects
				(font
					(size 1 1)
					(thickness 0.15)
				)
				(justify mirror)
			)
		)
		(property "Tolerance" "1%"
			(at 0 0 270)
			(unlocked yes)
			(layer "B.Fab")
			(hide yes)
			(effects
				(font
					(size 1 1)
					(thickness 0.15)
				)
				(justify mirror)
			)
		)
		(sheetname "/X710-AT2 RSVD/")
		(sheetfile "x710-at2-rsvd.kicad_sch")
		(attr smd)
		(fp_rect
			(start -0.925 0.47)
			(end 0.925 -0.47)
			(stroke
				(width 0.05)
				(type default)
			)
			(fill no)
			(layer "B.CrtYd")
		)
		(fp_rect
			(start -0.5 0.25)
			(end 0.5 -0.25)
			(stroke
				(width 0.15)
				(type solid)
			)
			(fill no)
			(layer "B.Fab")
		)
		(pad "1" smd roundrect
			(at -0.48 0 270)
			(size 0.59 0.64)
			(layers "B.Cu" "B.Mask" "B.Paste")
			(roundrect_rratio 0.25)
			(net 28 "GND")
			(pintype "passive")
		)
		(pad "2" smd roundrect
			(at 0.48 0 270)
			(size 0.59 0.64)
			(layers "B.Cu" "B.Mask" "B.Paste")
			(roundrect_rratio 0.25)
			(net 127 "/X710-AT2 RSVD/RSVDP22_VSS")
			(pintype "passive")
		)
	)
	(footprint "antmicro-footprints:C_0402_1005Metric"
		(layer "B.Cu")
		(at 88.225 100.15 90)
		(descr "Capacitor SMD 0402")
		(tags "capacitor SMD 0402")
		(property "Reference" "C91"
			(at 9.87 -0.409843 90)
			(layer "B.SilkS")
			(effects
				(font
					(size 0.7 0.7)
					(thickness 0.15)
				)
				(justify right top mirror)
			)
		)
		(property "Value" "C_1u_25V_0402"
			(at -1.022927 -2.155213 90)
			(layer "B.Fab")
			(hide yes)
			(effects
				(font
					(size 0.7 0.7)
					(thickness 0.15)
				)
				(justify right top mirror)
			)
		)
		(property "Datasheet" "https://www.murata.com/products/productdetail?partno=GRM155R61E105KE11%23"
			(at 0 0 90)
			(layer "B.Fab")
			(hide yes)
			(effects
				(font
					(size 1.27 1.27)
					(thickness 0.15)
				)
				(justify mirror)
			)
		)
		(property "Description" "SMD Multilayer Ceramic Capacitor, 1 µF, 25 V, 0402 [1005 Metric], ± 10%, X5R, GRM Series"
			(at 0 0 90)
			(layer "B.Fab")
			(hide yes)
			(effects
				(font
					(size 1.27 1.27)
					(thickness 0.15)
				)
				(justify mirror)
			)
		)
		(property "MPN" "GRM155R61E105KE11J"
			(at 0 0 90)
			(unlocked yes)
			(layer "B.Fab")
			(hide yes)
			(effects
				(font
					(size 1 1)
					(thickness 0.15)
				)
				(justify mirror)
			)
		)
		(property "Manufacturer" "Murata"
			(at 0 0 90)
			(unlocked yes)
			(layer "B.Fab")
			(hide yes)
			(effects
				(font
					(size 1 1)
					(thickness 0.15)
				)
				(justify mirror)
			)
		)
		(property "License" "Apache-2.0"
			(at 0 0 90)
			(unlocked yes)
			(layer "B.Fab")
			(hide yes)
			(effects
				(font
					(size 1 1)
					(thickness 0.15)
				)
				(justify mirror)
			)
		)
		(property "Author" "Antmicro"
			(at 0 0 90)
			(unlocked yes)
			(layer "B.Fab")
			(hide yes)
			(effects
				(font
					(size 1 1)
					(thickness 0.15)
				)
				(justify mirror)
			)
		)
		(property "Val" "1u"
			(at 0 0 90)
			(unlocked yes)
			(layer "B.Fab")
			(hide yes)
			(effects
				(font
					(size 1 1)
					(thickness 0.15)
				)
				(justify mirror)
			)
		)
		(property "Voltage" "25V"
			(at 0 0 90)
			(unlocked yes)
			(layer "B.Fab")
			(hide yes)
			(effects
				(font
					(size 1 1)
					(thickness 0.15)
				)
				(justify mirror)
			)
		)
		(property "Dielectric" "X5R"
			(at 0 0 90)
			(unlocked yes)
			(layer "B.Fab")
			(hide yes)
			(effects
				(font
					(size 1 1)
					(thickness 0.15)
				)
				(justify mirror)
			)
		)
		(sheetname "/X710-AT2 power/")
		(sheetfile "x710-at2-power.kicad_sch")
		(attr smd)
		(fp_rect
			(start -0.925 0.47)
			(end 0.925 -0.47)
			(stroke
				(width 0.05)
				(type default)
			)
			(fill no)
			(layer "B.CrtYd")
		)
		(fp_line
			(start 0.504 -0.248)
			(end -0.494 -0.248)
			(stroke
				(width 0.15)
				(type solid)
			)
			(layer "B.Fab")
		)
		(fp_line
			(start -0.494 -0.248)
			(end -0.494 0.25)
			(stroke
				(width 0.15)
				(type solid)
			)
			(layer "B.Fab")
		)
		(fp_line
			(start 0.504 0.25)
			(end 0.504 -0.248)
			(stroke
				(width 0.15)
				(type solid)
			)
			(layer "B.Fab")
		)
		(fp_line
			(start -0.494 0.25)
			(end 0.504 0.25)
			(stroke
				(width 0.15)
				(type solid)
			)
			(layer "B.Fab")
		)
		(pad "1" smd roundrect
			(at -0.48 0 90)
			(size 0.59 0.64)
			(layers "B.Cu" "B.Mask" "B.Paste")
			(roundrect_rratio 0.25)
			(net 28 "GND")
			(pintype "passive")
		)
		(pad "2" smd roundrect
			(at 0.48 0 90)
			(size 0.59 0.64)
			(layers "B.Cu" "B.Mask" "B.Paste")
			(roundrect_rratio 0.25)
			(net 1 "VCCA")
			(pintype "passive")
		)
	)
	(footprint "antmicro-footprints:C_0402_1005Metric"
		(layer "B.Cu")
		(at 86.225 96.45 90)
		(descr "Capacitor SMD 0402")
		(tags "capacitor SMD 0402")
		(property "Reference" "C105"
			(at 11.58 -0.432343 90)
			(layer "B.SilkS")
			(effects
				(font
					(size 0.7 0.7)
					(thickness 0.15)
				)
				(justify right top mirror)
			)
		)
		(property "Value" "C_1u_25V_0402"
			(at -1.022927 -2.155213 90)
			(layer "B.Fab")
			(hide yes)
			(effects
				(font
					(size 0.7 0.7)
					(thickness 0.15)
				)
				(justify right top mirror)
			)
		)
		(property "Datasheet" "https://www.murata.com/products/productdetail?partno=GRM155R61E105KE11%23"
			(at 0 0 90)
			(layer "B.Fab")
			(hide yes)
			(effects
				(font
					(size 1.27 1.27)
					(thickness 0.15)
				)
				(justify mirror)
			)
		)
		(property "Description" "SMD Multilayer Ceramic Capacitor, 1 µF, 25 V, 0402 [1005 Metric], ± 10%, X5R, GRM Series"
			(at 0 0 90)
			(layer "B.Fab")
			(hide yes)
			(effects
				(font
					(size 1.27 1.27)
					(thickness 0.15)
				)
				(justify mirror)
			)
		)
		(property "MPN" "GRM155R61E105KE11J"
			(at 0 0 90)
			(unlocked yes)
			(layer "B.Fab")
			(hide yes)
			(effects
				(font
					(size 1 1)
					(thickness 0.15)
				)
				(justify mirror)
			)
		)
		(property "Manufacturer" "Murata"
			(at 0 0 90)
			(unlocked yes)
			(layer "B.Fab")
			(hide yes)
			(effects
				(font
					(size 1 1)
					(thickness 0.15)
				)
				(justify mirror)
			)
		)
		(property "License" "Apache-2.0"
			(at 0 0 90)
			(unlocked yes)
			(layer "B.Fab")
			(hide yes)
			(effects
				(font
					(size 1 1)
					(thickness 0.15)
				)
				(justify mirror)
			)
		)
		(property "Author" "Antmicro"
			(at 0 0 90)
			(unlocked yes)
			(layer "B.Fab")
			(hide yes)
			(effects
				(font
					(size 1 1)
					(thickness 0.15)
				)
				(justify mirror)
			)
		)
		(property "Val" "1u"
			(at 0 0 90)
			(unlocked yes)
			(layer "B.Fab")
			(hide yes)
			(effects
				(font
					(size 1 1)
					(thickness 0.15)
				)
				(justify mirror)
			)
		)
		(property "Voltage" "25V"
			(at 0 0 90)
			(unlocked yes)
			(layer "B.Fab")
			(hide yes)
			(effects
				(font
					(size 1 1)
					(thickness 0.15)
				)
				(justify mirror)
			)
		)
		(property "Dielectric" "X5R"
			(at 0 0 90)
			(unlocked yes)
			(layer "B.Fab")
			(hide yes)
			(effects
				(font
					(size 1 1)
					(thickness 0.15)
				)
				(justify mirror)
			)
		)
		(sheetname "/X710-AT2 power/")
		(sheetfile "x710-at2-power.kicad_sch")
		(attr smd)
		(fp_rect
			(start -0.925 0.47)
			(end 0.925 -0.47)
			(stroke
				(width 0.05)
				(type default)
			)
			(fill no)
			(layer "B.CrtYd")
		)
		(fp_line
			(start 0.504 -0.248)
			(end -0.494 -0.248)
			(stroke
				(width 0.15)
				(type solid)
			)
			(layer "B.Fab")
		)
		(fp_line
			(start -0.494 -0.248)
			(end -0.494 0.25)
			(stroke
				(width 0.15)
				(type solid)
			)
			(layer "B.Fab")
		)
		(fp_line
			(start 0.504 0.25)
			(end 0.504 -0.248)
			(stroke
				(width 0.15)
				(type solid)
			)
			(layer "B.Fab")
		)
		(fp_line
			(start -0.494 0.25)
			(end 0.504 0.25)
			(stroke
				(width 0.15)
				(type solid)
			)
			(layer "B.Fab")
		)
		(pad "1" smd roundrect
			(at -0.48 0 90)
			(size 0.59 0.64)
			(layers "B.Cu" "B.Mask" "B.Paste")
			(roundrect_rratio 0.25)
			(net 28 "GND")
			(pintype "passive")
		)
		(pad "2" smd roundrect
			(at 0.48 0 90)
			(size 0.59 0.64)
			(layers "B.Cu" "B.Mask" "B.Paste")
			(roundrect_rratio 0.25)
			(net 9 "VCCD")
			(pintype "passive")
		)
	)
	(footprint "antmicro-footprints:C_0402_1005Metric"
		(layer "B.Cu")
		(at 92.8 113.610001 180)
		(descr "Capacitor SMD 0402")
		(tags "capacitor SMD 0402")
		(property "Reference" "C75"
			(at -1.18 -2.539999 0)
			(layer "B.SilkS")
			(effects
				(font
					(size 0.7 0.7)
					(thickness 0.15)
				)
				(justify left bottom mirror)
			)
		)
		(property "Value" "C_100n_0402"
			(at -1.022927 -2.155213 0)
			(layer "B.Fab")
			(hide yes)
			(effects
				(font
					(size 0.7 0.7)
					(thickness 0.15)
				)
				(justify left bottom mirror)
			)
		)
		(property "Datasheet" "https://www.murata.com/products/productdetail?partno=GRM155R61H104KE14%23"
			(at 0 0 0)
			(layer "B.Fab")
			(hide yes)
			(effects
				(font
					(size 1.27 1.27)
					(thickness 0.15)
				)
				(justify mirror)
			)
		)
		(property "Description" "SMD Multilayer Ceramic Capacitor, 0.1 µF, 50 V, 0402 [1005 Metric], ± 10%, X5R, GRM Series"
			(at 0 0 0)
			(layer "B.Fab")
			(hide yes)
			(effects
				(font
					(size 1.27 1.27)
					(thickness 0.15)
				)
				(justify mirror)
			)
		)
		(property "MPN" "GRM155R61H104KE14D"
			(at 0 0 180)
			(unlocked yes)
			(layer "B.Fab")
			(hide yes)
			(effects
				(font
					(size 1 1)
					(thickness 0.15)
				)
				(justify mirror)
			)
		)
		(property "Val" "100n"
			(at 0 0 180)
			(unlocked yes)
			(layer "B.Fab")
			(hide yes)
			(effects
				(font
					(size 1 1)
					(thickness 0.15)
				)
				(justify mirror)
			)
		)
		(property "Voltage" "50V"
			(at 0 0 180)
			(unlocked yes)
			(layer "B.Fab")
			(hide yes)
			(effects
				(font
					(size 1 1)
					(thickness 0.15)
				)
				(justify mirror)
			)
		)
		(property "Dielectric" "X5R"
			(at 0 0 180)
			(unlocked yes)
			(layer "B.Fab")
			(hide yes)
			(effects
				(font
					(size 1 1)
					(thickness 0.15)
				)
				(justify mirror)
			)
		)
		(property "Manufacturer" "Murata"
			(at 0 0 180)
			(unlocked yes)
			(layer "B.Fab")
			(hide yes)
			(effects
				(font
					(size 1 1)
					(thickness 0.15)
				)
				(justify mirror)
			)
		)
		(property "License" "Apache-2.0"
			(at 0 0 180)
			(unlocked yes)
			(layer "B.Fab")
			(hide yes)
			(effects
				(font
					(size 1 1)
					(thickness 0.15)
				)
				(justify mirror)
			)
		)
		(property "Author" "Antmicro"
			(at 0 0 180)
			(unlocked yes)
			(layer "B.Fab")
			(hide yes)
			(effects
				(font
					(size 1 1)
					(thickness 0.15)
				)
				(justify mirror)
			)
		)
		(sheetname "/X710-AT2 Misc/")
		(sheetfile "x710-at2-mics.kicad_sch")
		(attr smd)
		(fp_rect
			(start -0.925 0.47)
			(end 0.925 -0.47)
			(stroke
				(width 0.05)
				(type default)
			)
			(fill no)
			(layer "B.CrtYd")
		)
		(fp_line
			(start 0.504 0.25)
			(end 0.504 -0.248)
			(stroke
				(width 0.15)
				(type solid)
			)
			(layer "B.Fab")
		)
		(fp_line
			(start 0.504 -0.248)
			(end -0.494 -0.248)
			(stroke
				(width 0.15)
				(type solid)
			)
			(layer "B.Fab")
		)
		(fp_line
			(start -0.494 0.25)
			(end 0.504 0.25)
			(stroke
				(width 0.15)
				(type solid)
			)
			(layer "B.Fab")
		)
		(fp_line
			(start -0.494 -0.248)
			(end -0.494 0.25)
			(stroke
				(width 0.15)
				(type solid)
			)
			(layer "B.Fab")
		)
		(pad "1" smd roundrect
			(at -0.48 0 180)
			(size 0.59 0.64)
			(layers "B.Cu" "B.Mask" "B.Paste")
			(roundrect_rratio 0.25)
			(net 28 "GND")
			(pintype "passive")
		)
		(pad "2" smd roundrect
			(at 0.48 0 180)
			(size 0.59 0.64)
			(layers "B.Cu" "B.Mask" "B.Paste")
			(roundrect_rratio 0.25)
			(net 7 "+3V3")
			(pintype "passive")
		)
	)
	(footprint "antmicro-footprints:C_0402_1005Metric"
		(layer "B.Cu")
		(at 73.48 145.339998 -90)
		(descr "Capacitor SMD 0402")
		(tags "capacitor SMD 0402")
		(property "Reference" "C49"
			(at -2.939998 -0.46 90)
			(layer "B.SilkS")
			(effects
				(font
					(size 0.7 0.7)
					(thickness 0.15)
				)
				(justify left bottom mirror)
			)
		)
		(property "Value" "C_470p_0402"
			(at -1.022927 -2.155213 90)
			(layer "B.Fab")
			(hide yes)
			(effects
				(font
					(size 0.7 0.7)
					(thickness 0.15)
				)
				(justify left bottom mirror)
			)
		)
		(property "Datasheet" "https://www.passivecomponent.com/wp-content/uploads/datasheet/WTC_MLCC_General_Purpose.pdf"
			(at 0 0 90)
			(layer "B.Fab")
			(hide yes)
			(effects
				(font
					(size 1.27 1.27)
					(thickness 0.15)
				)
				(justify mirror)
			)
		)
		(property "Description" "SMD Multilayer Ceramic Capacitor, General Purpose, 470 pF, 25 V, 0402 [1005 Metric], ± 10%, X7R"
			(at 0 0 90)
			(layer "B.Fab")
			(hide yes)
			(effects
				(font
					(size 1.27 1.27)
					(thickness 0.15)
				)
				(justify mirror)
			)
		)
		(property "MPN" "0402B471K250CT"
			(at 0 0 270)
			(unlocked yes)
			(layer "B.Fab")
			(hide yes)
			(effects
				(font
					(size 1 1)
					(thickness 0.15)
				)
				(justify mirror)
			)
		)
		(property "Manufacturer" "Walsin"
			(at 0 0 270)
			(unlocked yes)
			(layer "B.Fab")
			(hide yes)
			(effects
				(font
					(size 1 1)
					(thickness 0.15)
				)
				(justify mirror)
			)
		)
		(property "License" "Apache-2.0"
			(at 0 0 270)
			(unlocked yes)
			(layer "B.Fab")
			(hide yes)
			(effects
				(font
					(size 1 1)
					(thickness 0.15)
				)
				(justify mirror)
			)
		)
		(property "Author" "Antmicro"
			(at 0 0 270)
			(unlocked yes)
			(layer "B.Fab")
			(hide yes)
			(effects
				(font
					(size 1 1)
					(thickness 0.15)
				)
				(justify mirror)
			)
		)
		(property "Val" "470p"
			(at 0 0 270)
			(unlocked yes)
			(layer "B.Fab")
			(hide yes)
			(effects
				(font
					(size 1 1)
					(thickness 0.15)
				)
				(justify mirror)
			)
		)
		(property "Voltage" "25V"
			(at 0 0 270)
			(unlocked yes)
			(layer "B.Fab")
			(hide yes)
			(effects
				(font
					(size 1 1)
					(thickness 0.15)
				)
				(justify mirror)
			)
		)
		(property "Dielectric" "X7R"
			(at 0 0 270)
			(unlocked yes)
			(layer "B.Fab")
			(hide yes)
			(effects
				(font
					(size 1 1)
					(thickness 0.15)
				)
				(justify mirror)
			)
		)
		(sheetname "/2xRJ45/")
		(sheetfile "2xrj45.kicad_sch")
		(attr smd)
		(fp_rect
			(start -0.925 0.47)
			(end 0.925 -0.47)
			(stroke
				(width 0.05)
				(type default)
			)
			(fill no)
			(layer "B.CrtYd")
		)
		(fp_line
			(start -0.494 0.25)
			(end 0.504 0.25)
			(stroke
				(width 0.15)
				(type solid)
			)
			(layer "B.Fab")
		)
		(fp_line
			(start 0.504 0.25)
			(end 0.504 -0.248)
			(stroke
				(width 0.15)
				(type solid)
			)
			(layer "B.Fab")
		)
		(fp_line
			(start -0.494 -0.248)
			(end -0.494 0.25)
			(stroke
				(width 0.15)
				(type solid)
			)
			(layer "B.Fab")
		)
		(fp_line
			(start 0.504 -0.248)
			(end -0.494 -0.248)
			(stroke
				(width 0.15)
				(type solid)
			)
			(layer "B.Fab")
		)
		(pad "1" smd roundrect
			(at -0.48 0 270)
			(size 0.59 0.64)
			(layers "B.Cu" "B.Mask" "B.Paste")
			(roundrect_rratio 0.25)
			(net 28 "GND")
			(pintype "passive")
		)
		(pad "2" smd roundrect
			(at 0.48 0 270)
			(size 0.59 0.64)
			(layers "B.Cu" "B.Mask" "B.Paste")
			(roundrect_rratio 0.25)
			(net 53 "Net-(J3-LED_YG_G-)")
			(pintype "passive")
		)
	)
	(footprint "antmicro-footprints:TP_SMD_0.75mm"
		(layer "B.Cu")
		(at 87.725 107.65 90)
		(property "Reference" "TP11"
			(at -2.13 0.505 90)
			(layer "B.SilkS")
			(effects
				(font
					(size 0.7 0.7)
					(thickness 0.15)
				)
				(justify right top mirror)
			)
		)
		(property "Value" "TP_0.75mm_SMD"
			(at 0 -1.2 90)
			(layer "B.Fab")
			(hide yes)
			(effects
				(font
					(size 0.7 0.7)
					(thickness 0.15)
				)
				(justify right top mirror)
			)
		)
		(property "Description" "SMT test point"
			(at 0 0 90)
			(layer "B.Fab")
			(hide yes)
			(effects
				(font
					(size 1.27 1.27)
					(thickness 0.15)
				)
				(justify mirror)
			)
		)
		(property "MPN" ""
			(at 0 0 90)
			(unlocked yes)
			(layer "B.Fab")
			(hide yes)
			(effects
				(font
					(size 1 1)
					(thickness 0.15)
				)
				(justify mirror)
			)
		)
		(property "Manufacturer" ""
			(at 0 0 90)
			(unlocked yes)
			(layer "B.Fab")
			(hide yes)
			(effects
				(font
					(size 1 1)
					(thickness 0.15)
				)
				(justify mirror)
			)
		)
		(property "Author" "Antmicro"
			(at 0 0 90)
			(unlocked yes)
			(layer "B.Fab")
			(hide yes)
			(effects
				(font
					(size 1 1)
					(thickness 0.15)
				)
				(justify mirror)
			)
		)
		(property "License" "Apache-2.0"
			(at 0 0 90)
			(unlocked yes)
			(layer "B.Fab")
			(hide yes)
			(effects
				(font
					(size 1 1)
					(thickness 0.15)
				)
				(justify mirror)
			)
		)
		(sheetname "/X710-AT2 Misc/")
		(sheetfile "x710-at2-mics.kicad_sch")
		(attr exclude_from_pos_files exclude_from_bom)
		(fp_circle
			(center 0 0)
			(end 0.475 0)
			(stroke
				(width 0.05)
				(type default)
			)
			(fill no)
			(layer "B.CrtYd")
		)
		(pad "1" smd circle
			(at 0 0 90)
			(size 0.75 0.75)
			(layers "B.Cu" "B.Mask")
			(net 135 "/X710-AT2 Misc/PHY_TMS")
			(pinfunction "1")
			(pintype "passive")
		)
	)
	(footprint "antmicro-footprints:TP_SMD_0.75mm"
		(layer "B.Cu")
		(at 61.925 84.775001 180)
		(property "Reference" "TP38"
			(at 0 0.6 0)
			(layer "B.SilkS")
			(hide yes)
			(effects
				(font
					(size 0.7 0.7)
					(thickness 0.15)
				)
				(justify left bottom mirror)
			)
		)
		(property "Value" "TP_0.75mm_SMD"
			(at 0 -1.2 0)
			(layer "B.Fab")
			(hide yes)
			(effects
				(font
					(size 0.7 0.7)
					(thickness 0.15)
				)
				(justify left bottom mirror)
			)
		)
		(property "Description" "SMT test point"
			(at 0 0 0)
			(layer "B.Fab")
			(hide yes)
			(effects
				(font
					(size 1.27 1.27)
					(thickness 0.15)
				)
				(justify mirror)
			)
		)
		(property "MPN" ""
			(at 0 0 0)
			(unlocked yes)
			(layer "B.Fab")
			(hide yes)
			(effects
				(font
					(size 1 1)
					(thickness 0.15)
				)
				(justify mirror)
			)
		)
		(property "Manufacturer" ""
			(at 0 0 0)
			(unlocked yes)
			(layer "B.Fab")
			(hide yes)
			(effects
				(font
					(size 1 1)
					(thickness 0.15)
				)
				(justify mirror)
			)
		)
		(property "Author" "Antmicro"
			(at 0 0 0)
			(unlocked yes)
			(layer "B.Fab")
			(hide yes)
			(effects
				(font
					(size 1 1)
					(thickness 0.15)
				)
				(justify mirror)
			)
		)
		(property "License" "Apache-2.0"
			(at 0 0 0)
			(unlocked yes)
			(layer "B.Fab")
			(hide yes)
			(effects
				(font
					(size 1 1)
					(thickness 0.15)
				)
				(justify mirror)
			)
		)
		(sheetname "/Power/")
		(sheetfile "power.kicad_sch")
		(attr exclude_from_pos_files exclude_from_bom)
		(fp_circle
			(center 0 0)
			(end 0.475 0)
			(stroke
				(width 0.05)
				(type default)
			)
			(fill no)
			(layer "B.CrtYd")
		)
		(pad "1" smd circle
			(at 0 0 180)
			(size 0.75 0.75)
			(layers "B.Cu" "B.Mask")
			(net 303 "/Power/+VCCD_OUT")
			(pinfunction "1")
			(pintype "passive")
		)
	)
	(footprint "antmicro-footprints:TP_SMD_0.75mm"
		(layer "B.Cu")
		(at 89.3 106.49 90)
		(property "Reference" "TP12"
			(at 0.87 0.36 180)
			(layer "B.SilkS")
			(effects
				(font
					(size 0.7 0.7)
					(thickness 0.15)
				)
				(justify right top mirror)
			)
		)
		(property "Value" "TP_0.75mm_SMD"
			(at 0 -1.2 90)
			(layer "B.Fab")
			(hide yes)
			(effects
				(font
					(size 0.7 0.7)
					(thickness 0.15)
				)
				(justify right top mirror)
			)
		)
		(property "Description" "SMT test point"
			(at 0 0 90)
			(layer "B.Fab")
			(hide yes)
			(effects
				(font
					(size 1.27 1.27)
					(thickness 0.15)
				)
				(justify mirror)
			)
		)
		(property "MPN" ""
			(at 0 0 90)
			(unlocked yes)
			(layer "B.Fab")
			(hide yes)
			(effects
				(font
					(size 1 1)
					(thickness 0.15)
				)
				(justify mirror)
			)
		)
		(property "Manufacturer" ""
			(at 0 0 90)
			(unlocked yes)
			(layer "B.Fab")
			(hide yes)
			(effects
				(font
					(size 1 1)
					(thickness 0.15)
				)
				(justify mirror)
			)
		)
		(property "Author" "Antmicro"
			(at 0 0 90)
			(unlocked yes)
			(layer "B.Fab")
			(hide yes)
			(effects
				(font
					(size 1 1)
					(thickness 0.15)
				)
				(justify mirror)
			)
		)
		(property "License" "Apache-2.0"
			(at 0 0 90)
			(unlocked yes)
			(layer "B.Fab")
			(hide yes)
			(effects
				(font
					(size 1 1)
					(thickness 0.15)
				)
				(justify mirror)
			)
		)
		(sheetname "/X710-AT2 Misc/")
		(sheetfile "x710-at2-mics.kicad_sch")
		(attr exclude_from_pos_files exclude_from_bom)
		(fp_circle
			(center 0 0)
			(end 0.475 0)
			(stroke
				(width 0.05)
				(type default)
			)
			(fill no)
			(layer "B.CrtYd")
		)
		(pad "1" smd circle
			(at 0 0 90)
			(size 0.75 0.75)
			(layers "B.Cu" "B.Mask")
			(net 136 "/X710-AT2 Misc/PHY_TDI")
			(pinfunction "1")
			(pintype "passive")
		)
	)
	(footprint "antmicro-footprints:C_0402_1005Metric"
		(layer "B.Cu")
		(at 86.225 102 90)
		(descr "Capacitor SMD 0402")
		(tags "capacitor SMD 0402")
		(property "Reference" "C116"
			(at 9.09 -0.447343 90)
			(layer "B.SilkS")
			(effects
				(font
					(size 0.7 0.7)
					(thickness 0.15)
				)
				(justify right top mirror)
			)
		)
		(property "Value" "C_1u_25V_0402"
			(at -1.022927 -2.155214 90)
			(layer "B.Fab")
			(hide yes)
			(effects
				(font
					(size 0.7 0.7)
					(thickness 0.15)
				)
				(justify right top mirror)
			)
		)
		(property "Datasheet" "https://www.murata.com/products/productdetail?partno=GRM155R61E105KE11%23"
			(at 0 0 90)
			(layer "B.Fab")
			(hide yes)
			(effects
				(font
					(size 1.27 1.27)
					(thickness 0.15)
				)
				(justify mirror)
			)
		)
		(property "Description" "SMD Multilayer Ceramic Capacitor, 1 µF, 25 V, 0402 [1005 Metric], ± 10%, X5R, GRM Series"
			(at 0 0 90)
			(layer "B.Fab")
			(hide yes)
			(effects
				(font
					(size 1.27 1.27)
					(thickness 0.15)
				)
				(justify mirror)
			)
		)
		(property "MPN" "GRM155R61E105KE11J"
			(at 0 0 90)
			(unlocked yes)
			(layer "B.Fab")
			(hide yes)
			(effects
				(font
					(size 1 1)
					(thickness 0.15)
				)
				(justify mirror)
			)
		)
		(property "Manufacturer" "Murata"
			(at 0 0 90)
			(unlocked yes)
			(layer "B.Fab")
			(hide yes)
			(effects
				(font
					(size 1 1)
					(thickness 0.15)
				)
				(justify mirror)
			)
		)
		(property "License" "Apache-2.0"
			(at 0 0 90)
			(unlocked yes)
			(layer "B.Fab")
			(hide yes)
			(effects
				(font
					(size 1 1)
					(thickness 0.15)
				)
				(justify mirror)
			)
		)
		(property "Author" "Antmicro"
			(at 0 0 90)
			(unlocked yes)
			(layer "B.Fab")
			(hide yes)
			(effects
				(font
					(size 1 1)
					(thickness 0.15)
				)
				(justify mirror)
			)
		)
		(property "Val" "1u"
			(at 0 0 90)
			(unlocked yes)
			(layer "B.Fab")
			(hide yes)
			(effects
				(font
					(size 1 1)
					(thickness 0.15)
				)
				(justify mirror)
			)
		)
		(property "Voltage" "25V"
			(at 0 0 90)
			(unlocked yes)
			(layer "B.Fab")
			(hide yes)
			(effects
				(font
					(size 1 1)
					(thickness 0.15)
				)
				(justify mirror)
			)
		)
		(property "Dielectric" "X5R"
			(at 0 0 90)
			(unlocked yes)
			(layer "B.Fab")
			(hide yes)
			(effects
				(font
					(size 1 1)
					(thickness 0.15)
				)
				(justify mirror)
			)
		)
		(sheetname "/X710-AT2 power/")
		(sheetfile "x710-at2-power.kicad_sch")
		(attr smd)
		(fp_rect
			(start -0.925 0.47)
			(end 0.925 -0.47)
			(stroke
				(width 0.05)
				(type default)
			)
			(fill no)
			(layer "B.CrtYd")
		)
		(fp_line
			(start 0.504 -0.248)
			(end -0.494 -0.248)
			(stroke
				(width 0.15)
				(type solid)
			)
			(layer "B.Fab")
		)
		(fp_line
			(start -0.494 -0.248)
			(end -0.494 0.25)
			(stroke
				(width 0.15)
				(type solid)
			)
			(layer "B.Fab")
		)
		(fp_line
			(start 0.504 0.25)
			(end 0.504 -0.248)
			(stroke
				(width 0.15)
				(type solid)
			)
			(layer "B.Fab")
		)
		(fp_line
			(start -0.494 0.25)
			(end 0.504 0.25)
			(stroke
				(width 0.15)
				(type solid)
			)
			(layer "B.Fab")
		)
		(pad "1" smd roundrect
			(at -0.48 0 90)
			(size 0.59 0.64)
			(layers "B.Cu" "B.Mask" "B.Paste")
			(roundrect_rratio 0.25)
			(net 28 "GND")
			(pintype "passive")
		)
		(pad "2" smd roundrect
			(at 0.48 0 90)
			(size 0.59 0.64)
			(layers "B.Cu" "B.Mask" "B.Paste")
			(roundrect_rratio 0.25)
			(net 9 "VCCD")
			(pintype "passive")
		)
	)
	(footprint "antmicro-footprints:R_0402_1005Metric"
		(layer "B.Cu")
		(at 109.5 66.6 180)
		(descr "Resistor SMD 0402")
		(tags "resistor SMD 0402")
		(property "Reference" "R164"
			(at -1.44 5.61 0)
			(layer "B.SilkS")
			(effects
				(font
					(size 0.7 0.7)
					(thickness 0.15)
				)
				(justify left bottom mirror)
			)
		)
		(property "Value" "R_10k_0402"
			(at -1.011843 -1.772046 0)
			(layer "B.Fab")
			(hide yes)
			(effects
				(font
					(size 0.7 0.7)
					(thickness 0.15)
				)
				(justify left bottom mirror)
			)
		)
		(property "Datasheet" "https://www.bourns.com/docs/product-datasheets/cr.pdf"
			(at 0 0 0)
			(layer "B.Fab")
			(hide yes)
			(effects
				(font
					(size 1.27 1.27)
					(thickness 0.15)
				)
				(justify mirror)
			)
		)
		(property "Description" "SMD Chip Resistor, 10 kohm, ± 1%, 62.5 mW, 0402 [1005 Metric], Thick Film, General Purpose"
			(at 0 0 0)
			(layer "B.Fab")
			(hide yes)
			(effects
				(font
					(size 1.27 1.27)
					(thickness 0.15)
				)
				(justify mirror)
			)
		)
		(property "MPN" "CR0402-FX-1002GLF"
			(at 0 0 180)
			(unlocked yes)
			(layer "B.Fab")
			(hide yes)
			(effects
				(font
					(size 1 1)
					(thickness 0.15)
				)
				(justify mirror)
			)
		)
		(property "Manufacturer" "Bourns"
			(at 0 0 180)
			(unlocked yes)
			(layer "B.Fab")
			(hide yes)
			(effects
				(font
					(size 1 1)
					(thickness 0.15)
				)
				(justify mirror)
			)
		)
		(property "License" "Apache-2.0"
			(at 0 0 180)
			(unlocked yes)
			(layer "B.Fab")
			(hide yes)
			(effects
				(font
					(size 1 1)
					(thickness 0.15)
				)
				(justify mirror)
			)
		)
		(property "Author" "Antmicro"
			(at 0 0 180)
			(unlocked yes)
			(layer "B.Fab")
			(hide yes)
			(effects
				(font
					(size 1 1)
					(thickness 0.15)
				)
				(justify mirror)
			)
		)
		(property "Val" "10k"
			(at 0 0 180)
			(unlocked yes)
			(layer "B.Fab")
			(hide yes)
			(effects
				(font
					(size 1 1)
					(thickness 0.15)
				)
				(justify mirror)
			)
		)
		(property "Tolerance" "1%"
			(at 0 0 180)
			(unlocked yes)
			(layer "B.Fab")
			(hide yes)
			(effects
				(font
					(size 1 1)
					(thickness 0.15)
				)
				(justify mirror)
			)
		)
		(sheetname "/OCuLink/")
		(sheetfile "oculink.kicad_sch")
		(attr smd exclude_from_pos_files exclude_from_bom dnp)
		(fp_rect
			(start -0.925 0.47)
			(end 0.925 -0.47)
			(stroke
				(width 0.05)
				(type default)
			)
			(fill no)
			(layer "B.CrtYd")
		)
		(fp_rect
			(start -0.5 0.25)
			(end 0.5 -0.25)
			(stroke
				(width 0.15)
				(type solid)
			)
			(fill no)
			(layer "B.Fab")
		)
		(pad "1" smd roundrect
			(at -0.48 0 180)
			(size 0.59 0.64)
			(layers "B.Cu" "B.Mask" "B.Paste")
			(roundrect_rratio 0.25)
			(net 319 "/OCuLink/~{PE_ RST}_R")
			(pintype "passive")
		)
		(pad "2" smd roundrect
			(at 0.48 0 180)
			(size 0.59 0.64)
			(layers "B.Cu" "B.Mask" "B.Paste")
			(roundrect_rratio 0.25)
			(net 7 "+3V3")
			(pintype "passive")
		)
	)
	(footprint "antmicro-footprints:R_0402_1005Metric"
		(layer "B.Cu")
		(at 98.48 145.34 90)
		(descr "Resistor SMD 0402")
		(tags "resistor SMD 0402")
		(property "Reference" "R39"
			(at 0.76 -0.32 90)
			(layer "B.SilkS")
			(effects
				(font
					(size 0.7 0.7)
					(thickness 0.15)
				)
				(justify right top mirror)
			)
		)
		(property "Value" "R_220R_0402"
			(at -1.011843 -1.772046 90)
			(layer "B.Fab")
			(hide yes)
			(effects
				(font
					(size 0.7 0.7)
					(thickness 0.15)
				)
				(justify right top mirror)
			)
		)
		(property "Datasheet" "https://www.bourns.com/docs/product-datasheets/cr.pdf"
			(at 0 0 90)
			(layer "B.Fab")
			(hide yes)
			(effects
				(font
					(size 1.27 1.27)
					(thickness 0.15)
				)
				(justify mirror)
			)
		)
		(property "Description" "SMD Chip Resistor, 220 ohm, ± 1%, 62.5 mW, 0402 [1005 Metric], Thick Film, General Purpose"
			(at 0 0 90)
			(layer "B.Fab")
			(hide yes)
			(effects
				(font
					(size 1.27 1.27)
					(thickness 0.15)
				)
				(justify mirror)
			)
		)
		(property "MPN" "CR0402-FX-2200GLF"
			(at 0 0 90)
			(unlocked yes)
			(layer "B.Fab")
			(hide yes)
			(effects
				(font
					(size 1 1)
					(thickness 0.15)
				)
				(justify mirror)
			)
		)
		(property "Manufacturer" "Bourns"
			(at 0 0 90)
			(unlocked yes)
			(layer "B.Fab")
			(hide yes)
			(effects
				(font
					(size 1 1)
					(thickness 0.15)
				)
				(justify mirror)
			)
		)
		(property "License" "Apache-2.0"
			(at 0 0 90)
			(unlocked yes)
			(layer "B.Fab")
			(hide yes)
			(effects
				(font
					(size 1 1)
					(thickness 0.15)
				)
				(justify mirror)
			)
		)
		(property "Author" "Antmicro"
			(at 0 0 90)
			(unlocked yes)
			(layer "B.Fab")
			(hide yes)
			(effects
				(font
					(size 1 1)
					(thickness 0.15)
				)
				(justify mirror)
			)
		)
		(property "Val" "220R"
			(at 0 0 90)
			(unlocked yes)
			(layer "B.Fab")
			(hide yes)
			(effects
				(font
					(size 1 1)
					(thickness 0.15)
				)
				(justify mirror)
			)
		)
		(property "Tolerance" "1%"
			(at 0 0 90)
			(unlocked yes)
			(layer "B.Fab")
			(hide yes)
			(effects
				(font
					(size 1 1)
					(thickness 0.15)
				)
				(justify mirror)
			)
		)
		(sheetname "/2xRJ45/")
		(sheetfile "2xrj45.kicad_sch")
		(attr smd)
		(fp_rect
			(start -0.925 0.47)
			(end 0.925 -0.47)
			(stroke
				(width 0.05)
				(type default)
			)
			(fill no)
			(layer "B.CrtYd")
		)
		(fp_rect
			(start -0.5 0.25)
			(end 0.5 -0.25)
			(stroke
				(width 0.15)
				(type solid)
			)
			(fill no)
			(layer "B.Fab")
		)
		(pad "1" smd roundrect
			(at -0.48 0 90)
			(size 0.59 0.64)
			(layers "B.Cu" "B.Mask" "B.Paste")
			(roundrect_rratio 0.25)
			(net 61 "Net-(J6-LED_YG_Y-)")
			(pintype "passive")
		)
		(pad "2" smd roundrect
			(at 0.48 0 90)
			(size 0.59 0.64)
			(layers "B.Cu" "B.Mask" "B.Paste")
			(roundrect_rratio 0.25)
			(net 86 "/2xRJ45/~{P1_LINK_LESS_THAN_10G}")
			(pintype "passive")
		)
	)
	(footprint "antmicro-footprints:R_0402_1005Metric"
		(layer "B.Cu")
		(at 74.95 103.2 180)
		(descr "Resistor SMD 0402")
		(tags "resistor SMD 0402")
		(property "Reference" "R117"
			(at 0.85 -0.45 0)
			(layer "B.SilkS")
			(effects
				(font
					(size 0.7 0.7)
					(thickness 0.15)
				)
				(justify left bottom mirror)
			)
		)
		(property "Value" "R_1k_0402"
			(at -1.011843 -1.772046 0)
			(layer "B.Fab")
			(hide yes)
			(effects
				(font
					(size 0.7 0.7)
					(thickness 0.15)
				)
				(justify left bottom mirror)
			)
		)
		(property "Datasheet" "https://www.bourns.com/docs/product-datasheets/cr.pdf"
			(at 0 0 0)
			(layer "B.Fab")
			(hide yes)
			(effects
				(font
					(size 1.27 1.27)
					(thickness 0.15)
				)
				(justify mirror)
			)
		)
		(property "Description" "SMD Chip Resistor, 1 kohm, ± 1%, 63 mW, 0402 [1005 Metric], Thick Film, General Purpose"
			(at 0 0 0)
			(layer "B.Fab")
			(hide yes)
			(effects
				(font
					(size 1.27 1.27)
					(thickness 0.15)
				)
				(justify mirror)
			)
		)
		(property "MPN" "CR0402-FX-1001GLF"
			(at 0 0 180)
			(unlocked yes)
			(layer "B.Fab")
			(hide yes)
			(effects
				(font
					(size 1 1)
					(thickness 0.15)
				)
				(justify mirror)
			)
		)
		(property "Manufacturer" "Bourns"
			(at 0 0 180)
			(unlocked yes)
			(layer "B.Fab")
			(hide yes)
			(effects
				(font
					(size 1 1)
					(thickness 0.15)
				)
				(justify mirror)
			)
		)
		(property "License" "Apache-2.0"
			(at 0 0 180)
			(unlocked yes)
			(layer "B.Fab")
			(hide yes)
			(effects
				(font
					(size 1 1)
					(thickness 0.15)
				)
				(justify mirror)
			)
		)
		(property "Author" "Antmicro"
			(at 0 0 180)
			(unlocked yes)
			(layer "B.Fab")
			(hide yes)
			(effects
				(font
					(size 1 1)
					(thickness 0.15)
				)
				(justify mirror)
			)
		)
		(property "Val" "1k"
			(at 0 0 180)
			(unlocked yes)
			(layer "B.Fab")
			(hide yes)
			(effects
				(font
					(size 1 1)
					(thickness 0.15)
				)
				(justify mirror)
			)
		)
		(property "Tolerance" "1%"
			(at 0 0 180)
			(unlocked yes)
			(layer "B.Fab")
			(hide yes)
			(effects
				(font
					(size 1 1)
					(thickness 0.15)
				)
				(justify mirror)
			)
		)
		(sheetname "/X710-AT2 Misc/")
		(sheetfile "x710-at2-mics.kicad_sch")
		(attr smd)
		(fp_rect
			(start -0.925 0.47)
			(end 0.925 -0.47)
			(stroke
				(width 0.05)
				(type default)
			)
			(fill no)
			(layer "B.CrtYd")
		)
		(fp_rect
			(start -0.5 0.25)
			(end 0.5 -0.25)
			(stroke
				(width 0.15)
				(type solid)
			)
			(fill no)
			(layer "B.Fab")
		)
		(pad "1" smd roundrect
			(at -0.48 0 180)
			(size 0.59 0.64)
			(layers "B.Cu" "B.Mask" "B.Paste")
			(roundrect_rratio 0.25)
			(net 113 "/X710-AT2 Misc/RSVDK40_1P88V")
			(pintype "passive")
		)
		(pad "2" smd roundrect
			(at 0.48 0 180)
			(size 0.59 0.64)
			(layers "B.Cu" "B.Mask" "B.Paste")
			(roundrect_rratio 0.25)
			(net 18 "+1V88")
			(pintype "passive")
		)
	)
	(footprint "antmicro-footprints:C_0402_1005Metric"
		(layer "B.Cu")
		(at 79.22 103.23 90)
		(descr "Capacitor SMD 0402")
		(tags "capacitor SMD 0402")
		(property "Reference" "C187"
			(at -11.62 -0.04 90)
			(layer "B.SilkS")
			(effects
				(font
					(size 0.7 0.7)
					(thickness 0.15)
				)
				(justify right top mirror)
			)
		)
		(property "Value" "C_1u_25V_0402"
			(at -1.022927 -2.155213 90)
			(layer "B.Fab")
			(hide yes)
			(effects
				(font
					(size 0.7 0.7)
					(thickness 0.15)
				)
				(justify right top mirror)
			)
		)
		(property "Datasheet" "https://www.murata.com/products/productdetail?partno=GRM155R61E105KE11%23"
			(at 0 0 90)
			(layer "B.Fab")
			(hide yes)
			(effects
				(font
					(size 1.27 1.27)
					(thickness 0.15)
				)
				(justify mirror)
			)
		)
		(property "Description" "SMD Multilayer Ceramic Capacitor, 1 µF, 25 V, 0402 [1005 Metric], ± 10%, X5R, GRM Series"
			(at 0 0 90)
			(layer "B.Fab")
			(hide yes)
			(effects
				(font
					(size 1.27 1.27)
					(thickness 0.15)
				)
				(justify mirror)
			)
		)
		(property "MPN" "GRM155R61E105KE11J"
			(at 0 0 90)
			(unlocked yes)
			(layer "B.Fab")
			(hide yes)
			(effects
				(font
					(size 1 1)
					(thickness 0.15)
				)
				(justify mirror)
			)
		)
		(property "Manufacturer" "Murata"
			(at 0 0 90)
			(unlocked yes)
			(layer "B.Fab")
			(hide yes)
			(effects
				(font
					(size 1 1)
					(thickness 0.15)
				)
				(justify mirror)
			)
		)
		(property "License" "Apache-2.0"
			(at 0 0 90)
			(unlocked yes)
			(layer "B.Fab")
			(hide yes)
			(effects
				(font
					(size 1 1)
					(thickness 0.15)
				)
				(justify mirror)
			)
		)
		(property "Author" "Antmicro"
			(at 0 0 90)
			(unlocked yes)
			(layer "B.Fab")
			(hide yes)
			(effects
				(font
					(size 1 1)
					(thickness 0.15)
				)
				(justify mirror)
			)
		)
		(property "Val" "1u"
			(at 0 0 90)
			(unlocked yes)
			(layer "B.Fab")
			(hide yes)
			(effects
				(font
					(size 1 1)
					(thickness 0.15)
				)
				(justify mirror)
			)
		)
		(property "Voltage" "25V"
			(at 0 0 90)
			(unlocked yes)
			(layer "B.Fab")
			(hide yes)
			(effects
				(font
					(size 1 1)
					(thickness 0.15)
				)
				(justify mirror)
			)
		)
		(property "Dielectric" "X5R"
			(at 0 0 90)
			(unlocked yes)
			(layer "B.Fab")
			(hide yes)
			(effects
				(font
					(size 1 1)
					(thickness 0.15)
				)
				(justify mirror)
			)
		)
		(sheetname "/X710-AT2 power/")
		(sheetfile "x710-at2-power.kicad_sch")
		(attr smd)
		(fp_rect
			(start -0.925 0.47)
			(end 0.925 -0.47)
			(stroke
				(width 0.05)
				(type default)
			)
			(fill no)
			(layer "B.CrtYd")
		)
		(fp_line
			(start 0.504 -0.248)
			(end -0.494 -0.248)
			(stroke
				(width 0.15)
				(type solid)
			)
			(layer "B.Fab")
		)
		(fp_line
			(start -0.494 -0.248)
			(end -0.494 0.25)
			(stroke
				(width 0.15)
				(type solid)
			)
			(layer "B.Fab")
		)
		(fp_line
			(start 0.504 0.25)
			(end 0.504 -0.248)
			(stroke
				(width 0.15)
				(type solid)
			)
			(layer "B.Fab")
		)
		(fp_line
			(start -0.494 0.25)
			(end 0.504 0.25)
			(stroke
				(width 0.15)
				(type solid)
			)
			(layer "B.Fab")
		)
		(pad "1" smd roundrect
			(at -0.48 0 90)
			(size 0.59 0.64)
			(layers "B.Cu" "B.Mask" "B.Paste")
			(roundrect_rratio 0.25)
			(net 28 "GND")
			(pintype "passive")
		)
		(pad "2" smd roundrect
			(at 0.48 0 90)
			(size 0.59 0.64)
			(layers "B.Cu" "B.Mask" "B.Paste")
			(roundrect_rratio 0.25)
			(net 24 "XFI_PVDD")
			(pintype "passive")
		)
	)
	(footprint "antmicro-footprints:C_0402_1005Metric"
		(layer "B.Cu")
		(at 85.225 100.15 90)
		(descr "Capacitor SMD 0402")
		(tags "capacitor SMD 0402")
		(property "Reference" "C119"
			(at 9.87 -0.442343 90)
			(layer "B.SilkS")
			(effects
				(font
					(size 0.7 0.7)
					(thickness 0.15)
				)
				(justify right top mirror)
			)
		)
		(property "Value" "C_1u_25V_0402"
			(at -1.022927 -2.155213 90)
			(layer "B.Fab")
			(hide yes)
			(effects
				(font
					(size 0.7 0.7)
					(thickness 0.15)
				)
				(justify right top mirror)
			)
		)
		(property "Datasheet" "https://www.murata.com/products/productdetail?partno=GRM155R61E105KE11%23"
			(at 0 0 90)
			(layer "B.Fab")
			(hide yes)
			(effects
				(font
					(size 1.27 1.27)
					(thickness 0.15)
				)
				(justify mirror)
			)
		)
		(property "Description" "SMD Multilayer Ceramic Capacitor, 1 µF, 25 V, 0402 [1005 Metric], ± 10%, X5R, GRM Series"
			(at 0 0 90)
			(layer "B.Fab")
			(hide yes)
			(effects
				(font
					(size 1.27 1.27)
					(thickness 0.15)
				)
				(justify mirror)
			)
		)
		(property "MPN" "GRM155R61E105KE11J"
			(at 0 0 90)
			(unlocked yes)
			(layer "B.Fab")
			(hide yes)
			(effects
				(font
					(size 1 1)
					(thickness 0.15)
				)
				(justify mirror)
			)
		)
		(property "Manufacturer" "Murata"
			(at 0 0 90)
			(unlocked yes)
			(layer "B.Fab")
			(hide yes)
			(effects
				(font
					(size 1 1)
					(thickness 0.15)
				)
				(justify mirror)
			)
		)
		(property "License" "Apache-2.0"
			(at 0 0 90)
			(unlocked yes)
			(layer "B.Fab")
			(hide yes)
			(effects
				(font
					(size 1 1)
					(thickness 0.15)
				)
				(justify mirror)
			)
		)
		(property "Author" "Antmicro"
			(at 0 0 90)
			(unlocked yes)
			(layer "B.Fab")
			(hide yes)
			(effects
				(font
					(size 1 1)
					(thickness 0.15)
				)
				(justify mirror)
			)
		)
		(property "Val" "1u"
			(at 0 0 90)
			(unlocked yes)
			(layer "B.Fab")
			(hide yes)
			(effects
				(font
					(size 1 1)
					(thickness 0.15)
				)
				(justify mirror)
			)
		)
		(property "Voltage" "25V"
			(at 0 0 90)
			(unlocked yes)
			(layer "B.Fab")
			(hide yes)
			(effects
				(font
					(size 1 1)
					(thickness 0.15)
				)
				(justify mirror)
			)
		)
		(property "Dielectric" "X5R"
			(at 0 0 90)
			(unlocked yes)
			(layer "B.Fab")
			(hide yes)
			(effects
				(font
					(size 1 1)
					(thickness 0.15)
				)
				(justify mirror)
			)
		)
		(sheetname "/X710-AT2 power/")
		(sheetfile "x710-at2-power.kicad_sch")
		(attr smd)
		(fp_rect
			(start -0.925 0.47)
			(end 0.925 -0.47)
			(stroke
				(width 0.05)
				(type default)
			)
			(fill no)
			(layer "B.CrtYd")
		)
		(fp_line
			(start 0.504 -0.248)
			(end -0.494 -0.248)
			(stroke
				(width 0.15)
				(type solid)
			)
			(layer "B.Fab")
		)
		(fp_line
			(start -0.494 -0.248)
			(end -0.494 0.25)
			(stroke
				(width 0.15)
				(type solid)
			)
			(layer "B.Fab")
		)
		(fp_line
			(start 0.504 0.25)
			(end 0.504 -0.248)
			(stroke
				(width 0.15)
				(type solid)
			)
			(layer "B.Fab")
		)
		(fp_line
			(start -0.494 0.25)
			(end 0.504 0.25)
			(stroke
				(width 0.15)
				(type solid)
			)
			(layer "B.Fab")
		)
		(pad "1" smd roundrect
			(at -0.48 0 90)
			(size 0.59 0.64)
			(layers "B.Cu" "B.Mask" "B.Paste")
			(roundrect_rratio 0.25)
			(net 28 "GND")
			(pintype "passive")
		)
		(pad "2" smd roundrect
			(at 0.48 0 90)
			(size 0.59 0.64)
			(layers "B.Cu" "B.Mask" "B.Paste")
			(roundrect_rratio 0.25)
			(net 9 "VCCD")
			(pintype "passive")
		)
	)
	(footprint "antmicro-footprints:C_0402_1005Metric"
		(layer "B.Cu")
		(at 87.225 94.6 90)
		(descr "Capacitor SMD 0402")
		(tags "capacitor SMD 0402")
		(property "Reference" "C95"
			(at 12.5 -0.462343 90)
			(layer "B.SilkS")
			(effects
				(font
					(size 0.7 0.7)
					(thickness 0.15)
				)
				(justify right top mirror)
			)
		)
		(property "Value" "C_1u_25V_0402"
			(at -1.022927 -2.155213 90)
			(layer "B.Fab")
			(hide yes)
			(effects
				(font
					(size 0.7 0.7)
					(thickness 0.15)
				)
				(justify right top mirror)
			)
		)
		(property "Datasheet" "https://www.murata.com/products/productdetail?partno=GRM155R61E105KE11%23"
			(at 0 0 90)
			(layer "B.Fab")
			(hide yes)
			(effects
				(font
					(size 1.27 1.27)
					(thickness 0.15)
				)
				(justify mirror)
			)
		)
		(property "Description" "SMD Multilayer Ceramic Capacitor, 1 µF, 25 V, 0402 [1005 Metric], ± 10%, X5R, GRM Series"
			(at 0 0 90)
			(layer "B.Fab")
			(hide yes)
			(effects
				(font
					(size 1.27 1.27)
					(thickness 0.15)
				)
				(justify mirror)
			)
		)
		(property "MPN" "GRM155R61E105KE11J"
			(at 0 0 90)
			(unlocked yes)
			(layer "B.Fab")
			(hide yes)
			(effects
				(font
					(size 1 1)
					(thickness 0.15)
				)
				(justify mirror)
			)
		)
		(property "Manufacturer" "Murata"
			(at 0 0 90)
			(unlocked yes)
			(layer "B.Fab")
			(hide yes)
			(effects
				(font
					(size 1 1)
					(thickness 0.15)
				)
				(justify mirror)
			)
		)
		(property "License" "Apache-2.0"
			(at 0 0 90)
			(unlocked yes)
			(layer "B.Fab")
			(hide yes)
			(effects
				(font
					(size 1 1)
					(thickness 0.15)
				)
				(justify mirror)
			)
		)
		(property "Author" "Antmicro"
			(at 0 0 90)
			(unlocked yes)
			(layer "B.Fab")
			(hide yes)
			(effects
				(font
					(size 1 1)
					(thickness 0.15)
				)
				(justify mirror)
			)
		)
		(property "Val" "1u"
			(at 0 0 90)
			(unlocked yes)
			(layer "B.Fab")
			(hide yes)
			(effects
				(font
					(size 1 1)
					(thickness 0.15)
				)
				(justify mirror)
			)
		)
		(property "Voltage" "25V"
			(at 0 0 90)
			(unlocked yes)
			(layer "B.Fab")
			(hide yes)
			(effects
				(font
					(size 1 1)
					(thickness 0.15)
				)
				(justify mirror)
			)
		)
		(property "Dielectric" "X5R"
			(at 0 0 90)
			(unlocked yes)
			(layer "B.Fab")
			(hide yes)
			(effects
				(font
					(size 1 1)
					(thickness 0.15)
				)
				(justify mirror)
			)
		)
		(sheetname "/X710-AT2 power/")
		(sheetfile "x710-at2-power.kicad_sch")
		(attr smd)
		(fp_rect
			(start -0.925 0.47)
			(end 0.925 -0.47)
			(stroke
				(width 0.05)
				(type default)
			)
			(fill no)
			(layer "B.CrtYd")
		)
		(fp_line
			(start 0.504 -0.248)
			(end -0.494 -0.248)
			(stroke
				(width 0.15)
				(type solid)
			)
			(layer "B.Fab")
		)
		(fp_line
			(start -0.494 -0.248)
			(end -0.494 0.25)
			(stroke
				(width 0.15)
				(type solid)
			)
			(layer "B.Fab")
		)
		(fp_line
			(start 0.504 0.25)
			(end 0.504 -0.248)
			(stroke
				(width 0.15)
				(type solid)
			)
			(layer "B.Fab")
		)
		(fp_line
			(start -0.494 0.25)
			(end 0.504 0.25)
			(stroke
				(width 0.15)
				(type solid)
			)
			(layer "B.Fab")
		)
		(pad "1" smd roundrect
			(at -0.48 0 90)
			(size 0.59 0.64)
			(layers "B.Cu" "B.Mask" "B.Paste")
			(roundrect_rratio 0.25)
			(net 28 "GND")
			(pintype "passive")
		)
		(pad "2" smd roundrect
			(at 0.48 0 90)
			(size 0.59 0.64)
			(layers "B.Cu" "B.Mask" "B.Paste")
			(roundrect_rratio 0.25)
			(net 1 "VCCA")
			(pintype "passive")
		)
	)
	(footprint "antmicro-footprints:R_0402_1005Metric"
		(layer "B.Cu")
		(at 96.45 107.1 180)
		(descr "Resistor SMD 0402")
		(tags "resistor SMD 0402")
		(property "Reference" "R83"
			(at -0.9 0.25 0)
			(layer "B.SilkS")
			(effects
				(font
					(size 0.7 0.7)
					(thickness 0.15)
				)
				(justify right top mirror)
			)
		)
		(property "Value" "R_22R_0402"
			(at -1.011843 -1.772047 0)
			(layer "B.Fab")
			(hide yes)
			(effects
				(font
					(size 0.7 0.7)
					(thickness 0.15)
				)
				(justify left bottom mirror)
			)
		)
		(property "Datasheet" "https://www.bourns.com/docs/product-datasheets/cr.pdf"
			(at 0 0 0)
			(layer "B.Fab")
			(hide yes)
			(effects
				(font
					(size 1.27 1.27)
					(thickness 0.15)
				)
				(justify mirror)
			)
		)
		(property "Description" "SMD Chip Resistor, 22 ohm, ± 1%, 62.5 mW, 0402 [1005 Metric], Thick Film, General Purpose"
			(at 0 0 0)
			(layer "B.Fab")
			(hide yes)
			(effects
				(font
					(size 1.27 1.27)
					(thickness 0.15)
				)
				(justify mirror)
			)
		)
		(property "MPN" "CR0402-FX-22R0GLF"
			(at 0 0 180)
			(unlocked yes)
			(layer "B.Fab")
			(hide yes)
			(effects
				(font
					(size 1 1)
					(thickness 0.15)
				)
				(justify mirror)
			)
		)
		(property "Manufacturer" "Bourns"
			(at 0 0 180)
			(unlocked yes)
			(layer "B.Fab")
			(hide yes)
			(effects
				(font
					(size 1 1)
					(thickness 0.15)
				)
				(justify mirror)
			)
		)
		(property "License" "Apache-2.0"
			(at 0 0 180)
			(unlocked yes)
			(layer "B.Fab")
			(hide yes)
			(effects
				(font
					(size 1 1)
					(thickness 0.15)
				)
				(justify mirror)
			)
		)
		(property "Author" "Antmicro"
			(at 0 0 180)
			(unlocked yes)
			(layer "B.Fab")
			(hide yes)
			(effects
				(font
					(size 1 1)
					(thickness 0.15)
				)
				(justify mirror)
			)
		)
		(property "Val" "22R"
			(at 0 0 180)
			(unlocked yes)
			(layer "B.Fab")
			(hide yes)
			(effects
				(font
					(size 1 1)
					(thickness 0.15)
				)
				(justify mirror)
			)
		)
		(property "Tolerance" "1%"
			(at 0 0 180)
			(unlocked yes)
			(layer "B.Fab")
			(hide yes)
			(effects
				(font
					(size 1 1)
					(thickness 0.15)
				)
				(justify mirror)
			)
		)
		(sheetname "/X710-AT2 Misc/")
		(sheetfile "x710-at2-mics.kicad_sch")
		(attr smd)
		(fp_rect
			(start -0.925 0.47)
			(end 0.925 -0.47)
			(stroke
				(width 0.05)
				(type default)
			)
			(fill no)
			(layer "B.CrtYd")
		)
		(fp_rect
			(start -0.5 0.25)
			(end 0.5 -0.25)
			(stroke
				(width 0.15)
				(type solid)
			)
			(fill no)
			(layer "B.Fab")
		)
		(pad "1" smd roundrect
			(at -0.48 0 180)
			(size 0.59 0.64)
			(layers "B.Cu" "B.Mask" "B.Paste")
			(roundrect_rratio 0.25)
			(net 364 "/X710-AT2 Misc/NCSI.ARB_OUT")
			(pintype "passive")
		)
		(pad "2" smd roundrect
			(at 0.48 0 180)
			(size 0.59 0.64)
			(layers "B.Cu" "B.Mask" "B.Paste")
			(roundrect_rratio 0.25)
			(net 159 "Net-(U9D-NCSI_ARB_OUT)")
			(pintype "passive")
		)
	)
	(footprint "antmicro-footprints:R_0402_1005Metric"
		(layer "B.Cu")
		(at 110.49 88.86 90)
		(descr "Resistor SMD 0402")
		(tags "resistor SMD 0402")
		(property "Reference" "R133"
			(at -3.58 -0.38 90)
			(layer "B.SilkS")
			(effects
				(font
					(size 0.7 0.7)
					(thickness 0.15)
				)
				(justify right top mirror)
			)
		)
		(property "Value" "R_10k_0402"
			(at -1.011843 -1.772046 90)
			(layer "B.Fab")
			(hide yes)
			(effects
				(font
					(size 0.7 0.7)
					(thickness 0.15)
				)
				(justify right top mirror)
			)
		)
		(property "Datasheet" "https://www.bourns.com/docs/product-datasheets/cr.pdf"
			(at 0 0 90)
			(layer "B.Fab")
			(hide yes)
			(effects
				(font
					(size 1.27 1.27)
					(thickness 0.15)
				)
				(justify mirror)
			)
		)
		(property "Description" "SMD Chip Resistor, 10 kohm, ± 1%, 62.5 mW, 0402 [1005 Metric], Thick Film, General Purpose"
			(at 0 0 90)
			(layer "B.Fab")
			(hide yes)
			(effects
				(font
					(size 1.27 1.27)
					(thickness 0.15)
				)
				(justify mirror)
			)
		)
		(property "MPN" "CR0402-FX-1002GLF"
			(at 0 0 90)
			(unlocked yes)
			(layer "B.Fab")
			(hide yes)
			(effects
				(font
					(size 1 1)
					(thickness 0.15)
				)
				(justify mirror)
			)
		)
		(property "Manufacturer" "Bourns"
			(at 0 0 90)
			(unlocked yes)
			(layer "B.Fab")
			(hide yes)
			(effects
				(font
					(size 1 1)
					(thickness 0.15)
				)
				(justify mirror)
			)
		)
		(property "License" "Apache-2.0"
			(at 0 0 90)
			(unlocked yes)
			(layer "B.Fab")
			(hide yes)
			(effects
				(font
					(size 1 1)
					(thickness 0.15)
				)
				(justify mirror)
			)
		)
		(property "Author" "Antmicro"
			(at 0 0 90)
			(unlocked yes)
			(layer "B.Fab")
			(hide yes)
			(effects
				(font
					(size 1 1)
					(thickness 0.15)
				)
				(justify mirror)
			)
		)
		(property "Val" "10k"
			(at 0 0 90)
			(unlocked yes)
			(layer "B.Fab")
			(hide yes)
			(effects
				(font
					(size 1 1)
					(thickness 0.15)
				)
				(justify mirror)
			)
		)
		(property "Tolerance" "1%"
			(at 0 0 90)
			(unlocked yes)
			(layer "B.Fab")
			(hide yes)
			(effects
				(font
					(size 1 1)
					(thickness 0.15)
				)
				(justify mirror)
			)
		)
		(sheetname "/X710-AT2 RSVD/")
		(sheetfile "x710-at2-rsvd.kicad_sch")
		(attr smd)
		(fp_rect
			(start -0.925 0.47)
			(end 0.925 -0.47)
			(stroke
				(width 0.05)
				(type default)
			)
			(fill no)
			(layer "B.CrtYd")
		)
		(fp_rect
			(start -0.5 0.25)
			(end 0.5 -0.25)
			(stroke
				(width 0.15)
				(type solid)
			)
			(fill no)
			(layer "B.Fab")
		)
		(pad "1" smd roundrect
			(at -0.48 0 90)
			(size 0.59 0.64)
			(layers "B.Cu" "B.Mask" "B.Paste")
			(roundrect_rratio 0.25)
			(net 28 "GND")
			(pintype "passive")
		)
		(pad "2" smd roundrect
			(at 0.48 0 90)
			(size 0.59 0.64)
			(layers "B.Cu" "B.Mask" "B.Paste")
			(roundrect_rratio 0.25)
			(net 121 "/X710-AT2 RSVD/DEBUG_Y16")
			(pintype "passive")
		)
	)
	(footprint "antmicro-footprints:TP_SMD_0.75mm"
		(layer "B.Cu")
		(at 87 106.35 90)
		(property "Reference" "TP10"
			(at 1.22 -2.29 180)
			(layer "B.SilkS")
			(effects
				(font
					(size 0.7 0.7)
					(thickness 0.15)
				)
				(justify right top mirror)
			)
		)
		(property "Value" "TP_0.75mm_SMD"
			(at 0 -1.2 90)
			(layer "B.Fab")
			(hide yes)
			(effects
				(font
					(size 0.7 0.7)
					(thickness 0.15)
				)
				(justify right top mirror)
			)
		)
		(property "Description" "SMT test point"
			(at 0 0 90)
			(layer "B.Fab")
			(hide yes)
			(effects
				(font
					(size 1.27 1.27)
					(thickness 0.15)
				)
				(justify mirror)
			)
		)
		(property "MPN" ""
			(at 0 0 90)
			(unlocked yes)
			(layer "B.Fab")
			(hide yes)
			(effects
				(font
					(size 1 1)
					(thickness 0.15)
				)
				(justify mirror)
			)
		)
		(property "Manufacturer" ""
			(at 0 0 90)
			(unlocked yes)
			(layer "B.Fab")
			(hide yes)
			(effects
				(font
					(size 1 1)
					(thickness 0.15)
				)
				(justify mirror)
			)
		)
		(property "Author" "Antmicro"
			(at 0 0 90)
			(unlocked yes)
			(layer "B.Fab")
			(hide yes)
			(effects
				(font
					(size 1 1)
					(thickness 0.15)
				)
				(justify mirror)
			)
		)
		(property "License" "Apache-2.0"
			(at 0 0 90)
			(unlocked yes)
			(layer "B.Fab")
			(hide yes)
			(effects
				(font
					(size 1 1)
					(thickness 0.15)
				)
				(justify mirror)
			)
		)
		(sheetname "/X710-AT2 Misc/")
		(sheetfile "x710-at2-mics.kicad_sch")
		(attr exclude_from_pos_files exclude_from_bom)
		(fp_circle
			(center 0 0)
			(end 0.475 0)
			(stroke
				(width 0.05)
				(type default)
			)
			(fill no)
			(layer "B.CrtYd")
		)
		(pad "1" smd circle
			(at 0 0 90)
			(size 0.75 0.75)
			(layers "B.Cu" "B.Mask")
			(net 134 "/X710-AT2 Misc/PHY_TCK")
			(pinfunction "1")
			(pintype "passive")
		)
	)
	(footprint "antmicro-footprints:TP_SMD_1mm"
		(layer "B.Cu")
		(at 80.24 72.3 -90)
		(property "Reference" "TP28"
			(at -1.84 7.148102 90)
			(layer "B.SilkS")
			(effects
				(font
					(size 0.7 0.7)
					(thickness 0.15)
				)
				(justify left bottom mirror)
			)
		)
		(property "Value" "TP_1mm_SMD"
			(at 0 -1.4 90)
			(layer "B.Fab")
			(hide yes)
			(effects
				(font
					(size 0.7 0.7)
					(thickness 0.15)
				)
				(justify left bottom mirror)
			)
		)
		(property "Description" "Test point 1mm SMD"
			(at 0 0 90)
			(layer "B.Fab")
			(hide yes)
			(effects
				(font
					(size 1.27 1.27)
					(thickness 0.15)
				)
				(justify mirror)
			)
		)
		(property "MPN" ""
			(at 0 0 90)
			(unlocked yes)
			(layer "B.Fab")
			(hide yes)
			(effects
				(font
					(size 1 1)
					(thickness 0.15)
				)
				(justify mirror)
			)
		)
		(property "Manufacturer" ""
			(at 0 0 90)
			(unlocked yes)
			(layer "B.Fab")
			(hide yes)
			(effects
				(font
					(size 1 1)
					(thickness 0.15)
				)
				(justify mirror)
			)
		)
		(property "Author" "Antmicro"
			(at 0 0 90)
			(unlocked yes)
			(layer "B.Fab")
			(hide yes)
			(effects
				(font
					(size 1 1)
					(thickness 0.15)
				)
				(justify mirror)
			)
		)
		(property "License" "Apache-2.0"
			(at 0 0 90)
			(unlocked yes)
			(layer "B.Fab")
			(hide yes)
			(effects
				(font
					(size 1 1)
					(thickness 0.15)
				)
				(justify mirror)
			)
		)
		(sheetname "/Power/")
		(sheetfile "power.kicad_sch")
		(attr exclude_from_pos_files exclude_from_bom)
		(fp_circle
			(center 0 0)
			(end 0.6 0)
			(stroke
				(width 0.05)
				(type default)
			)
			(fill no)
			(layer "B.CrtYd")
		)
		(pad "1" smd circle
			(at 0 0 270)
			(size 1 1)
			(layers "B.Cu" "B.Mask")
			(net 351 "/Power/+5V_USB")
			(pinfunction "1")
			(pintype "passive")
		)
	)
	(footprint "antmicro-footprints:SOT-416"
		(layer "B.Cu")
		(at 56.25 122.75)
		(descr "SOT-416")
		(tags "SOT-416")
		(property "Reference" "Q7"
			(at 1.169999 0.8 90)
			(layer "B.SilkS")
			(effects
				(font
					(size 0.7 0.7)
					(thickness 0.15)
				)
				(justify right top mirror)
			)
		)
		(property "Value" "DTC014T_SOT-416"
			(at 0 -2.000001 0)
			(layer "B.Fab")
			(hide yes)
			(effects
				(font
					(size 0.7 0.7)
					(thickness 0.15)
				)
				(justify right top mirror)
			)
		)
		(property "Datasheet" "https://www.rohm.com/datasheet?p=DTC014TEB&dist=Mouser&media=referral&source=mouser.com&campaign=Mouser"
			(at 0 0 0)
			(layer "B.Fab")
			(hide yes)
			(effects
				(font
					(size 1.27 1.27)
					(thickness 0.15)
				)
				(justify mirror)
			)
		)
		(property "Description" "Bipolar (BJT) Single Transistor with built-in base resistor, NPN, 50V, 100mA, 150mW, SOT-416FL, Surface Mount"
			(at 0 0 0)
			(layer "B.Fab")
			(hide yes)
			(effects
				(font
					(size 1.27 1.27)
					(thickness 0.15)
				)
				(justify mirror)
			)
		)
		(property "Manufacturer" "ROHM Semiconductor"
			(at 0 0 180)
			(unlocked yes)
			(layer "B.Fab")
			(hide yes)
			(effects
				(font
					(size 1 1)
					(thickness 0.15)
				)
				(justify mirror)
			)
		)
		(property "MPN" "DTC014TEBTL"
			(at 0 0 180)
			(unlocked yes)
			(layer "B.Fab")
			(hide yes)
			(effects
				(font
					(size 1 1)
					(thickness 0.15)
				)
				(justify mirror)
			)
		)
		(property "Author" "Antmicro"
			(at 0 0 180)
			(unlocked yes)
			(layer "B.Fab")
			(hide yes)
			(effects
				(font
					(size 1 1)
					(thickness 0.15)
				)
				(justify mirror)
			)
		)
		(property "License" "Apache-2.0"
			(at 0 0 180)
			(unlocked yes)
			(layer "B.Fab")
			(hide yes)
			(effects
				(font
					(size 1 1)
					(thickness 0.15)
				)
				(justify mirror)
			)
		)
		(sheetname "/Power/")
		(sheetfile "power.kicad_sch")
		(attr smd)
		(fp_line
			(start -0.5 0.15)
			(end -0.5 -0.15)
			(stroke
				(width 0.15)
				(type solid)
			)
			(layer "B.SilkS")
		)
		(fp_line
			(start 0.5 -0.9)
			(end -0.5 -0.9)
			(stroke
				(width 0.15)
				(type solid)
			)
			(layer "B.SilkS")
		)
		(fp_line
			(start 0.5 -0.9)
			(end 0.5 -0.7)
			(stroke
				(width 0.15)
				(type solid)
			)
			(layer "B.SilkS")
		)
		(fp_line
			(start 0.508 0.9)
			(end -0.5 0.9)
			(stroke
				(width 0.15)
				(type solid)
			)
			(layer "B.SilkS")
		)
		(fp_line
			(start 0.508 0.9)
			(end 0.508 0.592)
			(stroke
				(width 0.15)
				(type solid)
			)
			(layer "B.SilkS")
		)
		(fp_rect
			(start -1 1.05)
			(end 1 -1.05)
			(stroke
				(width 0.05)
				(type solid)
			)
			(fill no)
			(layer "B.CrtYd")
		)
		(fp_line
			(start -0.05 0.9)
			(end -0.45 0.5)
			(stroke
				(width 0.15)
				(type solid)
			)
			(layer "B.Fab")
		)
		(fp_rect
			(start 0.45 -0.9)
			(end -0.45 0.9)
			(stroke
				(width 0.15)
				(type solid)
			)
			(fill no)
			(layer "B.Fab")
		)
		(fp_text user "Author: Antmicro"
			(at -1 -4.602 180)
			(layer "B.Fab")
			(effects
				(font
					(size 0.7 0.7)
					(thickness 0.15)
				)
				(justify left bottom mirror)
			)
		)
		(fp_text user "${REFERENCE}"
			(at -1 -3.4 180)
			(layer "B.Fab")
			(effects
				(font
					(size 0.7 0.7)
					(thickness 0.15)
				)
				(justify left bottom mirror)
			)
		)
		(fp_text user "License: Apache-2.0"
			(at -1 -5.802 180)
			(layer "B.Fab")
			(effects
				(font
					(size 0.7 0.7)
					(thickness 0.15)
				)
				(justify left bottom mirror)
			)
		)
		(pad "1" smd rect
			(at -0.652 0.5)
			(size 0.6 0.5)
			(layers "B.Cu" "B.Mask" "B.Paste")
			(net 310 "/Power/+1V88_OUT")
			(pinfunction "B")
			(pintype "input")
		)
		(pad "2" smd rect
			(at -0.652 -0.498)
			(size 0.6 0.5)
			(layers "B.Cu" "B.Mask" "B.Paste")
			(net 28 "GND")
			(pinfunction "E")
			(pintype "passive")
		)
		(pad "3" smd rect
			(at 0.65 0)
			(size 0.6 0.5)
			(layers "B.Cu" "B.Mask" "B.Paste")
			(net 417 "Net-(Q7-C)")
			(pinfunction "C")
			(pintype "passive")
		)
	)
	(footprint "antmicro-footprints:C_0402_1005Metric"
		(layer "B.Cu")
		(at 87.225 98.3 90)
		(descr "Capacitor SMD 0402")
		(tags "capacitor SMD 0402")
		(property "Reference" "C106"
			(at 13.45 0.366228 270)
			(layer "B.SilkS")
			(effects
				(font
					(size 0.7 0.7)
					(thickness 0.15)
				)
				(justify left bottom mirror)
			)
		)
		(property "Value" "C_1u_25V_0402"
			(at -1.022927 -2.155213 270)
			(layer "B.Fab")
			(hide yes)
			(effects
				(font
					(size 0.7 0.7)
					(thickness 0.15)
				)
				(justify left bottom mirror)
			)
		)
		(property "Datasheet" "https://www.murata.com/products/productdetail?partno=GRM155R61E105KE11%23"
			(at 0 0 270)
			(layer "B.Fab")
			(hide yes)
			(effects
				(font
					(size 1.27 1.27)
					(thickness 0.15)
				)
				(justify mirror)
			)
		)
		(property "Description" "SMD Multilayer Ceramic Capacitor, 1 µF, 25 V, 0402 [1005 Metric], ± 10%, X5R, GRM Series"
			(at 0 0 270)
			(layer "B.Fab")
			(hide yes)
			(effects
				(font
					(size 1.27 1.27)
					(thickness 0.15)
				)
				(justify mirror)
			)
		)
		(property "MPN" "GRM155R61E105KE11J"
			(at 0 0 90)
			(unlocked yes)
			(layer "B.Fab")
			(hide yes)
			(effects
				(font
					(size 1 1)
					(thickness 0.15)
				)
				(justify mirror)
			)
		)
		(property "Manufacturer" "Murata"
			(at 0 0 90)
			(unlocked yes)
			(layer "B.Fab")
			(hide yes)
			(effects
				(font
					(size 1 1)
					(thickness 0.15)
				)
				(justify mirror)
			)
		)
		(property "License" "Apache-2.0"
			(at 0 0 90)
			(unlocked yes)
			(layer "B.Fab")
			(hide yes)
			(effects
				(font
					(size 1 1)
					(thickness 0.15)
				)
				(justify mirror)
			)
		)
		(property "Author" "Antmicro"
			(at 0 0 90)
			(unlocked yes)
			(layer "B.Fab")
			(hide yes)
			(effects
				(font
					(size 1 1)
					(thickness 0.15)
				)
				(justify mirror)
			)
		)
		(property "Val" "1u"
			(at 0 0 90)
			(unlocked yes)
			(layer "B.Fab")
			(hide yes)
			(effects
				(font
					(size 1 1)
					(thickness 0.15)
				)
				(justify mirror)
			)
		)
		(property "Voltage" "25V"
			(at 0 0 90)
			(unlocked yes)
			(layer "B.Fab")
			(hide yes)
			(effects
				(font
					(size 1 1)
					(thickness 0.15)
				)
				(justify mirror)
			)
		)
		(property "Dielectric" "X5R"
			(at 0 0 90)
			(unlocked yes)
			(layer "B.Fab")
			(hide yes)
			(effects
				(font
					(size 1 1)
					(thickness 0.15)
				)
				(justify mirror)
			)
		)
		(sheetname "/X710-AT2 power/")
		(sheetfile "x710-at2-power.kicad_sch")
		(attr smd)
		(fp_rect
			(start -0.925 0.47)
			(end 0.925 -0.47)
			(stroke
				(width 0.05)
				(type default)
			)
			(fill no)
			(layer "B.CrtYd")
		)
		(fp_line
			(start 0.504 -0.248)
			(end -0.494 -0.248)
			(stroke
				(width 0.15)
				(type solid)
			)
			(layer "B.Fab")
		)
		(fp_line
			(start -0.494 -0.248)
			(end -0.494 0.25)
			(stroke
				(width 0.15)
				(type solid)
			)
			(layer "B.Fab")
		)
		(fp_line
			(start 0.504 0.25)
			(end 0.504 -0.248)
			(stroke
				(width 0.15)
				(type solid)
			)
			(layer "B.Fab")
		)
		(fp_line
			(start -0.494 0.25)
			(end 0.504 0.25)
			(stroke
				(width 0.15)
				(type solid)
			)
			(layer "B.Fab")
		)
		(pad "1" smd roundrect
			(at -0.48 0 90)
			(size 0.59 0.64)
			(layers "B.Cu" "B.Mask" "B.Paste")
			(roundrect_rratio 0.25)
			(net 28 "GND")
			(pintype "passive")
		)
		(pad "2" smd roundrect
			(at 0.48 0 90)
			(size 0.59 0.64)
			(layers "B.Cu" "B.Mask" "B.Paste")
			(roundrect_rratio 0.25)
			(net 9 "VCCD")
			(pintype "passive")
		)
	)
	(footprint "antmicro-footprints:R_0402_1005Metric"
		(layer "B.Cu")
		(at 74 97.65)
		(descr "Resistor SMD 0402")
		(tags "resistor SMD 0402")
		(property "Reference" "R104"
			(at -0.85 0.45 0)
			(layer "B.SilkS")
			(effects
				(font
					(size 0.7 0.7)
					(thickness 0.15)
				)
				(justify left bottom mirror)
			)
		)
		(property "Value" "R_0R_0402"
			(at -1.011843 -1.772046 0)
			(layer "B.Fab")
			(hide yes)
			(effects
				(font
					(size 0.7 0.7)
					(thickness 0.15)
				)
				(justify right top mirror)
			)
		)
		(property "Datasheet" "https://industrial.panasonic.com/cdbs/www-data/pdf/RDA0000/AOA0000C301.pdf"
			(at 0 0 0)
			(layer "B.Fab")
			(hide yes)
			(effects
				(font
					(size 1.27 1.27)
					(thickness 0.15)
				)
				(justify mirror)
			)
		)
		(property "Description" "SMD Chip Resistor, Jumper, 0 ohm, 100 mW, 0402 [1005 Metric], Thick Film, General Purpose"
			(at 0 0 0)
			(layer "B.Fab")
			(hide yes)
			(effects
				(font
					(size 1.27 1.27)
					(thickness 0.15)
				)
				(justify mirror)
			)
		)
		(property "MPN" "ERJ2GE0R00X"
			(at 0 0 0)
			(unlocked yes)
			(layer "B.Fab")
			(hide yes)
			(effects
				(font
					(size 1 1)
					(thickness 0.15)
				)
				(justify mirror)
			)
		)
		(property "Manufacturer" "Panasonic"
			(at 0 0 0)
			(unlocked yes)
			(layer "B.Fab")
			(hide yes)
			(effects
				(font
					(size 1 1)
					(thickness 0.15)
				)
				(justify mirror)
			)
		)
		(property "License" "Apache-2.0"
			(at 0 0 0)
			(unlocked yes)
			(layer "B.Fab")
			(hide yes)
			(effects
				(font
					(size 1 1)
					(thickness 0.15)
				)
				(justify mirror)
			)
		)
		(property "Author" "Antmicro"
			(at 0 0 0)
			(unlocked yes)
			(layer "B.Fab")
			(hide yes)
			(effects
				(font
					(size 1 1)
					(thickness 0.15)
				)
				(justify mirror)
			)
		)
		(property "Val" "0R"
			(at 0 0 0)
			(unlocked yes)
			(layer "B.Fab")
			(hide yes)
			(effects
				(font
					(size 1 1)
					(thickness 0.15)
				)
				(justify mirror)
			)
		)
		(property "Tolerance" "~"
			(at 0 0 0)
			(unlocked yes)
			(layer "B.Fab")
			(hide yes)
			(effects
				(font
					(size 1 1)
					(thickness 0.15)
				)
				(justify mirror)
			)
		)
		(property "Current" "1A"
			(at 0 0 0)
			(unlocked yes)
			(layer "B.Fab")
			(hide yes)
			(effects
				(font
					(size 1 1)
					(thickness 0.15)
				)
				(justify mirror)
			)
		)
		(sheetname "/X710-AT2 Misc/")
		(sheetfile "x710-at2-mics.kicad_sch")
		(attr smd)
		(fp_rect
			(start -0.925 0.47)
			(end 0.925 -0.47)
			(stroke
				(width 0.05)
				(type default)
			)
			(fill no)
			(layer "B.CrtYd")
		)
		(fp_rect
			(start -0.5 0.25)
			(end 0.5 -0.25)
			(stroke
				(width 0.15)
				(type solid)
			)
			(fill no)
			(layer "B.Fab")
		)
		(pad "1" smd roundrect
			(at -0.48 0)
			(size 0.59 0.64)
			(layers "B.Cu" "B.Mask" "B.Paste")
			(roundrect_rratio 0.25)
			(net 108 "/X710-AT2 Misc/GPIO5_POR_BYPASS")
			(pintype "passive")
		)
		(pad "2" smd roundrect
			(at 0.48 0)
			(size 0.59 0.64)
			(layers "B.Cu" "B.Mask" "B.Paste")
			(roundrect_rratio 0.25)
			(net 47 "/X710-AT2 Misc/POR_BYPASS")
			(pintype "passive")
		)
	)
	(footprint "antmicro-footprints:R_0402_1005Metric"
		(layer "B.Cu")
		(at 106.19 86.644 180)
		(descr "Resistor SMD 0402")
		(tags "resistor SMD 0402")
		(property "Reference" "R118"
			(at -1.89 0.624 0)
			(layer "B.SilkS")
			(effects
				(font
					(size 0.7 0.7)
					(thickness 0.15)
				)
				(justify left bottom mirror)
			)
		)
		(property "Value" "R_100k_0402"
			(at -1.011843 -1.772047 0)
			(layer "B.Fab")
			(hide yes)
			(effects
				(font
					(size 0.7 0.7)
					(thickness 0.15)
				)
				(justify left bottom mirror)
			)
		)
		(property "Datasheet" "https://www.bourns.com/docs/product-datasheets/cr.pdf"
			(at 0 0 0)
			(layer "B.Fab")
			(hide yes)
			(effects
				(font
					(size 1.27 1.27)
					(thickness 0.15)
				)
				(justify mirror)
			)
		)
		(property "Description" "SMD Chip Resistor, 100 kohm, ± 1%, 62.5 mW, 0402 [1005 Metric], Thick Film, General Purpose"
			(at 0 0 0)
			(layer "B.Fab")
			(hide yes)
			(effects
				(font
					(size 1.27 1.27)
					(thickness 0.15)
				)
				(justify mirror)
			)
		)
		(property "MPN" "CR0402-FX-1003GLF"
			(at 0 0 0)
			(unlocked yes)
			(layer "B.Fab")
			(hide yes)
			(effects
				(font
					(size 1 1)
					(thickness 0.15)
				)
				(justify mirror)
			)
		)
		(property "Manufacturer" "Bourns"
			(at 0 0 0)
			(unlocked yes)
			(layer "B.Fab")
			(hide yes)
			(effects
				(font
					(size 1 1)
					(thickness 0.15)
				)
				(justify mirror)
			)
		)
		(property "License" "Apache-2.0"
			(at 0 0 0)
			(unlocked yes)
			(layer "B.Fab")
			(hide yes)
			(effects
				(font
					(size 1 1)
					(thickness 0.15)
				)
				(justify mirror)
			)
		)
		(property "Author" "Antmicro"
			(at 0 0 0)
			(unlocked yes)
			(layer "B.Fab")
			(hide yes)
			(effects
				(font
					(size 1 1)
					(thickness 0.15)
				)
				(justify mirror)
			)
		)
		(property "Val" "100k"
			(at 0 0 0)
			(unlocked yes)
			(layer "B.Fab")
			(hide yes)
			(effects
				(font
					(size 1 1)
					(thickness 0.15)
				)
				(justify mirror)
			)
		)
		(property "Tolerance" "1%"
			(at 0 0 0)
			(unlocked yes)
			(layer "B.Fab")
			(hide yes)
			(effects
				(font
					(size 1 1)
					(thickness 0.15)
				)
				(justify mirror)
			)
		)
		(sheetname "/X710-AT2 PCIe/")
		(sheetfile "x710-at2-pcie.kicad_sch")
		(attr smd exclude_from_pos_files exclude_from_bom dnp)
		(fp_rect
			(start -0.925 0.47)
			(end 0.925 -0.47)
			(stroke
				(width 0.05)
				(type default)
			)
			(fill no)
			(layer "B.CrtYd")
		)
		(fp_rect
			(start -0.5 0.25)
			(end 0.5 -0.25)
			(stroke
				(width 0.15)
				(type solid)
			)
			(fill no)
			(layer "B.Fab")
		)
		(pad "1" smd roundrect
			(at -0.48 0 180)
			(size 0.59 0.64)
			(layers "B.Cu" "B.Mask" "B.Paste")
			(roundrect_rratio 0.25)
			(net 7 "+3V3")
			(pintype "passive")
		)
		(pad "2" smd roundrect
			(at 0.48 0 180)
			(size 0.59 0.64)
			(layers "B.Cu" "B.Mask" "B.Paste")
			(roundrect_rratio 0.25)
			(net 404 "Net-(Y3-EN)")
			(pintype "passive")
		)
	)
	(footprint "antmicro-footprints:R_0402_1005Metric"
		(layer "B.Cu")
		(at 90.225 93.15 180)
		(descr "Resistor SMD 0402")
		(tags "resistor SMD 0402")
		(property "Reference" "R56"
			(at 0.775 -0.55 0)
			(layer "B.SilkS")
			(effects
				(font
					(size 0.7 0.7)
					(thickness 0.15)
				)
				(justify left bottom mirror)
			)
		)
		(property "Value" "R_4k75_0.5%_0402"
			(at -1.011843 -1.772046 0)
			(layer "B.Fab")
			(hide yes)
			(effects
				(font
					(size 0.7 0.7)
					(thickness 0.15)
				)
				(justify left bottom mirror)
			)
		)
		(property "Datasheet" "https://industrial.panasonic.com/cdbs/www-data/pdf/RDQ0000/ast-ind-151033.pdf"
			(at 0 0 0)
			(layer "B.Fab")
			(hide yes)
			(effects
				(font
					(size 1.27 1.27)
					(thickness 0.15)
				)
				(justify mirror)
			)
		)
		(property "Description" "SMD Chip Resistor, 4.75 kohm, ± 0.5%, 100 mW, 0402 [1005 Metric], Thick Film, High Temperature"
			(at 0 0 0)
			(layer "B.Fab")
			(hide yes)
			(effects
				(font
					(size 1.27 1.27)
					(thickness 0.15)
				)
				(justify mirror)
			)
		)
		(property "MPN" "ERJ-H2RD4751X"
			(at 0 0 180)
			(unlocked yes)
			(layer "B.Fab")
			(hide yes)
			(effects
				(font
					(size 1 1)
					(thickness 0.15)
				)
				(justify mirror)
			)
		)
		(property "Manufacturer" "Panasonic"
			(at 0 0 180)
			(unlocked yes)
			(layer "B.Fab")
			(hide yes)
			(effects
				(font
					(size 1 1)
					(thickness 0.15)
				)
				(justify mirror)
			)
		)
		(property "License" "Apache-2.0"
			(at 0 0 180)
			(unlocked yes)
			(layer "B.Fab")
			(hide yes)
			(effects
				(font
					(size 1 1)
					(thickness 0.15)
				)
				(justify mirror)
			)
		)
		(property "Author" "Antmicro"
			(at 0 0 180)
			(unlocked yes)
			(layer "B.Fab")
			(hide yes)
			(effects
				(font
					(size 1 1)
					(thickness 0.15)
				)
				(justify mirror)
			)
		)
		(property "Val" "4k75"
			(at 0 0 180)
			(unlocked yes)
			(layer "B.Fab")
			(hide yes)
			(effects
				(font
					(size 1 1)
					(thickness 0.15)
				)
				(justify mirror)
			)
		)
		(property "Tolerance" "0.5%"
			(at 0 0 180)
			(unlocked yes)
			(layer "B.Fab")
			(hide yes)
			(effects
				(font
					(size 1 1)
					(thickness 0.15)
				)
				(justify mirror)
			)
		)
		(sheetname "/X710-AT2 PCIe/")
		(sheetfile "x710-at2-pcie.kicad_sch")
		(attr smd)
		(fp_rect
			(start -0.925 0.47)
			(end 0.925 -0.47)
			(stroke
				(width 0.05)
				(type default)
			)
			(fill no)
			(layer "B.CrtYd")
		)
		(fp_rect
			(start -0.5 0.25)
			(end 0.5 -0.25)
			(stroke
				(width 0.15)
				(type solid)
			)
			(fill no)
			(layer "B.Fab")
		)
		(pad "1" smd roundrect
			(at -0.48 0 180)
			(size 0.59 0.64)
			(layers "B.Cu" "B.Mask" "B.Paste")
			(roundrect_rratio 0.25)
			(net 3 "/X710-AT2 PCIe/RBIAS")
			(pintype "passive")
		)
		(pad "2" smd roundrect
			(at 0.48 0 180)
			(size 0.59 0.64)
			(layers "B.Cu" "B.Mask" "B.Paste")
			(roundrect_rratio 0.25)
			(net 2 "/X710-AT2 PCIe/RSENSE")
			(pintype "passive")
		)
	)
	(footprint "antmicro-footprints:TP_SMD_0.75mm"
		(layer "B.Cu")
		(at 61.349999 99.500001 180)
		(property "Reference" "TP39"
			(at 0 0.6 0)
			(layer "B.SilkS")
			(hide yes)
			(effects
				(font
					(size 0.7 0.7)
					(thickness 0.15)
				)
				(justify left bottom mirror)
			)
		)
		(property "Value" "TP_0.75mm_SMD"
			(at 0 -1.2 0)
			(layer "B.Fab")
			(hide yes)
			(effects
				(font
					(size 0.7 0.7)
					(thickness 0.15)
				)
				(justify left bottom mirror)
			)
		)
		(property "Description" "SMT test point"
			(at 0 0 0)
			(layer "B.Fab")
			(hide yes)
			(effects
				(font
					(size 1.27 1.27)
					(thickness 0.15)
				)
				(justify mirror)
			)
		)
		(property "MPN" ""
			(at 0 0 0)
			(unlocked yes)
			(layer "B.Fab")
			(hide yes)
			(effects
				(font
					(size 1 1)
					(thickness 0.15)
				)
				(justify mirror)
			)
		)
		(property "Manufacturer" ""
			(at 0 0 0)
			(unlocked yes)
			(layer "B.Fab")
			(hide yes)
			(effects
				(font
					(size 1 1)
					(thickness 0.15)
				)
				(justify mirror)
			)
		)
		(property "Author" "Antmicro"
			(at 0 0 0)
			(unlocked yes)
			(layer "B.Fab")
			(hide yes)
			(effects
				(font
					(size 1 1)
					(thickness 0.15)
				)
				(justify mirror)
			)
		)
		(property "License" "Apache-2.0"
			(at 0 0 0)
			(unlocked yes)
			(layer "B.Fab")
			(hide yes)
			(effects
				(font
					(size 1 1)
					(thickness 0.15)
				)
				(justify mirror)
			)
		)
		(sheetname "/Power/")
		(sheetfile "power.kicad_sch")
		(attr exclude_from_pos_files exclude_from_bom)
		(fp_circle
			(center 0 0)
			(end 0.475 0)
			(stroke
				(width 0.05)
				(type default)
			)
			(fill no)
			(layer "B.CrtYd")
		)
		(pad "1" smd circle
			(at 0 0 180)
			(size 0.75 0.75)
			(layers "B.Cu" "B.Mask")
			(net 310 "/Power/+1V88_OUT")
			(pinfunction "1")
			(pintype "passive")
		)
	)
	(footprint "antmicro-footprints:R_0402_1005Metric"
		(layer "B.Cu")
		(at 74.480001 145.34 90)
		(descr "Resistor SMD 0402")
		(tags "resistor SMD 0402")
		(property "Reference" "R37"
			(at 0.77 -0.310001 90)
			(layer "B.SilkS")
			(effects
				(font
					(size 0.7 0.7)
					(thickness 0.15)
				)
				(justify right top mirror)
			)
		)
		(property "Value" "R_220R_0402"
			(at -1.011843 -1.772046 90)
			(layer "B.Fab")
			(hide yes)
			(effects
				(font
					(size 0.7 0.7)
					(thickness 0.15)
				)
				(justify right top mirror)
			)
		)
		(property "Datasheet" "https://www.bourns.com/docs/product-datasheets/cr.pdf"
			(at 0 0 90)
			(layer "B.Fab")
			(hide yes)
			(effects
				(font
					(size 1.27 1.27)
					(thickness 0.15)
				)
				(justify mirror)
			)
		)
		(property "Description" "SMD Chip Resistor, 220 ohm, ± 1%, 62.5 mW, 0402 [1005 Metric], Thick Film, General Purpose"
			(at 0 0 90)
			(layer "B.Fab")
			(hide yes)
			(effects
				(font
					(size 1.27 1.27)
					(thickness 0.15)
				)
				(justify mirror)
			)
		)
		(property "MPN" "CR0402-FX-2200GLF"
			(at 0 0 90)
			(unlocked yes)
			(layer "B.Fab")
			(hide yes)
			(effects
				(font
					(size 1 1)
					(thickness 0.15)
				)
				(justify mirror)
			)
		)
		(property "Manufacturer" "Bourns"
			(at 0 0 90)
			(unlocked yes)
			(layer "B.Fab")
			(hide yes)
			(effects
				(font
					(size 1 1)
					(thickness 0.15)
				)
				(justify mirror)
			)
		)
		(property "License" "Apache-2.0"
			(at 0 0 90)
			(unlocked yes)
			(layer "B.Fab")
			(hide yes)
			(effects
				(font
					(size 1 1)
					(thickness 0.15)
				)
				(justify mirror)
			)
		)
		(property "Author" "Antmicro"
			(at 0 0 90)
			(unlocked yes)
			(layer "B.Fab")
			(hide yes)
			(effects
				(font
					(size 1 1)
					(thickness 0.15)
				)
				(justify mirror)
			)
		)
		(property "Val" "220R"
			(at 0 0 90)
			(unlocked yes)
			(layer "B.Fab")
			(hide yes)
			(effects
				(font
					(size 1 1)
					(thickness 0.15)
				)
				(justify mirror)
			)
		)
		(property "Tolerance" "1%"
			(at 0 0 90)
			(unlocked yes)
			(layer "B.Fab")
			(hide yes)
			(effects
				(font
					(size 1 1)
					(thickness 0.15)
				)
				(justify mirror)
			)
		)
		(sheetname "/2xRJ45/")
		(sheetfile "2xrj45.kicad_sch")
		(attr smd)
		(fp_rect
			(start -0.925 0.47)
			(end 0.925 -0.47)
			(stroke
				(width 0.05)
				(type default)
			)
			(fill no)
			(layer "B.CrtYd")
		)
		(fp_rect
			(start -0.5 0.25)
			(end 0.5 -0.25)
			(stroke
				(width 0.15)
				(type solid)
			)
			(fill no)
			(layer "B.Fab")
		)
		(pad "1" smd roundrect
			(at -0.48 0 90)
			(size 0.59 0.64)
			(layers "B.Cu" "B.Mask" "B.Paste")
			(roundrect_rratio 0.25)
			(net 53 "Net-(J3-LED_YG_G-)")
			(pintype "passive")
		)
		(pad "2" smd roundrect
			(at 0.48 0 90)
			(size 0.59 0.64)
			(layers "B.Cu" "B.Mask" "B.Paste")
			(roundrect_rratio 0.25)
			(net 81 "/2xRJ45/~{P0_LED_LINK_10G}")
			(pintype "passive")
		)
	)
	(footprint "antmicro-footprints:TP_SMD_1mm"
		(layer "B.Cu")
		(at 77.99 72.3 -90)
		(property "Reference" "TP27"
			(at -1.81 5.81 90)
			(layer "B.SilkS")
			(effects
				(font
					(size 0.7 0.7)
					(thickness 0.15)
				)
				(justify left bottom mirror)
			)
		)
		(property "Value" "TP_1mm_SMD"
			(at 0 -1.4 90)
			(layer "B.Fab")
			(hide yes)
			(effects
				(font
					(size 0.7 0.7)
					(thickness 0.15)
				)
				(justify left bottom mirror)
			)
		)
		(property "Description" "Test point 1mm SMD"
			(at 0 0 90)
			(layer "B.Fab")
			(hide yes)
			(effects
				(font
					(size 1.27 1.27)
					(thickness 0.15)
				)
				(justify mirror)
			)
		)
		(property "MPN" ""
			(at 0 0 90)
			(unlocked yes)
			(layer "B.Fab")
			(hide yes)
			(effects
				(font
					(size 1 1)
					(thickness 0.15)
				)
				(justify mirror)
			)
		)
		(property "Manufacturer" ""
			(at 0 0 90)
			(unlocked yes)
			(layer "B.Fab")
			(hide yes)
			(effects
				(font
					(size 1 1)
					(thickness 0.15)
				)
				(justify mirror)
			)
		)
		(property "Author" "Antmicro"
			(at 0 0 90)
			(unlocked yes)
			(layer "B.Fab")
			(hide yes)
			(effects
				(font
					(size 1 1)
					(thickness 0.15)
				)
				(justify mirror)
			)
		)
		(property "License" "Apache-2.0"
			(at 0 0 90)
			(unlocked yes)
			(layer "B.Fab")
			(hide yes)
			(effects
				(font
					(size 1 1)
					(thickness 0.15)
				)
				(justify mirror)
			)
		)
		(sheetname "/Power/")
		(sheetfile "power.kicad_sch")
		(attr exclude_from_pos_files exclude_from_bom)
		(fp_circle
			(center 0 0)
			(end 0.6 0)
			(stroke
				(width 0.05)
				(type default)
			)
			(fill no)
			(layer "B.CrtYd")
		)
		(pad "1" smd circle
			(at 0 0 270)
			(size 1 1)
			(layers "B.Cu" "B.Mask")
			(net 350 "/Power/+12V_IN")
			(pinfunction "1")
			(pintype "passive")
		)
	)
	(footprint "antmicro-footprints:R_0402_1005Metric"
		(layer "B.Cu")
		(at 89.725 103.45)
		(descr "Resistor SMD 0402")
		(tags "resistor SMD 0402")
		(property "Reference" "R119"
			(at -1.695 0.58 0)
			(layer "B.SilkS")
			(effects
				(font
					(size 0.7 0.7)
					(thickness 0.15)
				)
				(justify right top mirror)
			)
		)
		(property "Value" "R_1k_0402"
			(at -1.011843 -1.772046 0)
			(layer "B.Fab")
			(hide yes)
			(effects
				(font
					(size 0.7 0.7)
					(thickness 0.15)
				)
				(justify right top mirror)
			)
		)
		(property "Datasheet" "https://www.bourns.com/docs/product-datasheets/cr.pdf"
			(at 0 0 0)
			(layer "B.Fab")
			(hide yes)
			(effects
				(font
					(size 1.27 1.27)
					(thickness 0.15)
				)
				(justify mirror)
			)
		)
		(property "Description" "SMD Chip Resistor, 1 kohm, ± 1%, 63 mW, 0402 [1005 Metric], Thick Film, General Purpose"
			(at 0 0 0)
			(layer "B.Fab")
			(hide yes)
			(effects
				(font
					(size 1.27 1.27)
					(thickness 0.15)
				)
				(justify mirror)
			)
		)
		(property "MPN" "CR0402-FX-1001GLF"
			(at 0 0 0)
			(unlocked yes)
			(layer "B.Fab")
			(hide yes)
			(effects
				(font
					(size 1 1)
					(thickness 0.15)
				)
				(justify mirror)
			)
		)
		(property "Manufacturer" "Bourns"
			(at 0 0 0)
			(unlocked yes)
			(layer "B.Fab")
			(hide yes)
			(effects
				(font
					(size 1 1)
					(thickness 0.15)
				)
				(justify mirror)
			)
		)
		(property "License" "Apache-2.0"
			(at 0 0 0)
			(unlocked yes)
			(layer "B.Fab")
			(hide yes)
			(effects
				(font
					(size 1 1)
					(thickness 0.15)
				)
				(justify mirror)
			)
		)
		(property "Author" "Antmicro"
			(at 0 0 0)
			(unlocked yes)
			(layer "B.Fab")
			(hide yes)
			(effects
				(font
					(size 1 1)
					(thickness 0.15)
				)
				(justify mirror)
			)
		)
		(property "Val" "1k"
			(at 0 0 0)
			(unlocked yes)
			(layer "B.Fab")
			(hide yes)
			(effects
				(font
					(size 1 1)
					(thickness 0.15)
				)
				(justify mirror)
			)
		)
		(property "Tolerance" "1%"
			(at 0 0 0)
			(unlocked yes)
			(layer "B.Fab")
			(hide yes)
			(effects
				(font
					(size 1 1)
					(thickness 0.15)
				)
				(justify mirror)
			)
		)
		(sheetname "/X710-AT2 Misc/")
		(sheetfile "x710-at2-mics.kicad_sch")
		(attr smd)
		(fp_rect
			(start -0.925 0.47)
			(end 0.925 -0.47)
			(stroke
				(width 0.05)
				(type default)
			)
			(fill no)
			(layer "B.CrtYd")
		)
		(fp_rect
			(start -0.5 0.25)
			(end 0.5 -0.25)
			(stroke
				(width 0.15)
				(type solid)
			)
			(fill no)
			(layer "B.Fab")
		)
		(pad "1" smd roundrect
			(at -0.48 0)
			(size 0.59 0.64)
			(layers "B.Cu" "B.Mask" "B.Paste")
			(roundrect_rratio 0.25)
			(net 28 "GND")
			(pintype "passive")
		)
		(pad "2" smd roundrect
			(at 0.48 0)
			(size 0.59 0.64)
			(layers "B.Cu" "B.Mask" "B.Paste")
			(roundrect_rratio 0.25)
			(net 115 "/X710-AT2 Misc/RSVD_J11_VSS")
			(pintype "passive")
		)
	)
	(footprint "antmicro-footprints:R_0402_1005Metric"
		(layer "B.Cu")
		(at 107.2 70.25 -90)
		(descr "Resistor SMD 0402")
		(tags "resistor SMD 0402")
		(property "Reference" "R93"
			(at 0.9 -0.48 90)
			(layer "B.SilkS")
			(effects
				(font
					(size 0.7 0.7)
					(thickness 0.15)
				)
				(justify left bottom mirror)
			)
		)
		(property "Value" "R_10k_0402"
			(at -1.011843 -1.772046 90)
			(layer "B.Fab")
			(hide yes)
			(effects
				(font
					(size 0.7 0.7)
					(thickness 0.15)
				)
				(justify left bottom mirror)
			)
		)
		(property "Datasheet" "https://www.bourns.com/docs/product-datasheets/cr.pdf"
			(at 0 0 90)
			(layer "B.Fab")
			(hide yes)
			(effects
				(font
					(size 1.27 1.27)
					(thickness 0.15)
				)
				(justify mirror)
			)
		)
		(property "Description" "SMD Chip Resistor, 10 kohm, ± 1%, 62.5 mW, 0402 [1005 Metric], Thick Film, General Purpose"
			(at 0 0 90)
			(layer "B.Fab")
			(hide yes)
			(effects
				(font
					(size 1.27 1.27)
					(thickness 0.15)
				)
				(justify mirror)
			)
		)
		(property "MPN" "CR0402-FX-1002GLF"
			(at 0 0 270)
			(unlocked yes)
			(layer "B.Fab")
			(hide yes)
			(effects
				(font
					(size 1 1)
					(thickness 0.15)
				)
				(justify mirror)
			)
		)
		(property "Manufacturer" "Bourns"
			(at 0 0 270)
			(unlocked yes)
			(layer "B.Fab")
			(hide yes)
			(effects
				(font
					(size 1 1)
					(thickness 0.15)
				)
				(justify mirror)
			)
		)
		(property "License" "Apache-2.0"
			(at 0 0 270)
			(unlocked yes)
			(layer "B.Fab")
			(hide yes)
			(effects
				(font
					(size 1 1)
					(thickness 0.15)
				)
				(justify mirror)
			)
		)
		(property "Author" "Antmicro"
			(at 0 0 270)
			(unlocked yes)
			(layer "B.Fab")
			(hide yes)
			(effects
				(font
					(size 1 1)
					(thickness 0.15)
				)
				(justify mirror)
			)
		)
		(property "Val" "10k"
			(at 0 0 270)
			(unlocked yes)
			(layer "B.Fab")
			(hide yes)
			(effects
				(font
					(size 1 1)
					(thickness 0.15)
				)
				(justify mirror)
			)
		)
		(property "Tolerance" "1%"
			(at 0 0 270)
			(unlocked yes)
			(layer "B.Fab")
			(hide yes)
			(effects
				(font
					(size 1 1)
					(thickness 0.15)
				)
				(justify mirror)
			)
		)
		(sheetname "/X710-AT2 Misc/")
		(sheetfile "x710-at2-mics.kicad_sch")
		(attr smd)
		(fp_rect
			(start -0.925 0.47)
			(end 0.925 -0.47)
			(stroke
				(width 0.05)
				(type default)
			)
			(fill no)
			(layer "B.CrtYd")
		)
		(fp_rect
			(start -0.5 0.25)
			(end 0.5 -0.25)
			(stroke
				(width 0.15)
				(type solid)
			)
			(fill no)
			(layer "B.Fab")
		)
		(pad "1" smd roundrect
			(at -0.48 0 270)
			(size 0.59 0.64)
			(layers "B.Cu" "B.Mask" "B.Paste")
			(roundrect_rratio 0.25)
			(net 395 "/OCuLink/SMBus.SDA")
			(pintype "passive")
		)
		(pad "2" smd roundrect
			(at 0.48 0 270)
			(size 0.59 0.64)
			(layers "B.Cu" "B.Mask" "B.Paste")
			(roundrect_rratio 0.25)
			(net 7 "+3V3")
			(pintype "passive")
		)
	)
	(footprint "antmicro-footprints:R_0402_1005Metric"
		(layer "B.Cu")
		(at 109.5 68.6 180)
		(descr "Resistor SMD 0402")
		(tags "resistor SMD 0402")
		(property "Reference" "R165"
			(at -1.44 5.61 0)
			(layer "B.SilkS")
			(effects
				(font
					(size 0.7 0.7)
					(thickness 0.15)
				)
				(justify left bottom mirror)
			)
		)
		(property "Value" "R_10k_0402"
			(at -1.011843 -1.772046 0)
			(layer "B.Fab")
			(hide yes)
			(effects
				(font
					(size 0.7 0.7)
					(thickness 0.15)
				)
				(justify left bottom mirror)
			)
		)
		(property "Datasheet" "https://www.bourns.com/docs/product-datasheets/cr.pdf"
			(at 0 0 0)
			(layer "B.Fab")
			(hide yes)
			(effects
				(font
					(size 1.27 1.27)
					(thickness 0.15)
				)
				(justify mirror)
			)
		)
		(property "Description" "SMD Chip Resistor, 10 kohm, ± 1%, 62.5 mW, 0402 [1005 Metric], Thick Film, General Purpose"
			(at 0 0 0)
			(layer "B.Fab")
			(hide yes)
			(effects
				(font
					(size 1.27 1.27)
					(thickness 0.15)
				)
				(justify mirror)
			)
		)
		(property "MPN" "CR0402-FX-1002GLF"
			(at 0 0 180)
			(unlocked yes)
			(layer "B.Fab")
			(hide yes)
			(effects
				(font
					(size 1 1)
					(thickness 0.15)
				)
				(justify mirror)
			)
		)
		(property "Manufacturer" "Bourns"
			(at 0 0 180)
			(unlocked yes)
			(layer "B.Fab")
			(hide yes)
			(effects
				(font
					(size 1 1)
					(thickness 0.15)
				)
				(justify mirror)
			)
		)
		(property "License" "Apache-2.0"
			(at 0 0 180)
			(unlocked yes)
			(layer "B.Fab")
			(hide yes)
			(effects
				(font
					(size 1 1)
					(thickness 0.15)
				)
				(justify mirror)
			)
		)
		(property "Author" "Antmicro"
			(at 0 0 180)
			(unlocked yes)
			(layer "B.Fab")
			(hide yes)
			(effects
				(font
					(size 1 1)
					(thickness 0.15)
				)
				(justify mirror)
			)
		)
		(property "Val" "10k"
			(at 0 0 180)
			(unlocked yes)
			(layer "B.Fab")
			(hide yes)
			(effects
				(font
					(size 1 1)
					(thickness 0.15)
				)
				(justify mirror)
			)
		)
		(property "Tolerance" "1%"
			(at 0 0 180)
			(unlocked yes)
			(layer "B.Fab")
			(hide yes)
			(effects
				(font
					(size 1 1)
					(thickness 0.15)
				)
				(justify mirror)
			)
		)
		(sheetname "/OCuLink/")
		(sheetfile "oculink.kicad_sch")
		(attr smd exclude_from_pos_files exclude_from_bom dnp)
		(fp_rect
			(start -0.925 0.47)
			(end 0.925 -0.47)
			(stroke
				(width 0.05)
				(type default)
			)
			(fill no)
			(layer "B.CrtYd")
		)
		(fp_rect
			(start -0.5 0.25)
			(end 0.5 -0.25)
			(stroke
				(width 0.15)
				(type solid)
			)
			(fill no)
			(layer "B.Fab")
		)
		(pad "1" smd roundrect
			(at -0.48 0 180)
			(size 0.59 0.64)
			(layers "B.Cu" "B.Mask" "B.Paste")
			(roundrect_rratio 0.25)
			(net 321 "/OCuLink/~{CPRSNT}_R")
			(pintype "passive")
		)
		(pad "2" smd roundrect
			(at 0.48 0 180)
			(size 0.59 0.64)
			(layers "B.Cu" "B.Mask" "B.Paste")
			(roundrect_rratio 0.25)
			(net 7 "+3V3")
			(pintype "passive")
		)
	)
	(footprint "antmicro-footprints:C_0402_1005Metric"
		(layer "B.Cu")
		(at 91.225 102 90)
		(descr "Capacitor SMD 0402")
		(tags "capacitor SMD 0402")
		(property "Reference" "C131"
			(at 9.09 -0.447343 90)
			(layer "B.SilkS")
			(effects
				(font
					(size 0.7 0.7)
					(thickness 0.15)
				)
				(justify right top mirror)
			)
		)
		(property "Value" "C_1u_25V_0402"
			(at -1.022927 -2.155213 90)
			(layer "B.Fab")
			(hide yes)
			(effects
				(font
					(size 0.7 0.7)
					(thickness 0.15)
				)
				(justify right top mirror)
			)
		)
		(property "Datasheet" "https://www.murata.com/products/productdetail?partno=GRM155R61E105KE11%23"
			(at 0 0 90)
			(layer "B.Fab")
			(hide yes)
			(effects
				(font
					(size 1.27 1.27)
					(thickness 0.15)
				)
				(justify mirror)
			)
		)
		(property "Description" "SMD Multilayer Ceramic Capacitor, 1 µF, 25 V, 0402 [1005 Metric], ± 10%, X5R, GRM Series"
			(at 0 0 90)
			(layer "B.Fab")
			(hide yes)
			(effects
				(font
					(size 1.27 1.27)
					(thickness 0.15)
				)
				(justify mirror)
			)
		)
		(property "MPN" "GRM155R61E105KE11J"
			(at 0 0 90)
			(unlocked yes)
			(layer "B.Fab")
			(hide yes)
			(effects
				(font
					(size 1 1)
					(thickness 0.15)
				)
				(justify mirror)
			)
		)
		(property "Manufacturer" "Murata"
			(at 0 0 90)
			(unlocked yes)
			(layer "B.Fab")
			(hide yes)
			(effects
				(font
					(size 1 1)
					(thickness 0.15)
				)
				(justify mirror)
			)
		)
		(property "License" "Apache-2.0"
			(at 0 0 90)
			(unlocked yes)
			(layer "B.Fab")
			(hide yes)
			(effects
				(font
					(size 1 1)
					(thickness 0.15)
				)
				(justify mirror)
			)
		)
		(property "Author" "Antmicro"
			(at 0 0 90)
			(unlocked yes)
			(layer "B.Fab")
			(hide yes)
			(effects
				(font
					(size 1 1)
					(thickness 0.15)
				)
				(justify mirror)
			)
		)
		(property "Val" "1u"
			(at 0 0 90)
			(unlocked yes)
			(layer "B.Fab")
			(hide yes)
			(effects
				(font
					(size 1 1)
					(thickness 0.15)
				)
				(justify mirror)
			)
		)
		(property "Voltage" "25V"
			(at 0 0 90)
			(unlocked yes)
			(layer "B.Fab")
			(hide yes)
			(effects
				(font
					(size 1 1)
					(thickness 0.15)
				)
				(justify mirror)
			)
		)
		(property "Dielectric" "X5R"
			(at 0 0 90)
			(unlocked yes)
			(layer "B.Fab")
			(hide yes)
			(effects
				(font
					(size 1 1)
					(thickness 0.15)
				)
				(justify mirror)
			)
		)
		(sheetname "/X710-AT2 power/")
		(sheetfile "x710-at2-power.kicad_sch")
		(attr smd)
		(fp_rect
			(start -0.925 0.47)
			(end 0.925 -0.47)
			(stroke
				(width 0.05)
				(type default)
			)
			(fill no)
			(layer "B.CrtYd")
		)
		(fp_line
			(start 0.504 -0.248)
			(end -0.494 -0.248)
			(stroke
				(width 0.15)
				(type solid)
			)
			(layer "B.Fab")
		)
		(fp_line
			(start -0.494 -0.248)
			(end -0.494 0.25)
			(stroke
				(width 0.15)
				(type solid)
			)
			(layer "B.Fab")
		)
		(fp_line
			(start 0.504 0.25)
			(end 0.504 -0.248)
			(stroke
				(width 0.15)
				(type solid)
			)
			(layer "B.Fab")
		)
		(fp_line
			(start -0.494 0.25)
			(end 0.504 0.25)
			(stroke
				(width 0.15)
				(type solid)
			)
			(layer "B.Fab")
		)
		(pad "1" smd roundrect
			(at -0.48 0 90)
			(size 0.59 0.64)
			(layers "B.Cu" "B.Mask" "B.Paste")
			(roundrect_rratio 0.25)
			(net 28 "GND")
			(pintype "passive")
		)
		(pad "2" smd roundrect
			(at 0.48 0 90)
			(size 0.59 0.64)
			(layers "B.Cu" "B.Mask" "B.Paste")
			(roundrect_rratio 0.25)
			(net 7 "+3V3")
			(pintype "passive")
		)
	)
	(footprint "antmicro-footprints:C_0402_1005Metric"
		(layer "B.Cu")
		(at 87.225 100.15 90)
		(descr "Capacitor SMD 0402")
		(tags "capacitor SMD 0402")
		(property "Reference" "C111"
			(at 9.81 -0.435 90)
			(layer "B.SilkS")
			(effects
				(font
					(size 0.7 0.7)
					(thickness 0.15)
				)
				(justify right top mirror)
			)
		)
		(property "Value" "C_1u_25V_0402"
			(at -1.022927 -2.155213 90)
			(layer "B.Fab")
			(hide yes)
			(effects
				(font
					(size 0.7 0.7)
					(thickness 0.15)
				)
				(justify right top mirror)
			)
		)
		(property "Datasheet" "https://www.murata.com/products/productdetail?partno=GRM155R61E105KE11%23"
			(at 0 0 90)
			(layer "B.Fab")
			(hide yes)
			(effects
				(font
					(size 1.27 1.27)
					(thickness 0.15)
				)
				(justify mirror)
			)
		)
		(property "Description" "SMD Multilayer Ceramic Capacitor, 1 µF, 25 V, 0402 [1005 Metric], ± 10%, X5R, GRM Series"
			(at 0 0 90)
			(layer "B.Fab")
			(hide yes)
			(effects
				(font
					(size 1.27 1.27)
					(thickness 0.15)
				)
				(justify mirror)
			)
		)
		(property "MPN" "GRM155R61E105KE11J"
			(at 0 0 90)
			(unlocked yes)
			(layer "B.Fab")
			(hide yes)
			(effects
				(font
					(size 1 1)
					(thickness 0.15)
				)
				(justify mirror)
			)
		)
		(property "Manufacturer" "Murata"
			(at 0 0 90)
			(unlocked yes)
			(layer "B.Fab")
			(hide yes)
			(effects
				(font
					(size 1 1)
					(thickness 0.15)
				)
				(justify mirror)
			)
		)
		(property "License" "Apache-2.0"
			(at 0 0 90)
			(unlocked yes)
			(layer "B.Fab")
			(hide yes)
			(effects
				(font
					(size 1 1)
					(thickness 0.15)
				)
				(justify mirror)
			)
		)
		(property "Author" "Antmicro"
			(at 0 0 90)
			(unlocked yes)
			(layer "B.Fab")
			(hide yes)
			(effects
				(font
					(size 1 1)
					(thickness 0.15)
				)
				(justify mirror)
			)
		)
		(property "Val" "1u"
			(at 0 0 90)
			(unlocked yes)
			(layer "B.Fab")
			(hide yes)
			(effects
				(font
					(size 1 1)
					(thickness 0.15)
				)
				(justify mirror)
			)
		)
		(property "Voltage" "25V"
			(at 0 0 90)
			(unlocked yes)
			(layer "B.Fab")
			(hide yes)
			(effects
				(font
					(size 1 1)
					(thickness 0.15)
				)
				(justify mirror)
			)
		)
		(property "Dielectric" "X5R"
			(at 0 0 90)
			(unlocked yes)
			(layer "B.Fab")
			(hide yes)
			(effects
				(font
					(size 1 1)
					(thickness 0.15)
				)
				(justify mirror)
			)
		)
		(sheetname "/X710-AT2 power/")
		(sheetfile "x710-at2-power.kicad_sch")
		(attr smd)
		(fp_rect
			(start -0.925 0.47)
			(end 0.925 -0.47)
			(stroke
				(width 0.05)
				(type default)
			)
			(fill no)
			(layer "B.CrtYd")
		)
		(fp_line
			(start 0.504 -0.248)
			(end -0.494 -0.248)
			(stroke
				(width 0.15)
				(type solid)
			)
			(layer "B.Fab")
		)
		(fp_line
			(start -0.494 -0.248)
			(end -0.494 0.25)
			(stroke
				(width 0.15)
				(type solid)
			)
			(layer "B.Fab")
		)
		(fp_line
			(start 0.504 0.25)
			(end 0.504 -0.248)
			(stroke
				(width 0.15)
				(type solid)
			)
			(layer "B.Fab")
		)
		(fp_line
			(start -0.494 0.25)
			(end 0.504 0.25)
			(stroke
				(width 0.15)
				(type solid)
			)
			(layer "B.Fab")
		)
		(pad "1" smd roundrect
			(at -0.48 0 90)
			(size 0.59 0.64)
			(layers "B.Cu" "B.Mask" "B.Paste")
			(roundrect_rratio 0.25)
			(net 28 "GND")
			(pintype "passive")
		)
		(pad "2" smd roundrect
			(at 0.48 0 90)
			(size 0.59 0.64)
			(layers "B.Cu" "B.Mask" "B.Paste")
			(roundrect_rratio 0.25)
			(net 9 "VCCD")
			(pintype "passive")
		)
	)
	(footprint "antmicro-footprints:USON-10_2.5x1mm_P0.5mm"
		(layer "B.Cu")
		(at 102.747999 55.88366 90)
		(descr "USON-10 2.5x1mm_ Pitch 0.5mm")
		(tags "USON-10 2.5x1mm Pitch 0.5mm")
		(property "Reference" "D4"
			(at -0.90134 -0.747999 0)
			(layer "B.SilkS")
			(effects
				(font
					(size 0.7 0.7)
					(thickness 0.15)
				)
				(justify right top mirror)
			)
		)
		(property "Value" "ESD204DQAR"
			(at 0.018 -2.499 90)
			(layer "B.Fab")
			(hide yes)
			(effects
				(font
					(size 0.7 0.7)
					(thickness 0.15)
				)
				(justify right top mirror)
			)
		)
		(property "Datasheet" "https://www.ti.com/lit/ds/symlink/esd204.pdf?ts=1706004844383&ref_url=https%253A%252F%252Fwww.ti.com%252Finterface%252Fdiodes%252Fesd-protection-diodes%252Fproducts.html"
			(at 0 0 90)
			(layer "B.Fab")
			(hide yes)
			(effects
				(font
					(size 1.27 1.27)
					(thickness 0.15)
				)
				(justify mirror)
			)
		)
		(property "Description" "TVS diode array, 30 kV, USON-10, 3.6 V, 0.55 pF"
			(at 0 0 90)
			(layer "B.Fab")
			(hide yes)
			(effects
				(font
					(size 1.27 1.27)
					(thickness 0.15)
				)
				(justify mirror)
			)
		)
		(property "MPN" "ESD204DQAR"
			(at 0 0 90)
			(unlocked yes)
			(layer "B.Fab")
			(hide yes)
			(effects
				(font
					(size 1 1)
					(thickness 0.15)
				)
				(justify mirror)
			)
		)
		(property "Manufacturer" "Texas Instruments"
			(at 0 0 90)
			(unlocked yes)
			(layer "B.Fab")
			(hide yes)
			(effects
				(font
					(size 1 1)
					(thickness 0.15)
				)
				(justify mirror)
			)
		)
		(property "Author" "Antmicro"
			(at 0 0 90)
			(unlocked yes)
			(layer "B.Fab")
			(hide yes)
			(effects
				(font
					(size 1 1)
					(thickness 0.15)
				)
				(justify mirror)
			)
		)
		(property "License" "Apache-2.0"
			(at 0 0 90)
			(unlocked yes)
			(layer "B.Fab")
			(hide yes)
			(effects
				(font
					(size 1 1)
					(thickness 0.15)
				)
				(justify mirror)
			)
		)
		(sheetname "/OCuLink/")
		(sheetfile "oculink.kicad_sch")
		(attr smd)
		(fp_line
			(start 0.498 -1.398)
			(end -0.5 -1.398)
			(stroke
				(width 0.15)
				(type solid)
			)
			(layer "B.SilkS")
		)
		(fp_line
			(start 0.498 1.401)
			(end -0.5 1.401)
			(stroke
				(width 0.15)
				(type solid)
			)
			(layer "B.SilkS")
		)
		(fp_circle
			(center -0.68 1.27)
			(end -0.63 1.27)
			(stroke
				(width 0.15)
				(type solid)
			)
			(fill yes)
			(layer "B.SilkS")
		)
		(fp_rect
			(start -0.8 1.5)
			(end 0.8 -1.499)
			(stroke
				(width 0.05)
				(type solid)
			)
			(fill no)
			(layer "B.CrtYd")
		)
		(fp_line
			(start -0.5 -1.249)
			(end 0.498 -1.249)
			(stroke
				(width 0.15)
				(type solid)
			)
			(layer "B.Fab")
		)
		(fp_line
			(start -0.5 1)
			(end -0.5 -1.249)
			(stroke
				(width 0.15)
				(type solid)
			)
			(layer "B.Fab")
		)
		(fp_line
			(start 0.498 1.25)
			(end 0.498 -1.249)
			(stroke
				(width 0.15)
				(type solid)
			)
			(layer "B.Fab")
		)
		(fp_line
			(start 0.498 1.25)
			(end -0.25 1.25)
			(stroke
				(width 0.15)
				(type solid)
			)
			(layer "B.Fab")
		)
		(fp_line
			(start -0.25 1.25)
			(end -0.5 1)
			(stroke
				(width 0.15)
				(type solid)
			)
			(layer "B.Fab")
		)
		(pad "1" smd roundrect
			(at -0.387 1 180)
			(size 0.25 0.55)
			(layers "B.Cu" "B.Mask" "B.Paste")
			(roundrect_rratio 0.25)
			(net 39 "/OCuLink/PCIe_{x4}.RX0+")
			(pintype "passive")
		)
		(pad "2" smd roundrect
			(at -0.387 0.5 180)
			(size 0.25 0.55)
			(layers "B.Cu" "B.Mask" "B.Paste")
			(roundrect_rratio 0.25)
			(net 36 "/OCuLink/PCIe_{x4}.RX0-")
			(pintype "passive")
		)
		(pad "3" smd roundrect
			(at -0.387 0 180)
			(size 0.4 0.55)
			(layers "B.Cu" "B.Mask" "B.Paste")
			(roundrect_rratio 0.25)
			(net 28 "GND")
			(pintype "power_in")
		)
		(pad "4" smd roundrect
			(at -0.387 -0.498 180)
			(size 0.25 0.55)
			(layers "B.Cu" "B.Mask" "B.Paste")
			(roundrect_rratio 0.25)
			(net 37 "/OCuLink/PCIe_{x4}.RX1+")
			(pintype "passive")
		)
		(pad "5" smd roundrect
			(at -0.387 -0.998 180)
			(size 0.25 0.55)
			(layers "B.Cu" "B.Mask" "B.Paste")
			(roundrect_rratio 0.25)
			(net 34 "/OCuLink/PCIe_{x4}.RX1-")
			(pintype "passive")
		)
		(pad "6" smd roundrect
			(at 0.385 -0.998 180)
			(size 0.25 0.55)
			(layers "B.Cu" "B.Mask" "B.Paste")
			(roundrect_rratio 0.25)
			(net 34 "/OCuLink/PCIe_{x4}.RX1-")
			(pintype "passive")
		)
		(pad "7" smd roundrect
			(at 0.385 -0.498 180)
			(size 0.25 0.55)
			(layers "B.Cu" "B.Mask" "B.Paste")
			(roundrect_rratio 0.25)
			(net 37 "/OCuLink/PCIe_{x4}.RX1+")
			(pintype "passive")
		)
		(pad "8" smd roundrect
			(at 0.385 0 180)
			(size 0.4 0.55)
			(layers "B.Cu" "B.Mask" "B.Paste")
			(roundrect_rratio 0.25)
			(net 28 "GND")
			(pintype "passive")
		)
		(pad "9" smd roundrect
			(at 0.385 0.5 180)
			(size 0.25 0.55)
			(layers "B.Cu" "B.Mask" "B.Paste")
			(roundrect_rratio 0.25)
			(net 36 "/OCuLink/PCIe_{x4}.RX0-")
			(pintype "passive")
		)
		(pad "10" smd roundrect
			(at 0.385 1 180)
			(size 0.25 0.55)
			(layers "B.Cu" "B.Mask" "B.Paste")
			(roundrect_rratio 0.25)
			(net 39 "/OCuLink/PCIe_{x4}.RX0+")
			(pintype "passive")
		)
	)
	(footprint "antmicro-footprints:C_0402_1005Metric"
		(layer "B.Cu")
		(at 60.67 111.55)
		(descr "Capacitor SMD 0402")
		(tags "capacitor SMD 0402")
		(property "Reference" "C36"
			(at -1.07 0.55 0)
			(layer "B.SilkS")
			(effects
				(font
					(size 0.7 0.7)
					(thickness 0.15)
				)
				(justify right top mirror)
			)
		)
		(property "Value" "C_100n_0402"
			(at -1.022927 -2.155213 0)
			(layer "B.Fab")
			(hide yes)
			(effects
				(font
					(size 0.7 0.7)
					(thickness 0.15)
				)
				(justify right top mirror)
			)
		)
		(property "Datasheet" "https://www.murata.com/products/productdetail?partno=GRM155R61H104KE14%23"
			(at 0 0 0)
			(layer "B.Fab")
			(hide yes)
			(effects
				(font
					(size 1.27 1.27)
					(thickness 0.15)
				)
				(justify mirror)
			)
		)
		(property "Description" "SMD Multilayer Ceramic Capacitor, 0.1 µF, 50 V, 0402 [1005 Metric], ± 10%, X5R, GRM Series"
			(at 0 0 0)
			(layer "B.Fab")
			(hide yes)
			(effects
				(font
					(size 1.27 1.27)
					(thickness 0.15)
				)
				(justify mirror)
			)
		)
		(property "MPN" "GRM155R61H104KE14D"
			(at 0 0 0)
			(unlocked yes)
			(layer "B.Fab")
			(hide yes)
			(effects
				(font
					(size 1 1)
					(thickness 0.15)
				)
				(justify mirror)
			)
		)
		(property "Manufacturer" "Murata"
			(at 0 0 0)
			(unlocked yes)
			(layer "B.Fab")
			(hide yes)
			(effects
				(font
					(size 1 1)
					(thickness 0.15)
				)
				(justify mirror)
			)
		)
		(property "License" "Apache-2.0"
			(at 0 0 0)
			(unlocked yes)
			(layer "B.Fab")
			(hide yes)
			(effects
				(font
					(size 1 1)
					(thickness 0.15)
				)
				(justify mirror)
			)
		)
		(property "Author" "Antmicro"
			(at 0 0 0)
			(unlocked yes)
			(layer "B.Fab")
			(hide yes)
			(effects
				(font
					(size 1 1)
					(thickness 0.15)
				)
				(justify mirror)
			)
		)
		(property "Val" "100n"
			(at 0 0 0)
			(unlocked yes)
			(layer "B.Fab")
			(hide yes)
			(effects
				(font
					(size 1 1)
					(thickness 0.15)
				)
				(justify mirror)
			)
		)
		(property "Voltage" "50V"
			(at 0 0 0)
			(unlocked yes)
			(layer "B.Fab")
			(hide yes)
			(effects
				(font
					(size 1 1)
					(thickness 0.15)
				)
				(justify mirror)
			)
		)
		(property "Dielectric" "X5R"
			(at 0 0 0)
			(unlocked yes)
			(layer "B.Fab")
			(hide yes)
			(effects
				(font
					(size 1 1)
					(thickness 0.15)
				)
				(justify mirror)
			)
		)
		(sheetname "/Power/")
		(sheetfile "power.kicad_sch")
		(attr smd)
		(fp_rect
			(start -0.925 0.47)
			(end 0.925 -0.47)
			(stroke
				(width 0.05)
				(type default)
			)
			(fill no)
			(layer "B.CrtYd")
		)
		(fp_line
			(start -0.494 -0.248)
			(end -0.494 0.25)
			(stroke
				(width 0.15)
				(type solid)
			)
			(layer "B.Fab")
		)
		(fp_line
			(start -0.494 0.25)
			(end 0.504 0.25)
			(stroke
				(width 0.15)
				(type solid)
			)
			(layer "B.Fab")
		)
		(fp_line
			(start 0.504 -0.248)
			(end -0.494 -0.248)
			(stroke
				(width 0.15)
				(type solid)
			)
			(layer "B.Fab")
		)
		(fp_line
			(start 0.504 0.25)
			(end 0.504 -0.248)
			(stroke
				(width 0.15)
				(type solid)
			)
			(layer "B.Fab")
		)
		(pad "1" smd roundrect
			(at -0.48 0)
			(size 0.59 0.64)
			(layers "B.Cu" "B.Mask" "B.Paste")
			(roundrect_rratio 0.25)
			(net 28 "GND")
			(pintype "passive")
		)
		(pad "2" smd roundrect
			(at 0.48 0)
			(size 0.59 0.64)
			(layers "B.Cu" "B.Mask" "B.Paste")
			(roundrect_rratio 0.25)
			(net 312 "/Power/+1V0_OUT")
			(pintype "passive")
		)
	)
	(footprint "antmicro-footprints:TP_SMD_0.75mm"
		(layer "B.Cu")
		(at 74.224997 85.184997 180)
		(property "Reference" "TP37"
			(at 0 0.6 0)
			(layer "B.SilkS")
			(hide yes)
			(effects
				(font
					(size 0.7 0.7)
					(thickness 0.15)
				)
				(justify left bottom mirror)
			)
		)
		(property "Value" "TP_0.75mm_SMD"
			(at 0 -1.2 0)
			(layer "B.Fab")
			(hide yes)
			(effects
				(font
					(size 0.7 0.7)
					(thickness 0.15)
				)
				(justify left bottom mirror)
			)
		)
		(property "Description" "SMT test point"
			(at 0 0 0)
			(layer "B.Fab")
			(hide yes)
			(effects
				(font
					(size 1.27 1.27)
					(thickness 0.15)
				)
				(justify mirror)
			)
		)
		(property "MPN" ""
			(at 0 0 0)
			(unlocked yes)
			(layer "B.Fab")
			(hide yes)
			(effects
				(font
					(size 1 1)
					(thickness 0.15)
				)
				(justify mirror)
			)
		)
		(property "Manufacturer" ""
			(at 0 0 0)
			(unlocked yes)
			(layer "B.Fab")
			(hide yes)
			(effects
				(font
					(size 1 1)
					(thickness 0.15)
				)
				(justify mirror)
			)
		)
		(property "Author" "Antmicro"
			(at 0 0 0)
			(unlocked yes)
			(layer "B.Fab")
			(hide yes)
			(effects
				(font
					(size 1 1)
					(thickness 0.15)
				)
				(justify mirror)
			)
		)
		(property "License" "Apache-2.0"
			(at 0 0 0)
			(unlocked yes)
			(layer "B.Fab")
			(hide yes)
			(effects
				(font
					(size 1 1)
					(thickness 0.15)
				)
				(justify mirror)
			)
		)
		(sheetname "/Power/")
		(sheetfile "power.kicad_sch")
		(attr exclude_from_pos_files exclude_from_bom)
		(fp_circle
			(center 0 0)
			(end 0.475 0)
			(stroke
				(width 0.05)
				(type default)
			)
			(fill no)
			(layer "B.CrtYd")
		)
		(pad "1" smd circle
			(at 0 0 180)
			(size 0.75 0.75)
			(layers "B.Cu" "B.Mask")
			(net 255 "/Power/+3V3_OUT")
			(pinfunction "1")
			(pintype "passive")
		)
	)
	(footprint "antmicro-footprints:SOIC-8_5.3x5.3x2mm_P1.27mm"
		(layer "B.Cu")
		(at 70.15 89.852146 90)
		(descr "8-Pin SOIC 208-mil")
		(property "Reference" "U13"
			(at -1.047854 -3.75 90)
			(layer "B.SilkS")
			(effects
				(font
					(size 0.7 0.7)
					(thickness 0.15)
				)
				(justify right top mirror)
			)
		)
		(property "Value" "AT25DF641A-SH"
			(at 0 -3.8 90)
			(layer "B.Fab")
			(hide yes)
			(effects
				(font
					(size 0.7 0.7)
					(thickness 0.15)
				)
				(justify right top mirror)
			)
		)
		(property "Datasheet" "https://eu.mouser.com/datasheet/3/1166/1/REN_DS-AT25DF641A-8693G-022022_unsecure_DST_20220220_1.pdf"
			(at 0 0 90)
			(layer "B.Fab")
			(hide yes)
			(effects
				(font
					(size 1.27 1.27)
					(thickness 0.15)
				)
				(justify mirror)
			)
		)
		(property "Description" "NOR Flash 64 Mbit, 3.0V (2.7V to 3.6V), -40C to 85C, SOIC-W 208mil (Tape & Reel), Single, Dual SPI NOR flash"
			(at 0 0 90)
			(layer "B.Fab")
			(hide yes)
			(effects
				(font
					(size 1.27 1.27)
					(thickness 0.15)
				)
				(justify mirror)
			)
		)
		(property "MPN" "AT25DF641A-SH-T "
			(at 0 0 90)
			(unlocked yes)
			(layer "B.Fab")
			(hide yes)
			(effects
				(font
					(size 1 1)
					(thickness 0.15)
				)
				(justify mirror)
			)
		)
		(property "Manufacturer" "Renesas"
			(at 0 0 90)
			(unlocked yes)
			(layer "B.Fab")
			(hide yes)
			(effects
				(font
					(size 1 1)
					(thickness 0.15)
				)
				(justify mirror)
			)
		)
		(property "Author" "Antmicro"
			(at 0 0 90)
			(unlocked yes)
			(layer "B.Fab")
			(hide yes)
			(effects
				(font
					(size 1 1)
					(thickness 0.15)
				)
				(justify mirror)
			)
		)
		(property "License" "Apache-2.0"
			(at 0 0 90)
			(unlocked yes)
			(layer "B.Fab")
			(hide yes)
			(effects
				(font
					(size 1 1)
					(thickness 0.15)
				)
				(justify mirror)
			)
		)
		(sheetname "/Flash memory/")
		(sheetfile "flash-memory.kicad_sch")
		(attr smd)
		(fp_line
			(start -2.8 2.641)
			(end -4.4 2.641)
			(stroke
				(width 0.15)
				(type solid)
			)
			(layer "B.SilkS")
		)
		(fp_circle
			(center -4.85 1.905)
			(end -4.8 1.855)
			(stroke
				(width 0.15)
				(type solid)
			)
			(fill yes)
			(layer "B.SilkS")
		)
		(fp_rect
			(start 4.675 3)
			(end -4.675 -3)
			(stroke
				(width 0.05)
				(type solid)
			)
			(fill no)
			(layer "B.CrtYd")
		)
		(fp_line
			(start 2.64 -2.64)
			(end -2.641 -2.64)
			(stroke
				(width 0.15)
				(type solid)
			)
			(layer "B.Fab")
		)
		(fp_line
			(start -2.641 -2.64)
			(end -2.641 2.641)
			(stroke
				(width 0.15)
				(type solid)
			)
			(layer "B.Fab")
		)
		(fp_line
			(start -2.641 1.371)
			(end -1.371 2.641)
			(stroke
				(width 0.15)
				(type solid)
			)
			(layer "B.Fab")
		)
		(fp_line
			(start 2.64 2.641)
			(end 2.64 -2.64)
			(stroke
				(width 0.15)
				(type solid)
			)
			(layer "B.Fab")
		)
		(fp_line
			(start -2.641 2.641)
			(end 2.64 2.641)
			(stroke
				(width 0.15)
				(type solid)
			)
			(layer "B.Fab")
		)
		(pad "1" smd roundrect
			(at -3.601 1.905)
			(size 0.65 1.65)
			(layers "B.Cu" "B.Mask" "B.Paste")
			(roundrect_rratio 0.25)
			(net 105 "/Flash memory/FLASH.~{CE}")
			(pinfunction "~{CS}")
			(pintype "input")
		)
		(pad "2" smd roundrect
			(at -3.601 0.635)
			(size 0.65 1.65)
			(layers "B.Cu" "B.Mask" "B.Paste")
			(roundrect_rratio 0.25)
			(net 140 "/Flash memory/FLASH.MISO")
			(pinfunction "SO")
			(pintype "bidirectional")
		)
		(pad "3" smd roundrect
			(at -3.601 -0.633)
			(size 0.65 1.65)
			(layers "B.Cu" "B.Mask" "B.Paste")
			(roundrect_rratio 0.25)
			(net 72 "/Flash memory/~{WP}")
			(pinfunction "~{WP}")
			(pintype "bidirectional")
		)
		(pad "4" smd roundrect
			(at -3.601 -1.904)
			(size 0.65 1.65)
			(layers "B.Cu" "B.Mask" "B.Paste")
			(roundrect_rratio 0.25)
			(net 28 "GND")
			(pinfunction "GND")
			(pintype "power_in")
		)
		(pad "5" smd roundrect
			(at 3.6 -1.904)
			(size 0.65 1.65)
			(layers "B.Cu" "B.Mask" "B.Paste")
			(roundrect_rratio 0.25)
			(net 139 "/Flash memory/FLASH.MOSI")
			(pinfunction "SI")
			(pintype "bidirectional")
		)
		(pad "6" smd roundrect
			(at 3.6 -0.633)
			(size 0.65 1.65)
			(layers "B.Cu" "B.Mask" "B.Paste")
			(roundrect_rratio 0.25)
			(net 106 "/Flash memory/FLASH.CLK")
			(pinfunction "SCK")
			(pintype "input")
		)
		(pad "7" smd roundrect
			(at 3.6 0.635)
			(size 0.65 1.65)
			(layers "B.Cu" "B.Mask" "B.Paste")
			(roundrect_rratio 0.25)
			(net 71 "/Flash memory/~{HOLD}")
			(pinfunction "~{HOLD}")
			(pintype "bidirectional")
		)
		(pad "8" smd roundrect
			(at 3.6 1.905)
			(size 0.65 1.65)
			(layers "B.Cu" "B.Mask" "B.Paste")
			(roundrect_rratio 0.25)
			(net 110 "/Flash memory/+3V3_FLASH")
			(pinfunction "VCC")
			(pintype "power_in")
		)
	)
	(footprint "antmicro-footprints:R_0402_1005Metric"
		(layer "B.Cu")
		(at 102.08 89.214 180)
		(descr "Resistor SMD 0402")
		(tags "resistor SMD 0402")
		(property "Reference" "R124"
			(at -1.87 -2.736 0)
			(layer "B.SilkS")
			(effects
				(font
					(size 0.7 0.7)
					(thickness 0.15)
				)
				(justify left bottom mirror)
			)
		)
		(property "Value" "R_33R_0402"
			(at -1.011843 -1.772047 0)
			(layer "B.Fab")
			(hide yes)
			(effects
				(font
					(size 0.7 0.7)
					(thickness 0.15)
				)
				(justify left bottom mirror)
			)
		)
		(property "Datasheet" "https://www.bourns.com/docs/product-datasheets/cr.pdf"
			(at 0 0 0)
			(layer "B.Fab")
			(hide yes)
			(effects
				(font
					(size 1.27 1.27)
					(thickness 0.15)
				)
				(justify mirror)
			)
		)
		(property "Description" "SMD Chip Resistor, 33 ohm, ± 1%, 62.5 mW, 0402 [1005 Metric], Thick Film, General Purpose"
			(at 0 0 0)
			(layer "B.Fab")
			(hide yes)
			(effects
				(font
					(size 1.27 1.27)
					(thickness 0.15)
				)
				(justify mirror)
			)
		)
		(property "MPN" "CR0402-FX-33R0GLF"
			(at 0 0 0)
			(unlocked yes)
			(layer "B.Fab")
			(hide yes)
			(effects
				(font
					(size 1 1)
					(thickness 0.15)
				)
				(justify mirror)
			)
		)
		(property "Manufacturer" "Bourns"
			(at 0 0 0)
			(unlocked yes)
			(layer "B.Fab")
			(hide yes)
			(effects
				(font
					(size 1 1)
					(thickness 0.15)
				)
				(justify mirror)
			)
		)
		(property "License" "Apache-2.0"
			(at 0 0 0)
			(unlocked yes)
			(layer "B.Fab")
			(hide yes)
			(effects
				(font
					(size 1 1)
					(thickness 0.15)
				)
				(justify mirror)
			)
		)
		(property "Author" "Antmicro"
			(at 0 0 0)
			(unlocked yes)
			(layer "B.Fab")
			(hide yes)
			(effects
				(font
					(size 1 1)
					(thickness 0.15)
				)
				(justify mirror)
			)
		)
		(property "Val" "33R"
			(at 0 0 0)
			(unlocked yes)
			(layer "B.Fab")
			(hide yes)
			(effects
				(font
					(size 1 1)
					(thickness 0.15)
				)
				(justify mirror)
			)
		)
		(property "Tolerance" "1%"
			(at 0 0 0)
			(unlocked yes)
			(layer "B.Fab")
			(hide yes)
			(effects
				(font
					(size 1 1)
					(thickness 0.15)
				)
				(justify mirror)
			)
		)
		(sheetname "/X710-AT2 PCIe/")
		(sheetfile "x710-at2-pcie.kicad_sch")
		(attr smd exclude_from_pos_files exclude_from_bom dnp)
		(fp_rect
			(start -0.925 0.47)
			(end 0.925 -0.47)
			(stroke
				(width 0.05)
				(type default)
			)
			(fill no)
			(layer "B.CrtYd")
		)
		(fp_rect
			(start -0.5 0.25)
			(end 0.5 -0.25)
			(stroke
				(width 0.15)
				(type solid)
			)
			(fill no)
			(layer "B.Fab")
		)
		(pad "1" smd roundrect
			(at -0.48 0 180)
			(size 0.59 0.64)
			(layers "B.Cu" "B.Mask" "B.Paste")
			(roundrect_rratio 0.25)
			(net 408 "/X710-AT2 PCIe/GEN_CLK-")
			(pintype "passive")
		)
		(pad "2" smd roundrect
			(at 0.48 0 180)
			(size 0.59 0.64)
			(layers "B.Cu" "B.Mask" "B.Paste")
			(roundrect_rratio 0.25)
			(net 406 "/X710-AT2 PCIe/GEN_F_CLK-")
			(pintype "passive")
		)
	)
	(footprint "antmicro-footprints:SOT-416"
		(layer "B.Cu")
		(at 56.25 118.05)
		(descr "SOT-416")
		(tags "SOT-416")
		(property "Reference" "Q9"
			(at 1.169999 0.8 270)
			(layer "B.SilkS")
			(effects
				(font
					(size 0.7 0.7)
					(thickness 0.15)
				)
				(justify right top mirror)
			)
		)
		(property "Value" "DTC014T_SOT-416"
			(at 0 -2.000001 0)
			(layer "B.Fab")
			(hide yes)
			(effects
				(font
					(size 0.7 0.7)
					(thickness 0.15)
				)
				(justify right top mirror)
			)
		)
		(property "Datasheet" "https://www.rohm.com/datasheet?p=DTC014TEB&dist=Mouser&media=referral&source=mouser.com&campaign=Mouser"
			(at 0 0 0)
			(layer "B.Fab")
			(hide yes)
			(effects
				(font
					(size 1.27 1.27)
					(thickness 0.15)
				)
				(justify mirror)
			)
		)
		(property "Description" "Bipolar (BJT) Single Transistor with built-in base resistor, NPN, 50V, 100mA, 150mW, SOT-416FL, Surface Mount"
			(at 0 0 0)
			(layer "B.Fab")
			(hide yes)
			(effects
				(font
					(size 1.27 1.27)
					(thickness 0.15)
				)
				(justify mirror)
			)
		)
		(property "Manufacturer" "ROHM Semiconductor"
			(at 0 0 180)
			(unlocked yes)
			(layer "B.Fab")
			(hide yes)
			(effects
				(font
					(size 1 1)
					(thickness 0.15)
				)
				(justify mirror)
			)
		)
		(property "MPN" "DTC014TEBTL"
			(at 0 0 180)
			(unlocked yes)
			(layer "B.Fab")
			(hide yes)
			(effects
				(font
					(size 1 1)
					(thickness 0.15)
				)
				(justify mirror)
			)
		)
		(property "Author" "Antmicro"
			(at 0 0 180)
			(unlocked yes)
			(layer "B.Fab")
			(hide yes)
			(effects
				(font
					(size 1 1)
					(thickness 0.15)
				)
				(justify mirror)
			)
		)
		(property "License" "Apache-2.0"
			(at 0 0 180)
			(unlocked yes)
			(layer "B.Fab")
			(hide yes)
			(effects
				(font
					(size 1 1)
					(thickness 0.15)
				)
				(justify mirror)
			)
		)
		(sheetname "/Power/")
		(sheetfile "power.kicad_sch")
		(attr smd)
		(fp_line
			(start -0.5 0.15)
			(end -0.5 -0.15)
			(stroke
				(width 0.15)
				(type solid)
			)
			(layer "B.SilkS")
		)
		(fp_line
			(start 0.5 -0.9)
			(end -0.5 -0.9)
			(stroke
				(width 0.15)
				(type solid)
			)
			(layer "B.SilkS")
		)
		(fp_line
			(start 0.5 -0.9)
			(end 0.5 -0.7)
			(stroke
				(width 0.15)
				(type solid)
			)
			(layer "B.SilkS")
		)
		(fp_line
			(start 0.508 0.9)
			(end -0.5 0.9)
			(stroke
				(width 0.15)
				(type solid)
			)
			(layer "B.SilkS")
		)
		(fp_line
			(start 0.508 0.9)
			(end 0.508 0.592)
			(stroke
				(width 0.15)
				(type solid)
			)
			(layer "B.SilkS")
		)
		(fp_rect
			(start -1 1.05)
			(end 1 -1.05)
			(stroke
				(width 0.05)
				(type solid)
			)
			(fill no)
			(layer "B.CrtYd")
		)
		(fp_line
			(start -0.05 0.9)
			(end -0.45 0.5)
			(stroke
				(width 0.15)
				(type solid)
			)
			(layer "B.Fab")
		)
		(fp_rect
			(start 0.45 -0.9)
			(end -0.45 0.9)
			(stroke
				(width 0.15)
				(type solid)
			)
			(fill no)
			(layer "B.Fab")
		)
		(fp_text user "License: Apache-2.0"
			(at -1 -5.802 180)
			(layer "B.Fab")
			(effects
				(font
					(size 0.7 0.7)
					(thickness 0.15)
				)
				(justify left bottom mirror)
			)
		)
		(fp_text user "${REFERENCE}"
			(at -1 -3.4 180)
			(layer "B.Fab")
			(effects
				(font
					(size 0.7 0.7)
					(thickness 0.15)
				)
				(justify left bottom mirror)
			)
		)
		(fp_text user "Author: Antmicro"
			(at -1 -4.602 180)
			(layer "B.Fab")
			(effects
				(font
					(size 0.7 0.7)
					(thickness 0.15)
				)
				(justify left bottom mirror)
			)
		)
		(pad "1" smd rect
			(at -0.652 0.5)
			(size 0.6 0.5)
			(layers "B.Cu" "B.Mask" "B.Paste")
			(net 311 "/Power/+DVDD_OUT")
			(pinfunction "B")
			(pintype "input")
		)
		(pad "2" smd rect
			(at -0.652 -0.498)
			(size 0.6 0.5)
			(layers "B.Cu" "B.Mask" "B.Paste")
			(net 28 "GND")
			(pinfunction "E")
			(pintype "passive")
		)
		(pad "3" smd rect
			(at 0.65 0)
			(size 0.6 0.5)
			(layers "B.Cu" "B.Mask" "B.Paste")
			(net 419 "Net-(Q9-C)")
			(pinfunction "C")
			(pintype "passive")
		)
	)
	(footprint "antmicro-footprints:R_0402_1005Metric"
		(layer "B.Cu")
		(at 73.75 88.9 -90)
		(descr "Resistor SMD 0402")
		(tags "resistor SMD 0402")
		(property "Reference" "R34"
			(at -1.1 -0.6 90)
			(layer "B.SilkS")
			(effects
				(font
					(size 0.7 0.7)
					(thickness 0.15)
				)
				(justify left top mirror)
			)
		)
		(property "Value" "R_10k_0402"
			(at -1.011843 -1.772046 90)
			(layer "B.Fab")
			(hide yes)
			(effects
				(font
					(size 0.7 0.7)
					(thickness 0.15)
				)
				(justify left bottom mirror)
			)
		)
		(property "Datasheet" "https://www.bourns.com/docs/product-datasheets/cr.pdf"
			(at 0 0 90)
			(layer "B.Fab")
			(hide yes)
			(effects
				(font
					(size 1.27 1.27)
					(thickness 0.15)
				)
				(justify mirror)
			)
		)
		(property "Description" "SMD Chip Resistor, 10 kohm, ± 1%, 62.5 mW, 0402 [1005 Metric], Thick Film, General Purpose"
			(at 0 0 90)
			(layer "B.Fab")
			(hide yes)
			(effects
				(font
					(size 1.27 1.27)
					(thickness 0.15)
				)
				(justify mirror)
			)
		)
		(property "MPN" "CR0402-FX-1002GLF"
			(at 0 0 270)
			(unlocked yes)
			(layer "B.Fab")
			(hide yes)
			(effects
				(font
					(size 1 1)
					(thickness 0.15)
				)
				(justify mirror)
			)
		)
		(property "Manufacturer" "Bourns"
			(at 0 0 270)
			(unlocked yes)
			(layer "B.Fab")
			(hide yes)
			(effects
				(font
					(size 1 1)
					(thickness 0.15)
				)
				(justify mirror)
			)
		)
		(property "License" "Apache-2.0"
			(at 0 0 270)
			(unlocked yes)
			(layer "B.Fab")
			(hide yes)
			(effects
				(font
					(size 1 1)
					(thickness 0.15)
				)
				(justify mirror)
			)
		)
		(property "Author" "Antmicro"
			(at 0 0 270)
			(unlocked yes)
			(layer "B.Fab")
			(hide yes)
			(effects
				(font
					(size 1 1)
					(thickness 0.15)
				)
				(justify mirror)
			)
		)
		(property "Val" "10k"
			(at 0 0 270)
			(unlocked yes)
			(layer "B.Fab")
			(hide yes)
			(effects
				(font
					(size 1 1)
					(thickness 0.15)
				)
				(justify mirror)
			)
		)
		(property "Tolerance" "1%"
			(at 0 0 270)
			(unlocked yes)
			(layer "B.Fab")
			(hide yes)
			(effects
				(font
					(size 1 1)
					(thickness 0.15)
				)
				(justify mirror)
			)
		)
		(sheetname "/Flash memory/")
		(sheetfile "flash-memory.kicad_sch")
		(attr smd)
		(fp_rect
			(start -0.925 0.47)
			(end 0.925 -0.47)
			(stroke
				(width 0.05)
				(type default)
			)
			(fill no)
			(layer "B.CrtYd")
		)
		(fp_rect
			(start -0.5 0.25)
			(end 0.5 -0.25)
			(stroke
				(width 0.15)
				(type solid)
			)
			(fill no)
			(layer "B.Fab")
		)
		(pad "1" smd roundrect
			(at -0.48 0 270)
			(size 0.59 0.64)
			(layers "B.Cu" "B.Mask" "B.Paste")
			(roundrect_rratio 0.25)
			(net 71 "/Flash memory/~{HOLD}")
			(pintype "passive")
		)
		(pad "2" smd roundrect
			(at 0.48 0 270)
			(size 0.59 0.64)
			(layers "B.Cu" "B.Mask" "B.Paste")
			(roundrect_rratio 0.25)
			(net 110 "/Flash memory/+3V3_FLASH")
			(pintype "passive")
		)
	)
	(footprint "antmicro-footprints:C_0402_1005Metric"
		(layer "B.Cu")
		(at 103.95 131.4 180)
		(descr "Capacitor SMD 0402")
		(tags "capacitor SMD 0402")
		(property "Reference" "C67"
			(at -2.99 -0.45 0)
			(layer "B.SilkS")
			(effects
				(font
					(size 0.7 0.7)
					(thickness 0.15)
				)
				(justify left bottom mirror)
			)
		)
		(property "Value" "C_1u_25V_0402"
			(at -1.022927 -2.155213 0)
			(layer "B.Fab")
			(hide yes)
			(effects
				(font
					(size 0.7 0.7)
					(thickness 0.15)
				)
				(justify left bottom mirror)
			)
		)
		(property "Datasheet" "https://www.murata.com/products/productdetail?partno=GRM155R61E105KE11%23"
			(at 0 0 0)
			(layer "B.Fab")
			(hide yes)
			(effects
				(font
					(size 1.27 1.27)
					(thickness 0.15)
				)
				(justify mirror)
			)
		)
		(property "Description" "SMD Multilayer Ceramic Capacitor, 1 µF, 25 V, 0402 [1005 Metric], ± 10%, X5R, GRM Series"
			(at 0 0 0)
			(layer "B.Fab")
			(hide yes)
			(effects
				(font
					(size 1.27 1.27)
					(thickness 0.15)
				)
				(justify mirror)
			)
		)
		(property "MPN" "GRM155R61E105KE11J"
			(at 0 0 180)
			(unlocked yes)
			(layer "B.Fab")
			(hide yes)
			(effects
				(font
					(size 1 1)
					(thickness 0.15)
				)
				(justify mirror)
			)
		)
		(property "Manufacturer" "Murata"
			(at 0 0 180)
			(unlocked yes)
			(layer "B.Fab")
			(hide yes)
			(effects
				(font
					(size 1 1)
					(thickness 0.15)
				)
				(justify mirror)
			)
		)
		(property "License" "Apache-2.0"
			(at 0 0 180)
			(unlocked yes)
			(layer "B.Fab")
			(hide yes)
			(effects
				(font
					(size 1 1)
					(thickness 0.15)
				)
				(justify mirror)
			)
		)
		(property "Author" "Antmicro"
			(at 0 0 180)
			(unlocked yes)
			(layer "B.Fab")
			(hide yes)
			(effects
				(font
					(size 1 1)
					(thickness 0.15)
				)
				(justify mirror)
			)
		)
		(property "Val" "1u"
			(at 0 0 180)
			(unlocked yes)
			(layer "B.Fab")
			(hide yes)
			(effects
				(font
					(size 1 1)
					(thickness 0.15)
				)
				(justify mirror)
			)
		)
		(property "Voltage" "25V"
			(at 0 0 180)
			(unlocked yes)
			(layer "B.Fab")
			(hide yes)
			(effects
				(font
					(size 1 1)
					(thickness 0.15)
				)
				(justify mirror)
			)
		)
		(property "Dielectric" "X5R"
			(at 0 0 180)
			(unlocked yes)
			(layer "B.Fab")
			(hide yes)
			(effects
				(font
					(size 1 1)
					(thickness 0.15)
				)
				(justify mirror)
			)
		)
		(sheetname "/2xRJ45/")
		(sheetfile "2xrj45.kicad_sch")
		(attr smd)
		(fp_rect
			(start -0.925 0.47)
			(end 0.925 -0.47)
			(stroke
				(width 0.05)
				(type default)
			)
			(fill no)
			(layer "B.CrtYd")
		)
		(fp_line
			(start 0.504 0.25)
			(end 0.504 -0.248)
			(stroke
				(width 0.15)
				(type solid)
			)
			(layer "B.Fab")
		)
		(fp_line
			(start 0.504 -0.248)
			(end -0.494 -0.248)
			(stroke
				(width 0.15)
				(type solid)
			)
			(layer "B.Fab")
		)
		(fp_line
			(start -0.494 0.25)
			(end 0.504 0.25)
			(stroke
				(width 0.15)
				(type solid)
			)
			(layer "B.Fab")
		)
		(fp_line
			(start -0.494 -0.248)
			(end -0.494 0.25)
			(stroke
				(width 0.15)
				(type solid)
			)
			(layer "B.Fab")
		)
		(pad "1" smd roundrect
			(at -0.48 0 180)
			(size 0.59 0.64)
			(layers "B.Cu" "B.Mask" "B.Paste")
			(roundrect_rratio 0.25)
			(net 28 "GND")
			(pintype "passive")
		)
		(pad "2" smd roundrect
			(at 0.48 0 180)
			(size 0.59 0.64)
			(layers "B.Cu" "B.Mask" "B.Paste")
			(roundrect_rratio 0.25)
			(net 300 "/2xRJ45/P1_CT")
			(pintype "passive")
		)
	)
	(footprint "antmicro-footprints:C_0402_1005Metric"
		(layer "B.Cu")
		(at 90.225 94.6 90)
		(descr "Capacitor SMD 0402")
		(tags "capacitor SMD 0402")
		(property "Reference" "C133"
			(at 12.5 -0.462343 90)
			(layer "B.SilkS")
			(effects
				(font
					(size 0.7 0.7)
					(thickness 0.15)
				)
				(justify right top mirror)
			)
		)
		(property "Value" "C_1u_25V_0402"
			(at -1.022927 -2.155213 90)
			(layer "B.Fab")
			(hide yes)
			(effects
				(font
					(size 0.7 0.7)
					(thickness 0.15)
				)
				(justify right top mirror)
			)
		)
		(property "Datasheet" "https://www.murata.com/products/productdetail?partno=GRM155R61E105KE11%23"
			(at 0 0 90)
			(layer "B.Fab")
			(hide yes)
			(effects
				(font
					(size 1.27 1.27)
					(thickness 0.15)
				)
				(justify mirror)
			)
		)
		(property "Description" "SMD Multilayer Ceramic Capacitor, 1 µF, 25 V, 0402 [1005 Metric], ± 10%, X5R, GRM Series"
			(at 0 0 90)
			(layer "B.Fab")
			(hide yes)
			(effects
				(font
					(size 1.27 1.27)
					(thickness 0.15)
				)
				(justify mirror)
			)
		)
		(property "MPN" "GRM155R61E105KE11J"
			(at 0 0 90)
			(unlocked yes)
			(layer "B.Fab")
			(hide yes)
			(effects
				(font
					(size 1 1)
					(thickness 0.15)
				)
				(justify mirror)
			)
		)
		(property "Manufacturer" "Murata"
			(at 0 0 90)
			(unlocked yes)
			(layer "B.Fab")
			(hide yes)
			(effects
				(font
					(size 1 1)
					(thickness 0.15)
				)
				(justify mirror)
			)
		)
		(property "License" "Apache-2.0"
			(at 0 0 90)
			(unlocked yes)
			(layer "B.Fab")
			(hide yes)
			(effects
				(font
					(size 1 1)
					(thickness 0.15)
				)
				(justify mirror)
			)
		)
		(property "Author" "Antmicro"
			(at 0 0 90)
			(unlocked yes)
			(layer "B.Fab")
			(hide yes)
			(effects
				(font
					(size 1 1)
					(thickness 0.15)
				)
				(justify mirror)
			)
		)
		(property "Val" "1u"
			(at 0 0 90)
			(unlocked yes)
			(layer "B.Fab")
			(hide yes)
			(effects
				(font
					(size 1 1)
					(thickness 0.15)
				)
				(justify mirror)
			)
		)
		(property "Voltage" "25V"
			(at 0 0 90)
			(unlocked yes)
			(layer "B.Fab")
			(hide yes)
			(effects
				(font
					(size 1 1)
					(thickness 0.15)
				)
				(justify mirror)
			)
		)
		(property "Dielectric" "X5R"
			(at 0 0 90)
			(unlocked yes)
			(layer "B.Fab")
			(hide yes)
			(effects
				(font
					(size 1 1)
					(thickness 0.15)
				)
				(justify mirror)
			)
		)
		(sheetname "/X710-AT2 power/")
		(sheetfile "x710-at2-power.kicad_sch")
		(attr smd)
		(fp_rect
			(start -0.925 0.47)
			(end 0.925 -0.47)
			(stroke
				(width 0.05)
				(type default)
			)
			(fill no)
			(layer "B.CrtYd")
		)
		(fp_line
			(start 0.504 -0.248)
			(end -0.494 -0.248)
			(stroke
				(width 0.15)
				(type solid)
			)
			(layer "B.Fab")
		)
		(fp_line
			(start -0.494 -0.248)
			(end -0.494 0.25)
			(stroke
				(width 0.15)
				(type solid)
			)
			(layer "B.Fab")
		)
		(fp_line
			(start 0.504 0.25)
			(end 0.504 -0.248)
			(stroke
				(width 0.15)
				(type solid)
			)
			(layer "B.Fab")
		)
		(fp_line
			(start -0.494 0.25)
			(end 0.504 0.25)
			(stroke
				(width 0.15)
				(type solid)
			)
			(layer "B.Fab")
		)
		(pad "1" smd roundrect
			(at -0.48 0 90)
			(size 0.59 0.64)
			(layers "B.Cu" "B.Mask" "B.Paste")
			(roundrect_rratio 0.25)
			(net 28 "GND")
			(pintype "passive")
		)
		(pad "2" smd roundrect
			(at 0.48 0 90)
			(size 0.59 0.64)
			(layers "B.Cu" "B.Mask" "B.Paste")
			(roundrect_rratio 0.25)
			(net 7 "+3V3")
			(pintype "passive")
		)
	)
	(footprint "antmicro-footprints:R_0402_1005Metric"
		(layer "B.Cu")
		(at 96.88 110.95)
		(descr "Resistor SMD 0402")
		(tags "resistor SMD 0402")
		(property "Reference" "R112"
			(at -3.61 -0.34 0)
			(layer "B.SilkS")
			(effects
				(font
					(size 0.7 0.7)
					(thickness 0.15)
				)
				(justify right top mirror)
			)
		)
		(property "Value" "R_1k_0402"
			(at -1.011843 -1.772046 0)
			(layer "B.Fab")
			(hide yes)
			(effects
				(font
					(size 0.7 0.7)
					(thickness 0.15)
				)
				(justify right top mirror)
			)
		)
		(property "Datasheet" "https://www.bourns.com/docs/product-datasheets/cr.pdf"
			(at 0 0 0)
			(layer "B.Fab")
			(hide yes)
			(effects
				(font
					(size 1.27 1.27)
					(thickness 0.15)
				)
				(justify mirror)
			)
		)
		(property "Description" "SMD Chip Resistor, 1 kohm, ± 1%, 63 mW, 0402 [1005 Metric], Thick Film, General Purpose"
			(at 0 0 0)
			(layer "B.Fab")
			(hide yes)
			(effects
				(font
					(size 1.27 1.27)
					(thickness 0.15)
				)
				(justify mirror)
			)
		)
		(property "MPN" "CR0402-FX-1001GLF"
			(at 0 0 0)
			(unlocked yes)
			(layer "B.Fab")
			(hide yes)
			(effects
				(font
					(size 1 1)
					(thickness 0.15)
				)
				(justify mirror)
			)
		)
		(property "Manufacturer" "Bourns"
			(at 0 0 0)
			(unlocked yes)
			(layer "B.Fab")
			(hide yes)
			(effects
				(font
					(size 1 1)
					(thickness 0.15)
				)
				(justify mirror)
			)
		)
		(property "License" "Apache-2.0"
			(at 0 0 0)
			(unlocked yes)
			(layer "B.Fab")
			(hide yes)
			(effects
				(font
					(size 1 1)
					(thickness 0.15)
				)
				(justify mirror)
			)
		)
		(property "Author" "Antmicro"
			(at 0 0 0)
			(unlocked yes)
			(layer "B.Fab")
			(hide yes)
			(effects
				(font
					(size 1 1)
					(thickness 0.15)
				)
				(justify mirror)
			)
		)
		(property "Val" "1k"
			(at 0 0 0)
			(unlocked yes)
			(layer "B.Fab")
			(hide yes)
			(effects
				(font
					(size 1 1)
					(thickness 0.15)
				)
				(justify mirror)
			)
		)
		(property "Tolerance" "1%"
			(at 0 0 0)
			(unlocked yes)
			(layer "B.Fab")
			(hide yes)
			(effects
				(font
					(size 1 1)
					(thickness 0.15)
				)
				(justify mirror)
			)
		)
		(sheetname "/X710-AT2 Misc/")
		(sheetfile "x710-at2-mics.kicad_sch")
		(attr smd)
		(fp_rect
			(start -0.925 0.47)
			(end 0.925 -0.47)
			(stroke
				(width 0.05)
				(type default)
			)
			(fill no)
			(layer "B.CrtYd")
		)
		(fp_rect
			(start -0.5 0.25)
			(end 0.5 -0.25)
			(stroke
				(width 0.15)
				(type solid)
			)
			(fill no)
			(layer "B.Fab")
		)
		(pad "1" smd roundrect
			(at -0.48 0)
			(size 0.59 0.64)
			(layers "B.Cu" "B.Mask" "B.Paste")
			(roundrect_rratio 0.25)
			(net 287 "/X710-AT2 10GbE/~{P1_INT}")
			(pintype "passive")
		)
		(pad "2" smd roundrect
			(at 0.48 0)
			(size 0.59 0.64)
			(layers "B.Cu" "B.Mask" "B.Paste")
			(roundrect_rratio 0.25)
			(net 7 "+3V3")
			(pintype "passive")
		)
	)
	(footprint "antmicro-footprints:R_0402_1005Metric"
		(layer "B.Cu")
		(at 96.45 100.1)
		(descr "Resistor SMD 0402")
		(tags "resistor SMD 0402")
		(property "Reference" "R61"
			(at 0.9 -0.327778 0)
			(layer "B.SilkS")
			(effects
				(font
					(size 0.7 0.7)
					(thickness 0.15)
				)
				(justify right top mirror)
			)
		)
		(property "Value" "R_3k3_0402"
			(at -1.011843 -1.772046 0)
			(layer "B.Fab")
			(hide yes)
			(effects
				(font
					(size 0.7 0.7)
					(thickness 0.15)
				)
				(justify right top mirror)
			)
		)
		(property "Datasheet" "https://www.bourns.com/docs/product-datasheets/cr.pdf"
			(at 0 0 0)
			(layer "B.Fab")
			(hide yes)
			(effects
				(font
					(size 1.27 1.27)
					(thickness 0.15)
				)
				(justify mirror)
			)
		)
		(property "Description" "SMD Chip Resistor, 3.3 kohm, ± 1%, 63 mW, 0402 [1005 Metric], Thick Film, General Purpose"
			(at 0 0 0)
			(layer "B.Fab")
			(hide yes)
			(effects
				(font
					(size 1.27 1.27)
					(thickness 0.15)
				)
				(justify mirror)
			)
		)
		(property "MPN" "CR0402-FX-3301GLF"
			(at 0 0 0)
			(unlocked yes)
			(layer "B.Fab")
			(hide yes)
			(effects
				(font
					(size 1 1)
					(thickness 0.15)
				)
				(justify mirror)
			)
		)
		(property "Manufacturer" "Bourns"
			(at 0 0 0)
			(unlocked yes)
			(layer "B.Fab")
			(hide yes)
			(effects
				(font
					(size 1 1)
					(thickness 0.15)
				)
				(justify mirror)
			)
		)
		(property "License" "Apache-2.0"
			(at 0 0 0)
			(unlocked yes)
			(layer "B.Fab")
			(hide yes)
			(effects
				(font
					(size 1 1)
					(thickness 0.15)
				)
				(justify mirror)
			)
		)
		(property "Author" "Antmicro"
			(at 0 0 0)
			(unlocked yes)
			(layer "B.Fab")
			(hide yes)
			(effects
				(font
					(size 1 1)
					(thickness 0.15)
				)
				(justify mirror)
			)
		)
		(property "Val" "3k3"
			(at 0 0 0)
			(unlocked yes)
			(layer "B.Fab")
			(hide yes)
			(effects
				(font
					(size 1 1)
					(thickness 0.15)
				)
				(justify mirror)
			)
		)
		(property "Tolerance" "1%"
			(at 0 0 0)
			(unlocked yes)
			(layer "B.Fab")
			(hide yes)
			(effects
				(font
					(size 1 1)
					(thickness 0.15)
				)
				(justify mirror)
			)
		)
		(sheetname "/X710-AT2 10GbE/")
		(sheetfile "x710-at2-10gbe.kicad_sch")
		(attr smd)
		(fp_rect
			(start -0.925 0.47)
			(end 0.925 -0.47)
			(stroke
				(width 0.05)
				(type default)
			)
			(fill no)
			(layer "B.CrtYd")
		)
		(fp_rect
			(start -0.5 0.25)
			(end 0.5 -0.25)
			(stroke
				(width 0.15)
				(type solid)
			)
			(fill no)
			(layer "B.Fab")
		)
		(pad "1" smd roundrect
			(at -0.48 0)
			(size 0.59 0.64)
			(layers "B.Cu" "B.Mask" "B.Paste")
			(roundrect_rratio 0.25)
			(net 96 "/X710-AT2 10GbE/MDC2_SCL2")
			(pintype "passive")
		)
		(pad "2" smd roundrect
			(at 0.48 0)
			(size 0.59 0.64)
			(layers "B.Cu" "B.Mask" "B.Paste")
			(roundrect_rratio 0.25)
			(net 7 "+3V3")
			(pintype "passive")
		)
	)
	(footprint "antmicro-footprints:TP_SMD_1mm"
		(layer "B.Cu")
		(at 77.99 74.55 -90)
		(property "Reference" "TP30"
			(at -1.04 5.811898 90)
			(layer "B.SilkS")
			(effects
				(font
					(size 0.7 0.7)
					(thickness 0.15)
				)
				(justify left bottom mirror)
			)
		)
		(property "Value" "TP_1mm_SMD"
			(at 0 -1.4 90)
			(layer "B.Fab")
			(hide yes)
			(effects
				(font
					(size 0.7 0.7)
					(thickness 0.15)
				)
				(justify left bottom mirror)
			)
		)
		(property "Description" "Test point 1mm SMD"
			(at 0 0 90)
			(layer "B.Fab")
			(hide yes)
			(effects
				(font
					(size 1.27 1.27)
					(thickness 0.15)
				)
				(justify mirror)
			)
		)
		(property "MPN" ""
			(at 0 0 90)
			(unlocked yes)
			(layer "B.Fab")
			(hide yes)
			(effects
				(font
					(size 1 1)
					(thickness 0.15)
				)
				(justify mirror)
			)
		)
		(property "Manufacturer" ""
			(at 0 0 90)
			(unlocked yes)
			(layer "B.Fab")
			(hide yes)
			(effects
				(font
					(size 1 1)
					(thickness 0.15)
				)
				(justify mirror)
			)
		)
		(property "Author" "Antmicro"
			(at 0 0 90)
			(unlocked yes)
			(layer "B.Fab")
			(hide yes)
			(effects
				(font
					(size 1 1)
					(thickness 0.15)
				)
				(justify mirror)
			)
		)
		(property "License" "Apache-2.0"
			(at 0 0 90)
			(unlocked yes)
			(layer "B.Fab")
			(hide yes)
			(effects
				(font
					(size 1 1)
					(thickness 0.15)
				)
				(justify mirror)
			)
		)
		(sheetname "/Power/")
		(sheetfile "power.kicad_sch")
		(attr exclude_from_pos_files exclude_from_bom)
		(fp_circle
			(center 0 0)
			(end 0.6 0)
			(stroke
				(width 0.05)
				(type default)
			)
			(fill no)
			(layer "B.CrtYd")
		)
		(pad "1" smd circle
			(at 0 0 270)
			(size 1 1)
			(layers "B.Cu" "B.Mask")
			(net 7 "+3V3")
			(pinfunction "1")
			(pintype "passive")
		)
	)
	(footprint "antmicro-footprints:C_0805_2012Metric"
		(layer "B.Cu")
		(at 103.95 134.7 180)
		(descr "Capacitor SMD 0805")
		(tags "capacitor SMD 0805")
		(property "Reference" "C63"
			(at -1.2 -1.05 0)
			(layer "B.SilkS")
			(effects
				(font
					(size 0.7 0.7)
					(thickness 0.15)
				)
				(justify left top mirror)
			)
		)
		(property "Value" "C_100u_0805"
			(at -2.055717 -1.963153 0)
			(layer "B.Fab")
			(hide yes)
			(effects
				(font
					(size 0.7 0.7)
					(thickness 0.15)
				)
				(justify left bottom mirror)
			)
		)
		(property "Datasheet" "https://www.murata.com/products/productdetail?partno=GRM21BR60J107ME15%23"
			(at 0 0 0)
			(layer "B.Fab")
			(hide yes)
			(effects
				(font
					(size 1.27 1.27)
					(thickness 0.15)
				)
				(justify mirror)
			)
		)
		(property "Description" "SMD Multilayer Ceramic Capacitor, 100 µF, 6.3 V, 0805 [2012 Metric], ± 20%, X5R, GRM Series"
			(at 0 0 0)
			(layer "B.Fab")
			(hide yes)
			(effects
				(font
					(size 1.27 1.27)
					(thickness 0.15)
				)
				(justify mirror)
			)
		)
		(property "MPN" "GRM21BR60J107ME15L"
			(at 0 0 180)
			(unlocked yes)
			(layer "B.Fab")
			(hide yes)
			(effects
				(font
					(size 1 1)
					(thickness 0.15)
				)
				(justify mirror)
			)
		)
		(property "Manufacturer" "Murata"
			(at 0 0 180)
			(unlocked yes)
			(layer "B.Fab")
			(hide yes)
			(effects
				(font
					(size 1 1)
					(thickness 0.15)
				)
				(justify mirror)
			)
		)
		(property "License" "Apache-2.0"
			(at 0 0 180)
			(unlocked yes)
			(layer "B.Fab")
			(hide yes)
			(effects
				(font
					(size 1 1)
					(thickness 0.15)
				)
				(justify mirror)
			)
		)
		(property "Author" "Antmicro"
			(at 0 0 180)
			(unlocked yes)
			(layer "B.Fab")
			(hide yes)
			(effects
				(font
					(size 1 1)
					(thickness 0.15)
				)
				(justify mirror)
			)
		)
		(property "Val" "100u"
			(at 0 0 180)
			(unlocked yes)
			(layer "B.Fab")
			(hide yes)
			(effects
				(font
					(size 1 1)
					(thickness 0.15)
				)
				(justify mirror)
			)
		)
		(property "Voltage" ""
			(at 0 0 180)
			(unlocked yes)
			(layer "B.Fab")
			(hide yes)
			(effects
				(font
					(size 1 1)
					(thickness 0.15)
				)
				(justify mirror)
			)
		)
		(property "Dielectric" ""
			(at 0 0 180)
			(unlocked yes)
			(layer "B.Fab")
			(hide yes)
			(effects
				(font
					(size 1 1)
					(thickness 0.15)
				)
				(justify mirror)
			)
		)
		(property "Public" "False"
			(at 0 0 180)
			(unlocked yes)
			(layer "B.Fab")
			(hide yes)
			(effects
				(font
					(size 1 1)
					(thickness 0.15)
				)
				(justify mirror)
			)
		)
		(sheetname "/2xRJ45/")
		(sheetfile "2xrj45.kicad_sch")
		(attr smd)
		(fp_line
			(start -0.3 0.7)
			(end 0.3 0.7)
			(stroke
				(width 0.15)
				(type solid)
			)
			(layer "B.SilkS")
		)
		(fp_line
			(start -0.3 -0.7)
			(end 0.3 -0.7)
			(stroke
				(width 0.15)
				(type solid)
			)
			(layer "B.SilkS")
		)
		(fp_rect
			(start 1.95 0.9)
			(end -1.95 -0.9)
			(stroke
				(width 0.05)
				(type default)
			)
			(fill no)
			(layer "B.CrtYd")
		)
		(fp_rect
			(start -0.95 0.675)
			(end 0.95 -0.675)
			(stroke
				(width 0.15)
				(type solid)
			)
			(fill no)
			(layer "B.Fab")
		)
		(pad "1" smd roundrect
			(at -1.1 0 180)
			(size 1.2 1.3)
			(layers "B.Cu" "B.Mask" "B.Paste")
			(roundrect_rratio 0.25)
			(net 28 "GND")
			(pintype "passive")
		)
		(pad "2" smd roundrect
			(at 1.1 0 180)
			(size 1.2 1.3)
			(layers "B.Cu" "B.Mask" "B.Paste")
			(roundrect_rratio 0.25)
			(net 300 "/2xRJ45/P1_CT")
			(pintype "passive")
		)
	)
	(footprint "antmicro-footprints:R_0402_1005Metric"
		(layer "B.Cu")
		(at 76.8 102.8)
		(descr "Resistor SMD 0402")
		(tags "resistor SMD 0402")
		(property "Reference" "R57"
			(at -2.9 -0.85 0)
			(layer "B.SilkS")
			(effects
				(font
					(size 0.7 0.7)
					(thickness 0.15)
				)
				(justify right top mirror)
			)
		)
		(property "Value" "R_4k53_0402"
			(at -1.011843 -1.772046 0)
			(layer "B.Fab")
			(hide yes)
			(effects
				(font
					(size 0.7 0.7)
					(thickness 0.15)
				)
				(justify right top mirror)
			)
		)
		(property "Datasheet" "https://industrial.panasonic.com/cdbs/www-data/pdf/RDM0000/AOA0000C307.pdf"
			(at 0 0 0)
			(layer "B.Fab")
			(hide yes)
			(effects
				(font
					(size 1.27 1.27)
					(thickness 0.15)
				)
				(justify mirror)
			)
		)
		(property "Description" "SMD Chip Resistor, 4.53 kohm, ± 0.1%, 62.5 mW, 0402 [1005 Metric], Automotive AEC-Q200 Thin Film"
			(at 0 0 0)
			(layer "B.Fab")
			(hide yes)
			(effects
				(font
					(size 1.27 1.27)
					(thickness 0.15)
				)
				(justify mirror)
			)
		)
		(property "MPN" "ERA-2AEB4531X"
			(at 0 0 0)
			(unlocked yes)
			(layer "B.Fab")
			(hide yes)
			(effects
				(font
					(size 1 1)
					(thickness 0.15)
				)
				(justify mirror)
			)
		)
		(property "Manufacturer" "Panasonic"
			(at 0 0 0)
			(unlocked yes)
			(layer "B.Fab")
			(hide yes)
			(effects
				(font
					(size 1 1)
					(thickness 0.15)
				)
				(justify mirror)
			)
		)
		(property "License" "Apache-2.0"
			(at 0 0 0)
			(unlocked yes)
			(layer "B.Fab")
			(hide yes)
			(effects
				(font
					(size 1 1)
					(thickness 0.15)
				)
				(justify mirror)
			)
		)
		(property "Author" "Antmicro"
			(at 0 0 0)
			(unlocked yes)
			(layer "B.Fab")
			(hide yes)
			(effects
				(font
					(size 1 1)
					(thickness 0.15)
				)
				(justify mirror)
			)
		)
		(property "Val" "4k53"
			(at 0 0 0)
			(unlocked yes)
			(layer "B.Fab")
			(hide yes)
			(effects
				(font
					(size 1 1)
					(thickness 0.15)
				)
				(justify mirror)
			)
		)
		(property "Tolerance" "0.1%"
			(at 0 0 0)
			(unlocked yes)
			(layer "B.Fab")
			(hide yes)
			(effects
				(font
					(size 1 1)
					(thickness 0.15)
				)
				(justify mirror)
			)
		)
		(sheetname "/X710-AT2 10GbE/")
		(sheetfile "x710-at2-10gbe.kicad_sch")
		(attr smd)
		(fp_rect
			(start -0.925 0.47)
			(end 0.925 -0.47)
			(stroke
				(width 0.05)
				(type default)
			)
			(fill no)
			(layer "B.CrtYd")
		)
		(fp_rect
			(start -0.5 0.25)
			(end 0.5 -0.25)
			(stroke
				(width 0.15)
				(type solid)
			)
			(fill no)
			(layer "B.Fab")
		)
		(pad "1" smd roundrect
			(at -0.48 0)
			(size 0.59 0.64)
			(layers "B.Cu" "B.Mask" "B.Paste")
			(roundrect_rratio 0.25)
			(net 28 "GND")
			(pintype "passive")
		)
		(pad "2" smd roundrect
			(at 0.48 0)
			(size 0.59 0.64)
			(layers "B.Cu" "B.Mask" "B.Paste")
			(roundrect_rratio 0.25)
			(net 83 "/X710-AT2 10GbE/RESCAL_RES_P")
			(pintype "passive")
		)
	)
	(footprint "antmicro-footprints:C_0603_1608Metric"
		(layer "B.Cu")
		(at 76.5 99.2 180)
		(descr "Capacitor SMD 0603")
		(tags "capacitor 0603")
		(property "Reference" "C99"
			(at -1.09 0.71 0)
			(layer "B.SilkS")
			(effects
				(font
					(size 0.7 0.7)
					(thickness 0.15)
				)
				(justify left bottom mirror)
			)
		)
		(property "Value" "C_10u_10V_X7R_0603"
			(at -1.42757 -1.770288 0)
			(layer "B.Fab")
			(hide yes)
			(effects
				(font
					(size 0.7 0.7)
					(thickness 0.15)
				)
				(justify left bottom mirror)
			)
		)
		(property "Datasheet" "https://www.murata.com/products/productdetail?partno=GRM188Z71A106KA73%23"
			(at 0 0 0)
			(layer "B.Fab")
			(hide yes)
			(effects
				(font
					(size 1.27 1.27)
					(thickness 0.15)
				)
				(justify mirror)
			)
		)
		(property "Description" "SMD Multilayer Ceramic Capacitor,  10µF, 10V, 0603, ±10%, X7R"
			(at 0 0 0)
			(layer "B.Fab")
			(hide yes)
			(effects
				(font
					(size 1.27 1.27)
					(thickness 0.15)
				)
				(justify mirror)
			)
		)
		(property "MPN" "GRM188Z71A106KA73D"
			(at 0 0 180)
			(unlocked yes)
			(layer "B.Fab")
			(hide yes)
			(effects
				(font
					(size 1 1)
					(thickness 0.15)
				)
				(justify mirror)
			)
		)
		(property "Val" "10u"
			(at 0 0 180)
			(unlocked yes)
			(layer "B.Fab")
			(hide yes)
			(effects
				(font
					(size 1 1)
					(thickness 0.15)
				)
				(justify mirror)
			)
		)
		(property "Voltage" "10V"
			(at 0 0 180)
			(unlocked yes)
			(layer "B.Fab")
			(hide yes)
			(effects
				(font
					(size 1 1)
					(thickness 0.15)
				)
				(justify mirror)
			)
		)
		(property "Dielectric" "X7R"
			(at 0 0 180)
			(unlocked yes)
			(layer "B.Fab")
			(hide yes)
			(effects
				(font
					(size 1 1)
					(thickness 0.15)
				)
				(justify mirror)
			)
		)
		(property "Manufacturer" "Murata"
			(at 0 0 180)
			(unlocked yes)
			(layer "B.Fab")
			(hide yes)
			(effects
				(font
					(size 1 1)
					(thickness 0.15)
				)
				(justify mirror)
			)
		)
		(property "License" "Apache-2.0"
			(at 0 0 180)
			(unlocked yes)
			(layer "B.Fab")
			(hide yes)
			(effects
				(font
					(size 1 1)
					(thickness 0.15)
				)
				(justify mirror)
			)
		)
		(property "Author" "Antmicro"
			(at 0 0 180)
			(unlocked yes)
			(layer "B.Fab")
			(hide yes)
			(effects
				(font
					(size 1 1)
					(thickness 0.15)
				)
				(justify mirror)
			)
		)
		(sheetname "/X710-AT2 power/")
		(sheetfile "x710-at2-power.kicad_sch")
		(attr smd)
		(fp_line
			(start -0.15 0.4)
			(end 0.15 0.4)
			(stroke
				(width 0.15)
				(type solid)
			)
			(layer "B.SilkS")
		)
		(fp_line
			(start -0.15 -0.4)
			(end 0.15 -0.4)
			(stroke
				(width 0.15)
				(type solid)
			)
			(layer "B.SilkS")
		)
		(fp_rect
			(start -1.25 0.65)
			(end 1.25 -0.65)
			(stroke
				(width 0.05)
				(type solid)
			)
			(fill no)
			(layer "B.CrtYd")
		)
		(fp_rect
			(start -0.8 0.4)
			(end 0.8 -0.4)
			(stroke
				(width 0.15)
				(type solid)
			)
			(fill no)
			(layer "B.Fab")
		)
		(pad "1" smd roundrect
			(at -0.7 0 180)
			(size 0.8 1)
			(layers "B.Cu" "B.Mask" "B.Paste")
			(roundrect_rratio 0.2)
			(net 28 "GND")
			(pintype "passive")
		)
		(pad "2" smd roundrect
			(at 0.7 0 180)
			(size 0.8 1)
			(layers "B.Cu" "B.Mask" "B.Paste")
			(roundrect_rratio 0.2)
			(net 18 "+1V88")
			(pintype "passive")
		)
	)
	(footprint "antmicro-footprints:R_0402_1005Metric"
		(layer "B.Cu")
		(at 109.49 88.86 90)
		(descr "Resistor SMD 0402")
		(tags "resistor SMD 0402")
		(property "Reference" "R131"
			(at -3.58 -0.38 90)
			(layer "B.SilkS")
			(effects
				(font
					(size 0.7 0.7)
					(thickness 0.15)
				)
				(justify right top mirror)
			)
		)
		(property "Value" "R_10k_0402"
			(at -1.011843 -1.772046 90)
			(layer "B.Fab")
			(hide yes)
			(effects
				(font
					(size 0.7 0.7)
					(thickness 0.15)
				)
				(justify right top mirror)
			)
		)
		(property "Datasheet" "https://www.bourns.com/docs/product-datasheets/cr.pdf"
			(at 0 0 90)
			(layer "B.Fab")
			(hide yes)
			(effects
				(font
					(size 1.27 1.27)
					(thickness 0.15)
				)
				(justify mirror)
			)
		)
		(property "Description" "SMD Chip Resistor, 10 kohm, ± 1%, 62.5 mW, 0402 [1005 Metric], Thick Film, General Purpose"
			(at 0 0 90)
			(layer "B.Fab")
			(hide yes)
			(effects
				(font
					(size 1.27 1.27)
					(thickness 0.15)
				)
				(justify mirror)
			)
		)
		(property "MPN" "CR0402-FX-1002GLF"
			(at 0 0 90)
			(unlocked yes)
			(layer "B.Fab")
			(hide yes)
			(effects
				(font
					(size 1 1)
					(thickness 0.15)
				)
				(justify mirror)
			)
		)
		(property "Manufacturer" "Bourns"
			(at 0 0 90)
			(unlocked yes)
			(layer "B.Fab")
			(hide yes)
			(effects
				(font
					(size 1 1)
					(thickness 0.15)
				)
				(justify mirror)
			)
		)
		(property "License" "Apache-2.0"
			(at 0 0 90)
			(unlocked yes)
			(layer "B.Fab")
			(hide yes)
			(effects
				(font
					(size 1 1)
					(thickness 0.15)
				)
				(justify mirror)
			)
		)
		(property "Author" "Antmicro"
			(at 0 0 90)
			(unlocked yes)
			(layer "B.Fab")
			(hide yes)
			(effects
				(font
					(size 1 1)
					(thickness 0.15)
				)
				(justify mirror)
			)
		)
		(property "Val" "10k"
			(at 0 0 90)
			(unlocked yes)
			(layer "B.Fab")
			(hide yes)
			(effects
				(font
					(size 1 1)
					(thickness 0.15)
				)
				(justify mirror)
			)
		)
		(property "Tolerance" "1%"
			(at 0 0 90)
			(unlocked yes)
			(layer "B.Fab")
			(hide yes)
			(effects
				(font
					(size 1 1)
					(thickness 0.15)
				)
				(justify mirror)
			)
		)
		(sheetname "/X710-AT2 RSVD/")
		(sheetfile "x710-at2-rsvd.kicad_sch")
		(attr smd)
		(fp_rect
			(start -0.925 0.47)
			(end 0.925 -0.47)
			(stroke
				(width 0.05)
				(type default)
			)
			(fill no)
			(layer "B.CrtYd")
		)
		(fp_rect
			(start -0.5 0.25)
			(end 0.5 -0.25)
			(stroke
				(width 0.15)
				(type solid)
			)
			(fill no)
			(layer "B.Fab")
		)
		(pad "1" smd roundrect
			(at -0.48 0 90)
			(size 0.59 0.64)
			(layers "B.Cu" "B.Mask" "B.Paste")
			(roundrect_rratio 0.25)
			(net 28 "GND")
			(pintype "passive")
		)
		(pad "2" smd roundrect
			(at 0.48 0 90)
			(size 0.59 0.64)
			(layers "B.Cu" "B.Mask" "B.Paste")
			(roundrect_rratio 0.25)
			(net 119 "/X710-AT2 RSVD/DEBUG_Y20")
			(pintype "passive")
		)
	)
	(footprint "antmicro-footprints:C_0402_1005Metric"
		(layer "B.Cu")
		(at 66 131.4)
		(descr "Capacitor SMD 0402")
		(tags "capacitor SMD 0402")
		(property "Reference" "C56"
			(at -3 -0.3 0)
			(layer "B.SilkS")
			(effects
				(font
					(size 0.7 0.7)
					(thickness 0.15)
				)
				(justify right top mirror)
			)
		)
		(property "Value" "C_1u_25V_0402"
			(at -1.022927 -2.155213 0)
			(layer "B.Fab")
			(hide yes)
			(effects
				(font
					(size 0.7 0.7)
					(thickness 0.15)
				)
				(justify right top mirror)
			)
		)
		(property "Datasheet" "https://www.murata.com/products/productdetail?partno=GRM155R61E105KE11%23"
			(at 0 0 0)
			(layer "B.Fab")
			(hide yes)
			(effects
				(font
					(size 1.27 1.27)
					(thickness 0.15)
				)
				(justify mirror)
			)
		)
		(property "Description" "SMD Multilayer Ceramic Capacitor, 1 µF, 25 V, 0402 [1005 Metric], ± 10%, X5R, GRM Series"
			(at 0 0 0)
			(layer "B.Fab")
			(hide yes)
			(effects
				(font
					(size 1.27 1.27)
					(thickness 0.15)
				)
				(justify mirror)
			)
		)
		(property "MPN" "GRM155R61E105KE11J"
			(at 0 0 0)
			(unlocked yes)
			(layer "B.Fab")
			(hide yes)
			(effects
				(font
					(size 1 1)
					(thickness 0.15)
				)
				(justify mirror)
			)
		)
		(property "Manufacturer" "Murata"
			(at 0 0 0)
			(unlocked yes)
			(layer "B.Fab")
			(hide yes)
			(effects
				(font
					(size 1 1)
					(thickness 0.15)
				)
				(justify mirror)
			)
		)
		(property "License" "Apache-2.0"
			(at 0 0 0)
			(unlocked yes)
			(layer "B.Fab")
			(hide yes)
			(effects
				(font
					(size 1 1)
					(thickness 0.15)
				)
				(justify mirror)
			)
		)
		(property "Author" "Antmicro"
			(at 0 0 0)
			(unlocked yes)
			(layer "B.Fab")
			(hide yes)
			(effects
				(font
					(size 1 1)
					(thickness 0.15)
				)
				(justify mirror)
			)
		)
		(property "Val" "1u"
			(at 0 0 0)
			(unlocked yes)
			(layer "B.Fab")
			(hide yes)
			(effects
				(font
					(size 1 1)
					(thickness 0.15)
				)
				(justify mirror)
			)
		)
		(property "Voltage" "25V"
			(at 0 0 0)
			(unlocked yes)
			(layer "B.Fab")
			(hide yes)
			(effects
				(font
					(size 1 1)
					(thickness 0.15)
				)
				(justify mirror)
			)
		)
		(property "Dielectric" "X5R"
			(at 0 0 0)
			(unlocked yes)
			(layer "B.Fab")
			(hide yes)
			(effects
				(font
					(size 1 1)
					(thickness 0.15)
				)
				(justify mirror)
			)
		)
		(sheetname "/2xRJ45/")
		(sheetfile "2xrj45.kicad_sch")
		(attr smd)
		(fp_rect
			(start -0.925 0.47)
			(end 0.925 -0.47)
			(stroke
				(width 0.05)
				(type default)
			)
			(fill no)
			(layer "B.CrtYd")
		)
		(fp_line
			(start -0.494 -0.248)
			(end -0.494 0.25)
			(stroke
				(width 0.15)
				(type solid)
			)
			(layer "B.Fab")
		)
		(fp_line
			(start -0.494 0.25)
			(end 0.504 0.25)
			(stroke
				(width 0.15)
				(type solid)
			)
			(layer "B.Fab")
		)
		(fp_line
			(start 0.504 -0.248)
			(end -0.494 -0.248)
			(stroke
				(width 0.15)
				(type solid)
			)
			(layer "B.Fab")
		)
		(fp_line
			(start 0.504 0.25)
			(end 0.504 -0.248)
			(stroke
				(width 0.15)
				(type solid)
			)
			(layer "B.Fab")
		)
		(pad "1" smd roundrect
			(at -0.48 0)
			(size 0.59 0.64)
			(layers "B.Cu" "B.Mask" "B.Paste")
			(roundrect_rratio 0.25)
			(net 28 "GND")
			(pintype "passive")
		)
		(pad "2" smd roundrect
			(at 0.48 0)
			(size 0.59 0.64)
			(layers "B.Cu" "B.Mask" "B.Paste")
			(roundrect_rratio 0.25)
			(net 299 "/2xRJ45/P0_CT")
			(pintype "passive")
		)
	)
	(footprint "antmicro-footprints:C_0402_1005Metric"
		(layer "B.Cu")
		(at 90.225 100.15 90)
		(descr "Capacitor SMD 0402")
		(tags "capacitor SMD 0402")
		(property "Reference" "C87"
			(at 9.87 -0.388176 90)
			(layer "B.SilkS")
			(effects
				(font
					(size 0.7 0.7)
					(thickness 0.15)
				)
				(justify right top mirror)
			)
		)
		(property "Value" "C_1u_25V_0402"
			(at -1.022927 -2.155213 90)
			(layer "B.Fab")
			(hide yes)
			(effects
				(font
					(size 0.7 0.7)
					(thickness 0.15)
				)
				(justify right top mirror)
			)
		)
		(property "Datasheet" "https://www.murata.com/products/productdetail?partno=GRM155R61E105KE11%23"
			(at 0 0 90)
			(layer "B.Fab")
			(hide yes)
			(effects
				(font
					(size 1.27 1.27)
					(thickness 0.15)
				)
				(justify mirror)
			)
		)
		(property "Description" "SMD Multilayer Ceramic Capacitor, 1 µF, 25 V, 0402 [1005 Metric], ± 10%, X5R, GRM Series"
			(at 0 0 90)
			(layer "B.Fab")
			(hide yes)
			(effects
				(font
					(size 1.27 1.27)
					(thickness 0.15)
				)
				(justify mirror)
			)
		)
		(property "MPN" "GRM155R61E105KE11J"
			(at 0 0 90)
			(unlocked yes)
			(layer "B.Fab")
			(hide yes)
			(effects
				(font
					(size 1 1)
					(thickness 0.15)
				)
				(justify mirror)
			)
		)
		(property "Manufacturer" "Murata"
			(at 0 0 90)
			(unlocked yes)
			(layer "B.Fab")
			(hide yes)
			(effects
				(font
					(size 1 1)
					(thickness 0.15)
				)
				(justify mirror)
			)
		)
		(property "License" "Apache-2.0"
			(at 0 0 90)
			(unlocked yes)
			(layer "B.Fab")
			(hide yes)
			(effects
				(font
					(size 1 1)
					(thickness 0.15)
				)
				(justify mirror)
			)
		)
		(property "Author" "Antmicro"
			(at 0 0 90)
			(unlocked yes)
			(layer "B.Fab")
			(hide yes)
			(effects
				(font
					(size 1 1)
					(thickness 0.15)
				)
				(justify mirror)
			)
		)
		(property "Val" "1u"
			(at 0 0 90)
			(unlocked yes)
			(layer "B.Fab")
			(hide yes)
			(effects
				(font
					(size 1 1)
					(thickness 0.15)
				)
				(justify mirror)
			)
		)
		(property "Voltage" "25V"
			(at 0 0 90)
			(unlocked yes)
			(layer "B.Fab")
			(hide yes)
			(effects
				(font
					(size 1 1)
					(thickness 0.15)
				)
				(justify mirror)
			)
		)
		(property "Dielectric" "X5R"
			(at 0 0 90)
			(unlocked yes)
			(layer "B.Fab")
			(hide yes)
			(effects
				(font
					(size 1 1)
					(thickness 0.15)
				)
				(justify mirror)
			)
		)
		(sheetname "/X710-AT2 power/")
		(sheetfile "x710-at2-power.kicad_sch")
		(attr smd)
		(fp_rect
			(start -0.925 0.47)
			(end 0.925 -0.47)
			(stroke
				(width 0.05)
				(type default)
			)
			(fill no)
			(layer "B.CrtYd")
		)
		(fp_line
			(start 0.504 -0.248)
			(end -0.494 -0.248)
			(stroke
				(width 0.15)
				(type solid)
			)
			(layer "B.Fab")
		)
		(fp_line
			(start -0.494 -0.248)
			(end -0.494 0.25)
			(stroke
				(width 0.15)
				(type solid)
			)
			(layer "B.Fab")
		)
		(fp_line
			(start 0.504 0.25)
			(end 0.504 -0.248)
			(stroke
				(width 0.15)
				(type solid)
			)
			(layer "B.Fab")
		)
		(fp_line
			(start -0.494 0.25)
			(end 0.504 0.25)
			(stroke
				(width 0.15)
				(type solid)
			)
			(layer "B.Fab")
		)
		(pad "1" smd roundrect
			(at -0.48 0 90)
			(size 0.59 0.64)
			(layers "B.Cu" "B.Mask" "B.Paste")
			(roundrect_rratio 0.25)
			(net 28 "GND")
			(pintype "passive")
		)
		(pad "2" smd roundrect
			(at 0.48 0 90)
			(size 0.59 0.64)
			(layers "B.Cu" "B.Mask" "B.Paste")
			(roundrect_rratio 0.25)
			(net 1 "VCCA")
			(pintype "passive")
		)
	)
	(footprint "antmicro-footprints:C_0402_1005Metric"
		(layer "B.Cu")
		(at 88 132.4)
		(descr "Capacitor SMD 0402")
		(tags "capacitor SMD 0402")
		(property "Reference" "C66"
			(at -0.98 2.59 0)
			(layer "B.SilkS")
			(effects
				(font
					(size 0.7 0.7)
					(thickness 0.15)
				)
				(justify right top mirror)
			)
		)
		(property "Value" "C_1u_25V_0402"
			(at -1.022927 -2.155213 0)
			(layer "B.Fab")
			(hide yes)
			(effects
				(font
					(size 0.7 0.7)
					(thickness 0.15)
				)
				(justify right top mirror)
			)
		)
		(property "Datasheet" "https://www.murata.com/products/productdetail?partno=GRM155R61E105KE11%23"
			(at 0 0 0)
			(layer "B.Fab")
			(hide yes)
			(effects
				(font
					(size 1.27 1.27)
					(thickness 0.15)
				)
				(justify mirror)
			)
		)
		(property "Description" "SMD Multilayer Ceramic Capacitor, 1 µF, 25 V, 0402 [1005 Metric], ± 10%, X5R, GRM Series"
			(at 0 0 0)
			(layer "B.Fab")
			(hide yes)
			(effects
				(font
					(size 1.27 1.27)
					(thickness 0.15)
				)
				(justify mirror)
			)
		)
		(property "MPN" "GRM155R61E105KE11J"
			(at 0 0 0)
			(unlocked yes)
			(layer "B.Fab")
			(hide yes)
			(effects
				(font
					(size 1 1)
					(thickness 0.15)
				)
				(justify mirror)
			)
		)
		(property "Manufacturer" "Murata"
			(at 0 0 0)
			(unlocked yes)
			(layer "B.Fab")
			(hide yes)
			(effects
				(font
					(size 1 1)
					(thickness 0.15)
				)
				(justify mirror)
			)
		)
		(property "License" "Apache-2.0"
			(at 0 0 0)
			(unlocked yes)
			(layer "B.Fab")
			(hide yes)
			(effects
				(font
					(size 1 1)
					(thickness 0.15)
				)
				(justify mirror)
			)
		)
		(property "Author" "Antmicro"
			(at 0 0 0)
			(unlocked yes)
			(layer "B.Fab")
			(hide yes)
			(effects
				(font
					(size 1 1)
					(thickness 0.15)
				)
				(justify mirror)
			)
		)
		(property "Val" "1u"
			(at 0 0 0)
			(unlocked yes)
			(layer "B.Fab")
			(hide yes)
			(effects
				(font
					(size 1 1)
					(thickness 0.15)
				)
				(justify mirror)
			)
		)
		(property "Voltage" "25V"
			(at 0 0 0)
			(unlocked yes)
			(layer "B.Fab")
			(hide yes)
			(effects
				(font
					(size 1 1)
					(thickness 0.15)
				)
				(justify mirror)
			)
		)
		(property "Dielectric" "X5R"
			(at 0 0 0)
			(unlocked yes)
			(layer "B.Fab")
			(hide yes)
			(effects
				(font
					(size 1 1)
					(thickness 0.15)
				)
				(justify mirror)
			)
		)
		(sheetname "/2xRJ45/")
		(sheetfile "2xrj45.kicad_sch")
		(attr smd)
		(fp_rect
			(start -0.925 0.47)
			(end 0.925 -0.47)
			(stroke
				(width 0.05)
				(type default)
			)
			(fill no)
			(layer "B.CrtYd")
		)
		(fp_line
			(start -0.494 -0.248)
			(end -0.494 0.25)
			(stroke
				(width 0.15)
				(type solid)
			)
			(layer "B.Fab")
		)
		(fp_line
			(start -0.494 0.25)
			(end 0.504 0.25)
			(stroke
				(width 0.15)
				(type solid)
			)
			(layer "B.Fab")
		)
		(fp_line
			(start 0.504 -0.248)
			(end -0.494 -0.248)
			(stroke
				(width 0.15)
				(type solid)
			)
			(layer "B.Fab")
		)
		(fp_line
			(start 0.504 0.25)
			(end 0.504 -0.248)
			(stroke
				(width 0.15)
				(type solid)
			)
			(layer "B.Fab")
		)
		(pad "1" smd roundrect
			(at -0.48 0)
			(size 0.59 0.64)
			(layers "B.Cu" "B.Mask" "B.Paste")
			(roundrect_rratio 0.25)
			(net 28 "GND")
			(pintype "passive")
		)
		(pad "2" smd roundrect
			(at 0.48 0)
			(size 0.59 0.64)
			(layers "B.Cu" "B.Mask" "B.Paste")
			(roundrect_rratio 0.25)
			(net 300 "/2xRJ45/P1_CT")
			(pintype "passive")
		)
	)
	(footprint "antmicro-footprints:C_0402_1005Metric"
		(layer "B.Cu")
		(at 96.88 112.960001)
		(descr "Capacitor SMD 0402")
		(tags "capacitor SMD 0402")
		(property "Reference" "C74"
			(at -2.9 -0.290001 0)
			(layer "B.SilkS")
			(effects
				(font
					(size 0.7 0.7)
					(thickness 0.15)
				)
				(justify right top mirror)
			)
		)
		(property "Value" "C_100n_0402"
			(at -1.022927 -2.155213 0)
			(layer "B.Fab")
			(hide yes)
			(effects
				(font
					(size 0.7 0.7)
					(thickness 0.15)
				)
				(justify right top mirror)
			)
		)
		(property "Datasheet" "https://www.murata.com/products/productdetail?partno=GRM155R61H104KE14%23"
			(at 0 0 0)
			(layer "B.Fab")
			(hide yes)
			(effects
				(font
					(size 1.27 1.27)
					(thickness 0.15)
				)
				(justify mirror)
			)
		)
		(property "Description" "SMD Multilayer Ceramic Capacitor, 0.1 µF, 50 V, 0402 [1005 Metric], ± 10%, X5R, GRM Series"
			(at 0 0 0)
			(layer "B.Fab")
			(hide yes)
			(effects
				(font
					(size 1.27 1.27)
					(thickness 0.15)
				)
				(justify mirror)
			)
		)
		(property "MPN" "GRM155R61H104KE14D"
			(at 0 0 0)
			(unlocked yes)
			(layer "B.Fab")
			(hide yes)
			(effects
				(font
					(size 1 1)
					(thickness 0.15)
				)
				(justify mirror)
			)
		)
		(property "Val" "100n"
			(at 0 0 0)
			(unlocked yes)
			(layer "B.Fab")
			(hide yes)
			(effects
				(font
					(size 1 1)
					(thickness 0.15)
				)
				(justify mirror)
			)
		)
		(property "Voltage" "50V"
			(at 0 0 0)
			(unlocked yes)
			(layer "B.Fab")
			(hide yes)
			(effects
				(font
					(size 1 1)
					(thickness 0.15)
				)
				(justify mirror)
			)
		)
		(property "Dielectric" "X5R"
			(at 0 0 0)
			(unlocked yes)
			(layer "B.Fab")
			(hide yes)
			(effects
				(font
					(size 1 1)
					(thickness 0.15)
				)
				(justify mirror)
			)
		)
		(property "Manufacturer" "Murata"
			(at 0 0 0)
			(unlocked yes)
			(layer "B.Fab")
			(hide yes)
			(effects
				(font
					(size 1 1)
					(thickness 0.15)
				)
				(justify mirror)
			)
		)
		(property "License" "Apache-2.0"
			(at 0 0 0)
			(unlocked yes)
			(layer "B.Fab")
			(hide yes)
			(effects
				(font
					(size 1 1)
					(thickness 0.15)
				)
				(justify mirror)
			)
		)
		(property "Author" "Antmicro"
			(at 0 0 0)
			(unlocked yes)
			(layer "B.Fab")
			(hide yes)
			(effects
				(font
					(size 1 1)
					(thickness 0.15)
				)
				(justify mirror)
			)
		)
		(sheetname "/X710-AT2 Misc/")
		(sheetfile "x710-at2-mics.kicad_sch")
		(attr smd)
		(fp_rect
			(start -0.925 0.47)
			(end 0.925 -0.47)
			(stroke
				(width 0.05)
				(type default)
			)
			(fill no)
			(layer "B.CrtYd")
		)
		(fp_line
			(start -0.494 -0.248)
			(end -0.494 0.25)
			(stroke
				(width 0.15)
				(type solid)
			)
			(layer "B.Fab")
		)
		(fp_line
			(start -0.494 0.25)
			(end 0.504 0.25)
			(stroke
				(width 0.15)
				(type solid)
			)
			(layer "B.Fab")
		)
		(fp_line
			(start 0.504 -0.248)
			(end -0.494 -0.248)
			(stroke
				(width 0.15)
				(type solid)
			)
			(layer "B.Fab")
		)
		(fp_line
			(start 0.504 0.25)
			(end 0.504 -0.248)
			(stroke
				(width 0.15)
				(type solid)
			)
			(layer "B.Fab")
		)
		(pad "1" smd roundrect
			(at -0.48 0)
			(size 0.59 0.64)
			(layers "B.Cu" "B.Mask" "B.Paste")
			(roundrect_rratio 0.25)
			(net 28 "GND")
			(pintype "passive")
		)
		(pad "2" smd roundrect
			(at 0.48 0)
			(size 0.59 0.64)
			(layers "B.Cu" "B.Mask" "B.Paste")
			(roundrect_rratio 0.25)
			(net 18 "+1V88")
			(pintype "passive")
		)
	)
	(footprint "antmicro-footprints:C_0402_1005Metric"
		(layer "B.Cu")
		(at 80.47 106.93 -90)
		(descr "Capacitor SMD 0402")
		(tags "capacitor SMD 0402")
		(property "Reference" "C143"
			(at 9.97 -0.91 90)
			(layer "B.SilkS")
			(effects
				(font
					(size 0.7 0.7)
					(thickness 0.15)
				)
				(justify left bottom mirror)
			)
		)
		(property "Value" "C_1u_25V_0402"
			(at -1.022927 -2.155213 90)
			(layer "B.Fab")
			(hide yes)
			(effects
				(font
					(size 0.7 0.7)
					(thickness 0.15)
				)
				(justify left bottom mirror)
			)
		)
		(property "Datasheet" "https://www.murata.com/products/productdetail?partno=GRM155R61E105KE11%23"
			(at 0 0 90)
			(layer "B.Fab")
			(hide yes)
			(effects
				(font
					(size 1.27 1.27)
					(thickness 0.15)
				)
				(justify mirror)
			)
		)
		(property "Description" "SMD Multilayer Ceramic Capacitor, 1 µF, 25 V, 0402 [1005 Metric], ± 10%, X5R, GRM Series"
			(at 0 0 90)
			(layer "B.Fab")
			(hide yes)
			(effects
				(font
					(size 1.27 1.27)
					(thickness 0.15)
				)
				(justify mirror)
			)
		)
		(property "MPN" "GRM155R61E105KE11J"
			(at 0 0 270)
			(unlocked yes)
			(layer "B.Fab")
			(hide yes)
			(effects
				(font
					(size 1 1)
					(thickness 0.15)
				)
				(justify mirror)
			)
		)
		(property "Manufacturer" "Murata"
			(at 0 0 270)
			(unlocked yes)
			(layer "B.Fab")
			(hide yes)
			(effects
				(font
					(size 1 1)
					(thickness 0.15)
				)
				(justify mirror)
			)
		)
		(property "License" "Apache-2.0"
			(at 0 0 270)
			(unlocked yes)
			(layer "B.Fab")
			(hide yes)
			(effects
				(font
					(size 1 1)
					(thickness 0.15)
				)
				(justify mirror)
			)
		)
		(property "Author" "Antmicro"
			(at 0 0 270)
			(unlocked yes)
			(layer "B.Fab")
			(hide yes)
			(effects
				(font
					(size 1 1)
					(thickness 0.15)
				)
				(justify mirror)
			)
		)
		(property "Val" "1u"
			(at 0 0 270)
			(unlocked yes)
			(layer "B.Fab")
			(hide yes)
			(effects
				(font
					(size 1 1)
					(thickness 0.15)
				)
				(justify mirror)
			)
		)
		(property "Voltage" "25V"
			(at 0 0 270)
			(unlocked yes)
			(layer "B.Fab")
			(hide yes)
			(effects
				(font
					(size 1 1)
					(thickness 0.15)
				)
				(justify mirror)
			)
		)
		(property "Dielectric" "X5R"
			(at 0 0 270)
			(unlocked yes)
			(layer "B.Fab")
			(hide yes)
			(effects
				(font
					(size 1 1)
					(thickness 0.15)
				)
				(justify mirror)
			)
		)
		(sheetname "/X710-AT2 power/")
		(sheetfile "x710-at2-power.kicad_sch")
		(attr smd)
		(fp_rect
			(start -0.925 0.47)
			(end 0.925 -0.47)
			(stroke
				(width 0.05)
				(type default)
			)
			(fill no)
			(layer "B.CrtYd")
		)
		(fp_line
			(start -0.494 0.25)
			(end 0.504 0.25)
			(stroke
				(width 0.15)
				(type solid)
			)
			(layer "B.Fab")
		)
		(fp_line
			(start 0.504 0.25)
			(end 0.504 -0.248)
			(stroke
				(width 0.15)
				(type solid)
			)
			(layer "B.Fab")
		)
		(fp_line
			(start -0.494 -0.248)
			(end -0.494 0.25)
			(stroke
				(width 0.15)
				(type solid)
			)
			(layer "B.Fab")
		)
		(fp_line
			(start 0.504 -0.248)
			(end -0.494 -0.248)
			(stroke
				(width 0.15)
				(type solid)
			)
			(layer "B.Fab")
		)
		(pad "1" smd roundrect
			(at -0.48 0 270)
			(size 0.59 0.64)
			(layers "B.Cu" "B.Mask" "B.Paste")
			(roundrect_rratio 0.25)
			(net 28 "GND")
			(pintype "passive")
		)
		(pad "2" smd roundrect
			(at 0.48 0 270)
			(size 0.59 0.64)
			(layers "B.Cu" "B.Mask" "B.Paste")
			(roundrect_rratio 0.25)
			(net 10 "AVDDH")
			(pintype "passive")
		)
	)
	(footprint "antmicro-footprints:C_0402_1005Metric"
		(layer "B.Cu")
		(at 88 131.4)
		(descr "Capacitor SMD 0402")
		(tags "capacitor SMD 0402")
		(property "Reference" "C64"
			(at -0.98 2.59 0)
			(layer "B.SilkS")
			(effects
				(font
					(size 0.7 0.7)
					(thickness 0.15)
				)
				(justify right top mirror)
			)
		)
		(property "Value" "C_1u_25V_0402"
			(at -1.022927 -2.155213 0)
			(layer "B.Fab")
			(hide yes)
			(effects
				(font
					(size 0.7 0.7)
					(thickness 0.15)
				)
				(justify right top mirror)
			)
		)
		(property "Datasheet" "https://www.murata.com/products/productdetail?partno=GRM155R61E105KE11%23"
			(at 0 0 0)
			(layer "B.Fab")
			(hide yes)
			(effects
				(font
					(size 1.27 1.27)
					(thickness 0.15)
				)
				(justify mirror)
			)
		)
		(property "Description" "SMD Multilayer Ceramic Capacitor, 1 µF, 25 V, 0402 [1005 Metric], ± 10%, X5R, GRM Series"
			(at 0 0 0)
			(layer "B.Fab")
			(hide yes)
			(effects
				(font
					(size 1.27 1.27)
					(thickness 0.15)
				)
				(justify mirror)
			)
		)
		(property "MPN" "GRM155R61E105KE11J"
			(at 0 0 0)
			(unlocked yes)
			(layer "B.Fab")
			(hide yes)
			(effects
				(font
					(size 1 1)
					(thickness 0.15)
				)
				(justify mirror)
			)
		)
		(property "Manufacturer" "Murata"
			(at 0 0 0)
			(unlocked yes)
			(layer "B.Fab")
			(hide yes)
			(effects
				(font
					(size 1 1)
					(thickness 0.15)
				)
				(justify mirror)
			)
		)
		(property "License" "Apache-2.0"
			(at 0 0 0)
			(unlocked yes)
			(layer "B.Fab")
			(hide yes)
			(effects
				(font
					(size 1 1)
					(thickness 0.15)
				)
				(justify mirror)
			)
		)
		(property "Author" "Antmicro"
			(at 0 0 0)
			(unlocked yes)
			(layer "B.Fab")
			(hide yes)
			(effects
				(font
					(size 1 1)
					(thickness 0.15)
				)
				(justify mirror)
			)
		)
		(property "Val" "1u"
			(at 0 0 0)
			(unlocked yes)
			(layer "B.Fab")
			(hide yes)
			(effects
				(font
					(size 1 1)
					(thickness 0.15)
				)
				(justify mirror)
			)
		)
		(property "Voltage" "25V"
			(at 0 0 0)
			(unlocked yes)
			(layer "B.Fab")
			(hide yes)
			(effects
				(font
					(size 1 1)
					(thickness 0.15)
				)
				(justify mirror)
			)
		)
		(property "Dielectric" "X5R"
			(at 0 0 0)
			(unlocked yes)
			(layer "B.Fab")
			(hide yes)
			(effects
				(font
					(size 1 1)
					(thickness 0.15)
				)
				(justify mirror)
			)
		)
		(sheetname "/2xRJ45/")
		(sheetfile "2xrj45.kicad_sch")
		(attr smd)
		(fp_rect
			(start -0.925 0.47)
			(end 0.925 -0.47)
			(stroke
				(width 0.05)
				(type default)
			)
			(fill no)
			(layer "B.CrtYd")
		)
		(fp_line
			(start -0.494 -0.248)
			(end -0.494 0.25)
			(stroke
				(width 0.15)
				(type solid)
			)
			(layer "B.Fab")
		)
		(fp_line
			(start -0.494 0.25)
			(end 0.504 0.25)
			(stroke
				(width 0.15)
				(type solid)
			)
			(layer "B.Fab")
		)
		(fp_line
			(start 0.504 -0.248)
			(end -0.494 -0.248)
			(stroke
				(width 0.15)
				(type solid)
			)
			(layer "B.Fab")
		)
		(fp_line
			(start 0.504 0.25)
			(end 0.504 -0.248)
			(stroke
				(width 0.15)
				(type solid)
			)
			(layer "B.Fab")
		)
		(pad "1" smd roundrect
			(at -0.48 0)
			(size 0.59 0.64)
			(layers "B.Cu" "B.Mask" "B.Paste")
			(roundrect_rratio 0.25)
			(net 28 "GND")
			(pintype "passive")
		)
		(pad "2" smd roundrect
			(at 0.48 0)
			(size 0.59 0.64)
			(layers "B.Cu" "B.Mask" "B.Paste")
			(roundrect_rratio 0.25)
			(net 300 "/2xRJ45/P1_CT")
			(pintype "passive")
		)
	)
	(footprint "antmicro-footprints:R_0402_1005Metric"
		(layer "B.Cu")
		(at 111.49 86.76 90)
		(descr "Resistor SMD 0402")
		(tags "resistor SMD 0402")
		(property "Reference" "R129"
			(at 0.81 -0.31 90)
			(layer "B.SilkS")
			(effects
				(font
					(size 0.7 0.7)
					(thickness 0.15)
				)
				(justify right top mirror)
			)
		)
		(property "Value" "R_1k_0402"
			(at -1.011843 -1.772046 90)
			(layer "B.Fab")
			(hide yes)
			(effects
				(font
					(size 0.7 0.7)
					(thickness 0.15)
				)
				(justify right top mirror)
			)
		)
		(property "Datasheet" "https://www.bourns.com/docs/product-datasheets/cr.pdf"
			(at 0 0 90)
			(layer "B.Fab")
			(hide yes)
			(effects
				(font
					(size 1.27 1.27)
					(thickness 0.15)
				)
				(justify mirror)
			)
		)
		(property "Description" "SMD Chip Resistor, 1 kohm, ± 1%, 63 mW, 0402 [1005 Metric], Thick Film, General Purpose"
			(at 0 0 90)
			(layer "B.Fab")
			(hide yes)
			(effects
				(font
					(size 1.27 1.27)
					(thickness 0.15)
				)
				(justify mirror)
			)
		)
		(property "MPN" "CR0402-FX-1001GLF"
			(at 0 0 90)
			(unlocked yes)
			(layer "B.Fab")
			(hide yes)
			(effects
				(font
					(size 1 1)
					(thickness 0.15)
				)
				(justify mirror)
			)
		)
		(property "Manufacturer" "Bourns"
			(at 0 0 90)
			(unlocked yes)
			(layer "B.Fab")
			(hide yes)
			(effects
				(font
					(size 1 1)
					(thickness 0.15)
				)
				(justify mirror)
			)
		)
		(property "License" "Apache-2.0"
			(at 0 0 90)
			(unlocked yes)
			(layer "B.Fab")
			(hide yes)
			(effects
				(font
					(size 1 1)
					(thickness 0.15)
				)
				(justify mirror)
			)
		)
		(property "Author" "Antmicro"
			(at 0 0 90)
			(unlocked yes)
			(layer "B.Fab")
			(hide yes)
			(effects
				(font
					(size 1 1)
					(thickness 0.15)
				)
				(justify mirror)
			)
		)
		(property "Val" "1k"
			(at 0 0 90)
			(unlocked yes)
			(layer "B.Fab")
			(hide yes)
			(effects
				(font
					(size 1 1)
					(thickness 0.15)
				)
				(justify mirror)
			)
		)
		(property "Tolerance" "1%"
			(at 0 0 90)
			(unlocked yes)
			(layer "B.Fab")
			(hide yes)
			(effects
				(font
					(size 1 1)
					(thickness 0.15)
				)
				(justify mirror)
			)
		)
		(sheetname "/X710-AT2 RSVD/")
		(sheetfile "x710-at2-rsvd.kicad_sch")
		(attr smd)
		(fp_rect
			(start -0.925 0.47)
			(end 0.925 -0.47)
			(stroke
				(width 0.05)
				(type default)
			)
			(fill no)
			(layer "B.CrtYd")
		)
		(fp_rect
			(start -0.5 0.25)
			(end 0.5 -0.25)
			(stroke
				(width 0.15)
				(type solid)
			)
			(fill no)
			(layer "B.Fab")
		)
		(pad "1" smd roundrect
			(at -0.48 0 90)
			(size 0.59 0.64)
			(layers "B.Cu" "B.Mask" "B.Paste")
			(roundrect_rratio 0.25)
			(net 120 "/X710-AT2 RSVD/DEBUG_W7")
			(pintype "passive")
		)
		(pad "2" smd roundrect
			(at 0.48 0 90)
			(size 0.59 0.64)
			(layers "B.Cu" "B.Mask" "B.Paste")
			(roundrect_rratio 0.25)
			(net 114 "/X710-AT2 RSVD/DEBUG_EN")
			(pintype "passive")
		)
	)
	(footprint "antmicro-footprints:R_0402_1005Metric"
		(layer "B.Cu")
		(at 109.5 71.6 180)
		(descr "Resistor SMD 0402")
		(tags "resistor SMD 0402")
		(property "Reference" "R169"
			(at -1.44 5.61 0)
			(layer "B.SilkS")
			(effects
				(font
					(size 0.7 0.7)
					(thickness 0.15)
				)
				(justify left bottom mirror)
			)
		)
		(property "Value" "R_0R_0402"
			(at -1.011843 -1.772046 0)
			(layer "B.Fab")
			(hide yes)
			(effects
				(font
					(size 0.7 0.7)
					(thickness 0.15)
				)
				(justify left bottom mirror)
			)
		)
		(property "Datasheet" "https://industrial.panasonic.com/cdbs/www-data/pdf/RDA0000/AOA0000C301.pdf"
			(at 0 0 0)
			(layer "B.Fab")
			(hide yes)
			(effects
				(font
					(size 1.27 1.27)
					(thickness 0.15)
				)
				(justify mirror)
			)
		)
		(property "Description" "SMD Chip Resistor, Jumper, 0 ohm, 100 mW, 0402 [1005 Metric], Thick Film, General Purpose"
			(at 0 0 0)
			(layer "B.Fab")
			(hide yes)
			(effects
				(font
					(size 1.27 1.27)
					(thickness 0.15)
				)
				(justify mirror)
			)
		)
		(property "MPN" "ERJ2GE0R00X"
			(at 0 0 180)
			(unlocked yes)
			(layer "B.Fab")
			(hide yes)
			(effects
				(font
					(size 1 1)
					(thickness 0.15)
				)
				(justify mirror)
			)
		)
		(property "Manufacturer" "Panasonic"
			(at 0 0 180)
			(unlocked yes)
			(layer "B.Fab")
			(hide yes)
			(effects
				(font
					(size 1 1)
					(thickness 0.15)
				)
				(justify mirror)
			)
		)
		(property "License" "Apache-2.0"
			(at 0 0 180)
			(unlocked yes)
			(layer "B.Fab")
			(hide yes)
			(effects
				(font
					(size 1 1)
					(thickness 0.15)
				)
				(justify mirror)
			)
		)
		(property "Author" "Antmicro"
			(at 0 0 180)
			(unlocked yes)
			(layer "B.Fab")
			(hide yes)
			(effects
				(font
					(size 1 1)
					(thickness 0.15)
				)
				(justify mirror)
			)
		)
		(property "Val" "0R"
			(at 0 0 180)
			(unlocked yes)
			(layer "B.Fab")
			(hide yes)
			(effects
				(font
					(size 1 1)
					(thickness 0.15)
				)
				(justify mirror)
			)
		)
		(property "Tolerance" "~"
			(at 0 0 180)
			(unlocked yes)
			(layer "B.Fab")
			(hide yes)
			(effects
				(font
					(size 1 1)
					(thickness 0.15)
				)
				(justify mirror)
			)
		)
		(property "Current" "1A"
			(at 0 0 180)
			(unlocked yes)
			(layer "B.Fab")
			(hide yes)
			(effects
				(font
					(size 1 1)
					(thickness 0.15)
				)
				(justify mirror)
			)
		)
		(sheetname "/OCuLink/")
		(sheetfile "oculink.kicad_sch")
		(attr smd)
		(fp_rect
			(start -0.925 0.47)
			(end 0.925 -0.47)
			(stroke
				(width 0.05)
				(type default)
			)
			(fill no)
			(layer "B.CrtYd")
		)
		(fp_rect
			(start -0.5 0.25)
			(end 0.5 -0.25)
			(stroke
				(width 0.15)
				(type solid)
			)
			(fill no)
			(layer "B.Fab")
		)
		(pad "1" smd roundrect
			(at -0.48 0 180)
			(size 0.59 0.64)
			(layers "B.Cu" "B.Mask" "B.Paste")
			(roundrect_rratio 0.25)
			(net 320 "/OCuLink/~{CWAKE}_R")
			(pintype "passive")
		)
		(pad "2" smd roundrect
			(at 0.48 0 180)
			(size 0.59 0.64)
			(layers "B.Cu" "B.Mask" "B.Paste")
			(roundrect_rratio 0.25)
			(net 309 "/OCuLink/~{PE_WAKE}")
			(pintype "passive")
		)
	)
	(footprint "antmicro-footprints:C_0402_1005Metric"
		(layer "B.Cu")
		(at 84.375 107.895 -90)
		(descr "Capacitor SMD 0402")
		(tags "capacitor SMD 0402")
		(property "Reference" "C177"
			(at 0.805 -0.355 90)
			(layer "B.SilkS")
			(effects
				(font
					(size 0.7 0.7)
					(thickness 0.15)
				)
				(justify left bottom mirror)
			)
		)
		(property "Value" "C_1u_25V_0402"
			(at -1.022927 -2.155213 90)
			(layer "B.Fab")
			(hide yes)
			(effects
				(font
					(size 0.7 0.7)
					(thickness 0.15)
				)
				(justify left bottom mirror)
			)
		)
		(property "Datasheet" "https://www.murata.com/products/productdetail?partno=GRM155R61E105KE11%23"
			(at 0 0 90)
			(layer "B.Fab")
			(hide yes)
			(effects
				(font
					(size 1.27 1.27)
					(thickness 0.15)
				)
				(justify mirror)
			)
		)
		(property "Description" "SMD Multilayer Ceramic Capacitor, 1 µF, 25 V, 0402 [1005 Metric], ± 10%, X5R, GRM Series"
			(at 0 0 90)
			(layer "B.Fab")
			(hide yes)
			(effects
				(font
					(size 1.27 1.27)
					(thickness 0.15)
				)
				(justify mirror)
			)
		)
		(property "MPN" "GRM155R61E105KE11J"
			(at 0 0 270)
			(unlocked yes)
			(layer "B.Fab")
			(hide yes)
			(effects
				(font
					(size 1 1)
					(thickness 0.15)
				)
				(justify mirror)
			)
		)
		(property "Manufacturer" "Murata"
			(at 0 0 270)
			(unlocked yes)
			(layer "B.Fab")
			(hide yes)
			(effects
				(font
					(size 1 1)
					(thickness 0.15)
				)
				(justify mirror)
			)
		)
		(property "License" "Apache-2.0"
			(at 0 0 270)
			(unlocked yes)
			(layer "B.Fab")
			(hide yes)
			(effects
				(font
					(size 1 1)
					(thickness 0.15)
				)
				(justify mirror)
			)
		)
		(property "Author" "Antmicro"
			(at 0 0 270)
			(unlocked yes)
			(layer "B.Fab")
			(hide yes)
			(effects
				(font
					(size 1 1)
					(thickness 0.15)
				)
				(justify mirror)
			)
		)
		(property "Val" "1u"
			(at 0 0 270)
			(unlocked yes)
			(layer "B.Fab")
			(hide yes)
			(effects
				(font
					(size 1 1)
					(thickness 0.15)
				)
				(justify mirror)
			)
		)
		(property "Voltage" "25V"
			(at 0 0 270)
			(unlocked yes)
			(layer "B.Fab")
			(hide yes)
			(effects
				(font
					(size 1 1)
					(thickness 0.15)
				)
				(justify mirror)
			)
		)
		(property "Dielectric" "X5R"
			(at 0 0 270)
			(unlocked yes)
			(layer "B.Fab")
			(hide yes)
			(effects
				(font
					(size 1 1)
					(thickness 0.15)
				)
				(justify mirror)
			)
		)
		(sheetname "/X710-AT2 power/")
		(sheetfile "x710-at2-power.kicad_sch")
		(attr smd)
		(fp_rect
			(start -0.925 0.47)
			(end 0.925 -0.47)
			(stroke
				(width 0.05)
				(type default)
			)
			(fill no)
			(layer "B.CrtYd")
		)
		(fp_line
			(start -0.494 0.25)
			(end 0.504 0.25)
			(stroke
				(width 0.15)
				(type solid)
			)
			(layer "B.Fab")
		)
		(fp_line
			(start 0.504 0.25)
			(end 0.504 -0.248)
			(stroke
				(width 0.15)
				(type solid)
			)
			(layer "B.Fab")
		)
		(fp_line
			(start -0.494 -0.248)
			(end -0.494 0.25)
			(stroke
				(width 0.15)
				(type solid)
			)
			(layer "B.Fab")
		)
		(fp_line
			(start 0.504 -0.248)
			(end -0.494 -0.248)
			(stroke
				(width 0.15)
				(type solid)
			)
			(layer "B.Fab")
		)
		(pad "1" smd roundrect
			(at -0.48 0 270)
			(size 0.59 0.64)
			(layers "B.Cu" "B.Mask" "B.Paste")
			(roundrect_rratio 0.25)
			(net 28 "GND")
			(pintype "passive")
		)
		(pad "2" smd roundrect
			(at 0.48 0 270)
			(size 0.59 0.64)
			(layers "B.Cu" "B.Mask" "B.Paste")
			(roundrect_rratio 0.25)
			(net 14 "P1_AVDDL")
			(pintype "passive")
		)
	)
	(footprint "antmicro-footprints:C_0402_1005Metric"
		(layer "B.Cu")
		(at 78.55 97.4 90)
		(descr "Capacitor SMD 0402")
		(tags "capacitor SMD 0402")
		(property "Reference" "C135"
			(at 1.02 -0.28 90)
			(layer "B.SilkS")
			(effects
				(font
					(size 0.7 0.7)
					(thickness 0.15)
				)
				(justify right top mirror)
			)
		)
		(property "Value" "C_1u_25V_0402"
			(at -1.022927 -2.155213 90)
			(layer "B.Fab")
			(hide yes)
			(effects
				(font
					(size 0.7 0.7)
					(thickness 0.15)
				)
				(justify right top mirror)
			)
		)
		(property "Datasheet" "https://www.murata.com/products/productdetail?partno=GRM155R61E105KE11%23"
			(at 0 0 90)
			(layer "B.Fab")
			(hide yes)
			(effects
				(font
					(size 1.27 1.27)
					(thickness 0.15)
				)
				(justify mirror)
			)
		)
		(property "Description" "SMD Multilayer Ceramic Capacitor, 1 µF, 25 V, 0402 [1005 Metric], ± 10%, X5R, GRM Series"
			(at 0 0 90)
			(layer "B.Fab")
			(hide yes)
			(effects
				(font
					(size 1.27 1.27)
					(thickness 0.15)
				)
				(justify mirror)
			)
		)
		(property "MPN" "GRM155R61E105KE11J"
			(at 0 0 90)
			(unlocked yes)
			(layer "B.Fab")
			(hide yes)
			(effects
				(font
					(size 1 1)
					(thickness 0.15)
				)
				(justify mirror)
			)
		)
		(property "Manufacturer" "Murata"
			(at 0 0 90)
			(unlocked yes)
			(layer "B.Fab")
			(hide yes)
			(effects
				(font
					(size 1 1)
					(thickness 0.15)
				)
				(justify mirror)
			)
		)
		(property "License" "Apache-2.0"
			(at 0 0 90)
			(unlocked yes)
			(layer "B.Fab")
			(hide yes)
			(effects
				(font
					(size 1 1)
					(thickness 0.15)
				)
				(justify mirror)
			)
		)
		(property "Author" "Antmicro"
			(at 0 0 90)
			(unlocked yes)
			(layer "B.Fab")
			(hide yes)
			(effects
				(font
					(size 1 1)
					(thickness 0.15)
				)
				(justify mirror)
			)
		)
		(property "Val" "1u"
			(at 0 0 90)
			(unlocked yes)
			(layer "B.Fab")
			(hide yes)
			(effects
				(font
					(size 1 1)
					(thickness 0.15)
				)
				(justify mirror)
			)
		)
		(property "Voltage" "25V"
			(at 0 0 90)
			(unlocked yes)
			(layer "B.Fab")
			(hide yes)
			(effects
				(font
					(size 1 1)
					(thickness 0.15)
				)
				(justify mirror)
			)
		)
		(property "Dielectric" "X5R"
			(at 0 0 90)
			(unlocked yes)
			(layer "B.Fab")
			(hide yes)
			(effects
				(font
					(size 1 1)
					(thickness 0.15)
				)
				(justify mirror)
			)
		)
		(sheetname "/X710-AT2 power/")
		(sheetfile "x710-at2-power.kicad_sch")
		(attr smd)
		(fp_rect
			(start -0.925 0.47)
			(end 0.925 -0.47)
			(stroke
				(width 0.05)
				(type default)
			)
			(fill no)
			(layer "B.CrtYd")
		)
		(fp_line
			(start 0.504 -0.248)
			(end -0.494 -0.248)
			(stroke
				(width 0.15)
				(type solid)
			)
			(layer "B.Fab")
		)
		(fp_line
			(start -0.494 -0.248)
			(end -0.494 0.25)
			(stroke
				(width 0.15)
				(type solid)
			)
			(layer "B.Fab")
		)
		(fp_line
			(start 0.504 0.25)
			(end 0.504 -0.248)
			(stroke
				(width 0.15)
				(type solid)
			)
			(layer "B.Fab")
		)
		(fp_line
			(start -0.494 0.25)
			(end 0.504 0.25)
			(stroke
				(width 0.15)
				(type solid)
			)
			(layer "B.Fab")
		)
		(pad "1" smd roundrect
			(at -0.48 0 90)
			(size 0.59 0.64)
			(layers "B.Cu" "B.Mask" "B.Paste")
			(roundrect_rratio 0.25)
			(net 28 "GND")
			(pintype "passive")
		)
		(pad "2" smd roundrect
			(at 0.48 0 90)
			(size 0.59 0.64)
			(layers "B.Cu" "B.Mask" "B.Paste")
			(roundrect_rratio 0.25)
			(net 7 "+3V3")
			(pintype "passive")
		)
	)
	(footprint "antmicro-footprints:TP_SMD_0.75mm"
		(layer "B.Cu")
		(at 103.55 101.2 90)
		(property "Reference" "TP5"
			(at 0.265351 0.625533 180)
			(layer "B.SilkS")
			(effects
				(font
					(size 0.7 0.7)
					(thickness 0.15)
				)
				(justify right top mirror)
			)
		)
		(property "Value" "TP_0.75mm_SMD"
			(at 0 -1.2 90)
			(layer "B.Fab")
			(hide yes)
			(effects
				(font
					(size 0.7 0.7)
					(thickness 0.15)
				)
				(justify right top mirror)
			)
		)
		(property "Description" "SMT test point"
			(at 0 0 90)
			(layer "B.Fab")
			(hide yes)
			(effects
				(font
					(size 1.27 1.27)
					(thickness 0.15)
				)
				(justify mirror)
			)
		)
		(property "MPN" ""
			(at 0 0 90)
			(unlocked yes)
			(layer "B.Fab")
			(hide yes)
			(effects
				(font
					(size 1 1)
					(thickness 0.15)
				)
				(justify mirror)
			)
		)
		(property "Manufacturer" ""
			(at 0 0 90)
			(unlocked yes)
			(layer "B.Fab")
			(hide yes)
			(effects
				(font
					(size 1 1)
					(thickness 0.15)
				)
				(justify mirror)
			)
		)
		(property "Author" "Antmicro"
			(at 0 0 90)
			(unlocked yes)
			(layer "B.Fab")
			(hide yes)
			(effects
				(font
					(size 1 1)
					(thickness 0.15)
				)
				(justify mirror)
			)
		)
		(property "License" "Apache-2.0"
			(at 0 0 90)
			(unlocked yes)
			(layer "B.Fab")
			(hide yes)
			(effects
				(font
					(size 1 1)
					(thickness 0.15)
				)
				(justify mirror)
			)
		)
		(sheetname "/X710-AT2 Misc/")
		(sheetfile "x710-at2-mics.kicad_sch")
		(attr exclude_from_pos_files exclude_from_bom)
		(fp_circle
			(center 0 0)
			(end 0.475 0)
			(stroke
				(width 0.05)
				(type default)
			)
			(fill no)
			(layer "B.CrtYd")
		)
		(pad "1" smd circle
			(at 0 0 90)
			(size 0.75 0.75)
			(layers "B.Cu" "B.Mask")
			(net 366 "/X710-AT2 Misc/NCSI.TX_EN")
			(pinfunction "1")
			(pintype "passive")
		)
	)
	(footprint "antmicro-footprints:L_0402_1005Metric"
		(layer "B.Cu")
		(at 81.95 130.4 180)
		(descr "Inductor SMD 0402")
		(tags "Inductor SMD 0402")
		(property "Reference" "L6"
			(at -0.72 -3.35 0)
			(layer "B.SilkS")
			(effects
				(font
					(size 0.7 0.7)
					(thickness 0.15)
				)
				(justify left bottom mirror)
			)
		)
		(property "Value" "L_2n4_0.85A_0402"
			(at 0 -1.399999 0)
			(layer "B.Fab")
			(hide yes)
			(effects
				(font
					(size 0.7 0.7)
					(thickness 0.15)
				)
				(justify left bottom mirror)
			)
		)
		(property "Datasheet" "https://www.murata.com/products/productdetail?partno=LQW15AN2N4B00%23"
			(at 0 0 0)
			(layer "B.Fab")
			(hide yes)
			(effects
				(font
					(size 1.27 1.27)
					(thickness 0.15)
				)
				(justify mirror)
			)
		)
		(property "Description" "Wirewound Inductor, 2.4 nH, 0.05 ohm, 15 GHz, 850 mA, 0402 [1005 Metric], LQW15AN"
			(at 0 0 0)
			(layer "B.Fab")
			(hide yes)
			(effects
				(font
					(size 1.27 1.27)
					(thickness 0.15)
				)
				(justify mirror)
			)
		)
		(property "Val" "2n4/0.85A"
			(at 0 0 180)
			(unlocked yes)
			(layer "B.Fab")
			(hide yes)
			(effects
				(font
					(size 1 1)
					(thickness 0.15)
				)
				(justify mirror)
			)
		)
		(property "Manufacturer" "Murata"
			(at 0 0 180)
			(unlocked yes)
			(layer "B.Fab")
			(hide yes)
			(effects
				(font
					(size 1 1)
					(thickness 0.15)
				)
				(justify mirror)
			)
		)
		(property "MPN" "LQW15AN2N4B00D"
			(at 0 0 180)
			(unlocked yes)
			(layer "B.Fab")
			(hide yes)
			(effects
				(font
					(size 1 1)
					(thickness 0.15)
				)
				(justify mirror)
			)
		)
		(property "ISat" "0.85 A"
			(at 0 0 180)
			(unlocked yes)
			(layer "B.Fab")
			(hide yes)
			(effects
				(font
					(size 1 1)
					(thickness 0.15)
				)
				(justify mirror)
			)
		)
		(property "IMax" "0.85 A"
			(at 0 0 180)
			(unlocked yes)
			(layer "B.Fab")
			(hide yes)
			(effects
				(font
					(size 1 1)
					(thickness 0.15)
				)
				(justify mirror)
			)
		)
		(property "Size" "1.0x0.5"
			(at 0 0 180)
			(unlocked yes)
			(layer "B.Fab")
			(hide yes)
			(effects
				(font
					(size 1 1)
					(thickness 0.15)
				)
				(justify mirror)
			)
		)
		(property "Author" "Antmicro"
			(at 0 0 180)
			(unlocked yes)
			(layer "B.Fab")
			(hide yes)
			(effects
				(font
					(size 1 1)
					(thickness 0.15)
				)
				(justify mirror)
			)
		)
		(property "License" "Apache-2.0"
			(at 0 0 180)
			(unlocked yes)
			(layer "B.Fab")
			(hide yes)
			(effects
				(font
					(size 1 1)
					(thickness 0.15)
				)
				(justify mirror)
			)
		)
		(sheetname "/2xRJ45/")
		(sheetfile "2xrj45.kicad_sch")
		(attr smd)
		(fp_rect
			(start -0.925 0.47)
			(end 0.925 -0.47)
			(stroke
				(width 0.05)
				(type default)
			)
			(fill no)
			(layer "B.CrtYd")
		)
		(fp_rect
			(start -0.499 0.249)
			(end 0.499 -0.249)
			(stroke
				(width 0.15)
				(type solid)
			)
			(fill no)
			(layer "B.Fab")
		)
		(pad "1" smd roundrect
			(at -0.48 0 180)
			(size 0.59 0.64)
			(layers "B.Cu" "B.Mask" "B.Paste")
			(roundrect_rratio 0.25)
			(net 301 "+1V88_CT")
			(pintype "passive")
		)
		(pad "2" smd roundrect
			(at 0.48 0 180)
			(size 0.59 0.64)
			(layers "B.Cu" "B.Mask" "B.Paste")
			(roundrect_rratio 0.25)
			(net 299 "/2xRJ45/P0_CT")
			(pintype "passive")
		)
	)
	(footprint "antmicro-footprints:TP_SMD_1mm"
		(layer "B.Cu")
		(at 75.74 72.3 -90)
		(property "Reference" "TP31"
			(at -1.83 4.508102 90)
			(layer "B.SilkS")
			(effects
				(font
					(size 0.7 0.7)
					(thickness 0.15)
				)
				(justify left bottom mirror)
			)
		)
		(property "Value" "TP_1mm_SMD"
			(at 0 -1.4 90)
			(layer "B.Fab")
			(hide yes)
			(effects
				(font
					(size 0.7 0.7)
					(thickness 0.15)
				)
				(justify left bottom mirror)
			)
		)
		(property "Description" "Test point 1mm SMD"
			(at 0 0 90)
			(layer "B.Fab")
			(hide yes)
			(effects
				(font
					(size 1.27 1.27)
					(thickness 0.15)
				)
				(justify mirror)
			)
		)
		(property "MPN" ""
			(at 0 0 90)
			(unlocked yes)
			(layer "B.Fab")
			(hide yes)
			(effects
				(font
					(size 1 1)
					(thickness 0.15)
				)
				(justify mirror)
			)
		)
		(property "Manufacturer" ""
			(at 0 0 90)
			(unlocked yes)
			(layer "B.Fab")
			(hide yes)
			(effects
				(font
					(size 1 1)
					(thickness 0.15)
				)
				(justify mirror)
			)
		)
		(property "Author" "Antmicro"
			(at 0 0 90)
			(unlocked yes)
			(layer "B.Fab")
			(hide yes)
			(effects
				(font
					(size 1 1)
					(thickness 0.15)
				)
				(justify mirror)
			)
		)
		(property "License" "Apache-2.0"
			(at 0 0 90)
			(unlocked yes)
			(layer "B.Fab")
			(hide yes)
			(effects
				(font
					(size 1 1)
					(thickness 0.15)
				)
				(justify mirror)
			)
		)
		(sheetname "/Power/")
		(sheetfile "power.kicad_sch")
		(attr exclude_from_pos_files exclude_from_bom)
		(fp_circle
			(center 0 0)
			(end 0.6 0)
			(stroke
				(width 0.05)
				(type default)
			)
			(fill no)
			(layer "B.CrtYd")
		)
		(pad "1" smd circle
			(at 0 0 270)
			(size 1 1)
			(layers "B.Cu" "B.Mask")
			(net 9 "VCCD")
			(pinfunction "1")
			(pintype "passive")
		)
	)
	(footprint "antmicro-footprints:R_0402_1005Metric"
		(layer "B.Cu")
		(at 91 111.15 -90)
		(descr "Resistor SMD 0402")
		(tags "resistor SMD 0402")
		(property "Reference" "R111"
			(at 0.84 -0.36 90)
			(layer "B.SilkS")
			(effects
				(font
					(size 0.7 0.7)
					(thickness 0.15)
				)
				(justify left bottom mirror)
			)
		)
		(property "Value" "R_1k_0402"
			(at -1.011843 -1.772046 90)
			(layer "B.Fab")
			(hide yes)
			(effects
				(font
					(size 0.7 0.7)
					(thickness 0.15)
				)
				(justify left bottom mirror)
			)
		)
		(property "Datasheet" "https://www.bourns.com/docs/product-datasheets/cr.pdf"
			(at 0 0 90)
			(layer "B.Fab")
			(hide yes)
			(effects
				(font
					(size 1.27 1.27)
					(thickness 0.15)
				)
				(justify mirror)
			)
		)
		(property "Description" "SMD Chip Resistor, 1 kohm, ± 1%, 63 mW, 0402 [1005 Metric], Thick Film, General Purpose"
			(at 0 0 90)
			(layer "B.Fab")
			(hide yes)
			(effects
				(font
					(size 1.27 1.27)
					(thickness 0.15)
				)
				(justify mirror)
			)
		)
		(property "MPN" "CR0402-FX-1001GLF"
			(at 0 0 270)
			(unlocked yes)
			(layer "B.Fab")
			(hide yes)
			(effects
				(font
					(size 1 1)
					(thickness 0.15)
				)
				(justify mirror)
			)
		)
		(property "Manufacturer" "Bourns"
			(at 0 0 270)
			(unlocked yes)
			(layer "B.Fab")
			(hide yes)
			(effects
				(font
					(size 1 1)
					(thickness 0.15)
				)
				(justify mirror)
			)
		)
		(property "License" "Apache-2.0"
			(at 0 0 270)
			(unlocked yes)
			(layer "B.Fab")
			(hide yes)
			(effects
				(font
					(size 1 1)
					(thickness 0.15)
				)
				(justify mirror)
			)
		)
		(property "Author" "Antmicro"
			(at 0 0 270)
			(unlocked yes)
			(layer "B.Fab")
			(hide yes)
			(effects
				(font
					(size 1 1)
					(thickness 0.15)
				)
				(justify mirror)
			)
		)
		(property "Val" "1k"
			(at 0 0 270)
			(unlocked yes)
			(layer "B.Fab")
			(hide yes)
			(effects
				(font
					(size 1 1)
					(thickness 0.15)
				)
				(justify mirror)
			)
		)
		(property "Tolerance" "1%"
			(at 0 0 270)
			(unlocked yes)
			(layer "B.Fab")
			(hide yes)
			(effects
				(font
					(size 1 1)
					(thickness 0.15)
				)
				(justify mirror)
			)
		)
		(sheetname "/X710-AT2 Misc/")
		(sheetfile "x710-at2-mics.kicad_sch")
		(attr smd)
		(fp_rect
			(start -0.925 0.47)
			(end 0.925 -0.47)
			(stroke
				(width 0.05)
				(type default)
			)
			(fill no)
			(layer "B.CrtYd")
		)
		(fp_rect
			(start -0.5 0.25)
			(end 0.5 -0.25)
			(stroke
				(width 0.15)
				(type solid)
			)
			(fill no)
			(layer "B.Fab")
		)
		(pad "1" smd roundrect
			(at -0.48 0 270)
			(size 0.59 0.64)
			(layers "B.Cu" "B.Mask" "B.Paste")
			(roundrect_rratio 0.25)
			(net 142 "/X710-AT2 10GbE/~{P0_INT}")
			(pintype "passive")
		)
		(pad "2" smd roundrect
			(at 0.48 0 270)
			(size 0.59 0.64)
			(layers "B.Cu" "B.Mask" "B.Paste")
			(roundrect_rratio 0.25)
			(net 7 "+3V3")
			(pintype "passive")
		)
	)
	(footprint "antmicro-footprints:C_0402_1005Metric"
		(layer "B.Cu")
		(at 81.95 131.4 180)
		(descr "Capacitor SMD 0402")
		(tags "capacitor SMD 0402")
		(property "Reference" "C59"
			(at -0.721 -3.350999 0)
			(layer "B.SilkS")
			(effects
				(font
					(size 0.7 0.7)
					(thickness 0.15)
				)
				(justify left bottom mirror)
			)
		)
		(property "Value" "C_1u_25V_0402"
			(at -1.022927 -2.155213 0)
			(layer "B.Fab")
			(hide yes)
			(effects
				(font
					(size 0.7 0.7)
					(thickness 0.15)
				)
				(justify left bottom mirror)
			)
		)
		(property "Datasheet" "https://www.murata.com/products/productdetail?partno=GRM155R61E105KE11%23"
			(at 0 0 0)
			(layer "B.Fab")
			(hide yes)
			(effects
				(font
					(size 1.27 1.27)
					(thickness 0.15)
				)
				(justify mirror)
			)
		)
		(property "Description" "SMD Multilayer Ceramic Capacitor, 1 µF, 25 V, 0402 [1005 Metric], ± 10%, X5R, GRM Series"
			(at 0 0 0)
			(layer "B.Fab")
			(hide yes)
			(effects
				(font
					(size 1.27 1.27)
					(thickness 0.15)
				)
				(justify mirror)
			)
		)
		(property "MPN" "GRM155R61E105KE11J"
			(at 0 0 180)
			(unlocked yes)
			(layer "B.Fab")
			(hide yes)
			(effects
				(font
					(size 1 1)
					(thickness 0.15)
				)
				(justify mirror)
			)
		)
		(property "Manufacturer" "Murata"
			(at 0 0 180)
			(unlocked yes)
			(layer "B.Fab")
			(hide yes)
			(effects
				(font
					(size 1 1)
					(thickness 0.15)
				)
				(justify mirror)
			)
		)
		(property "License" "Apache-2.0"
			(at 0 0 180)
			(unlocked yes)
			(layer "B.Fab")
			(hide yes)
			(effects
				(font
					(size 1 1)
					(thickness 0.15)
				)
				(justify mirror)
			)
		)
		(property "Author" "Antmicro"
			(at 0 0 180)
			(unlocked yes)
			(layer "B.Fab")
			(hide yes)
			(effects
				(font
					(size 1 1)
					(thickness 0.15)
				)
				(justify mirror)
			)
		)
		(property "Val" "1u"
			(at 0 0 180)
			(unlocked yes)
			(layer "B.Fab")
			(hide yes)
			(effects
				(font
					(size 1 1)
					(thickness 0.15)
				)
				(justify mirror)
			)
		)
		(property "Voltage" "25V"
			(at 0 0 180)
			(unlocked yes)
			(layer "B.Fab")
			(hide yes)
			(effects
				(font
					(size 1 1)
					(thickness 0.15)
				)
				(justify mirror)
			)
		)
		(property "Dielectric" "X5R"
			(at 0 0 180)
			(unlocked yes)
			(layer "B.Fab")
			(hide yes)
			(effects
				(font
					(size 1 1)
					(thickness 0.15)
				)
				(justify mirror)
			)
		)
		(sheetname "/2xRJ45/")
		(sheetfile "2xrj45.kicad_sch")
		(attr smd)
		(fp_rect
			(start -0.925 0.47)
			(end 0.925 -0.47)
			(stroke
				(width 0.05)
				(type default)
			)
			(fill no)
			(layer "B.CrtYd")
		)
		(fp_line
			(start 0.504 0.25)
			(end 0.504 -0.248)
			(stroke
				(width 0.15)
				(type solid)
			)
			(layer "B.Fab")
		)
		(fp_line
			(start 0.504 -0.248)
			(end -0.494 -0.248)
			(stroke
				(width 0.15)
				(type solid)
			)
			(layer "B.Fab")
		)
		(fp_line
			(start -0.494 0.25)
			(end 0.504 0.25)
			(stroke
				(width 0.15)
				(type solid)
			)
			(layer "B.Fab")
		)
		(fp_line
			(start -0.494 -0.248)
			(end -0.494 0.25)
			(stroke
				(width 0.15)
				(type solid)
			)
			(layer "B.Fab")
		)
		(pad "1" smd roundrect
			(at -0.48 0 180)
			(size 0.59 0.64)
			(layers "B.Cu" "B.Mask" "B.Paste")
			(roundrect_rratio 0.25)
			(net 28 "GND")
			(pintype "passive")
		)
		(pad "2" smd roundrect
			(at 0.48 0 180)
			(size 0.59 0.64)
			(layers "B.Cu" "B.Mask" "B.Paste")
			(roundrect_rratio 0.25)
			(net 299 "/2xRJ45/P0_CT")
			(pintype "passive")
		)
	)
	(footprint "antmicro-footprints:C_0402_1005Metric"
		(layer "B.Cu")
		(at 81 108.375)
		(descr "Capacitor SMD 0402")
		(tags "capacitor SMD 0402")
		(property "Reference" "C178"
			(at -0.97 11.475 0)
			(layer "B.SilkS")
			(effects
				(font
					(size 0.7 0.7)
					(thickness 0.15)
				)
				(justify right top mirror)
			)
		)
		(property "Value" "C_1u_25V_0402"
			(at -1.022927 -2.155213 0)
			(layer "B.Fab")
			(hide yes)
			(effects
				(font
					(size 0.7 0.7)
					(thickness 0.15)
				)
				(justify right top mirror)
			)
		)
		(property "Datasheet" "https://www.murata.com/products/productdetail?partno=GRM155R61E105KE11%23"
			(at 0 0 0)
			(layer "B.Fab")
			(hide yes)
			(effects
				(font
					(size 1.27 1.27)
					(thickness 0.15)
				)
				(justify mirror)
			)
		)
		(property "Description" "SMD Multilayer Ceramic Capacitor, 1 µF, 25 V, 0402 [1005 Metric], ± 10%, X5R, GRM Series"
			(at 0 0 0)
			(layer "B.Fab")
			(hide yes)
			(effects
				(font
					(size 1.27 1.27)
					(thickness 0.15)
				)
				(justify mirror)
			)
		)
		(property "MPN" "GRM155R61E105KE11J"
			(at 0 0 0)
			(unlocked yes)
			(layer "B.Fab")
			(hide yes)
			(effects
				(font
					(size 1 1)
					(thickness 0.15)
				)
				(justify mirror)
			)
		)
		(property "Manufacturer" "Murata"
			(at 0 0 0)
			(unlocked yes)
			(layer "B.Fab")
			(hide yes)
			(effects
				(font
					(size 1 1)
					(thickness 0.15)
				)
				(justify mirror)
			)
		)
		(property "License" "Apache-2.0"
			(at 0 0 0)
			(unlocked yes)
			(layer "B.Fab")
			(hide yes)
			(effects
				(font
					(size 1 1)
					(thickness 0.15)
				)
				(justify mirror)
			)
		)
		(property "Author" "Antmicro"
			(at 0 0 0)
			(unlocked yes)
			(layer "B.Fab")
			(hide yes)
			(effects
				(font
					(size 1 1)
					(thickness 0.15)
				)
				(justify mirror)
			)
		)
		(property "Val" "1u"
			(at 0 0 0)
			(unlocked yes)
			(layer "B.Fab")
			(hide yes)
			(effects
				(font
					(size 1 1)
					(thickness 0.15)
				)
				(justify mirror)
			)
		)
		(property "Voltage" "25V"
			(at 0 0 0)
			(unlocked yes)
			(layer "B.Fab")
			(hide yes)
			(effects
				(font
					(size 1 1)
					(thickness 0.15)
				)
				(justify mirror)
			)
		)
		(property "Dielectric" "X5R"
			(at 0 0 0)
			(unlocked yes)
			(layer "B.Fab")
			(hide yes)
			(effects
				(font
					(size 1 1)
					(thickness 0.15)
				)
				(justify mirror)
			)
		)
		(sheetname "/X710-AT2 power/")
		(sheetfile "x710-at2-power.kicad_sch")
		(attr smd)
		(fp_rect
			(start -0.925 0.47)
			(end 0.925 -0.47)
			(stroke
				(width 0.05)
				(type default)
			)
			(fill no)
			(layer "B.CrtYd")
		)
		(fp_line
			(start -0.494 -0.248)
			(end -0.494 0.25)
			(stroke
				(width 0.15)
				(type solid)
			)
			(layer "B.Fab")
		)
		(fp_line
			(start -0.494 0.25)
			(end 0.504 0.25)
			(stroke
				(width 0.15)
				(type solid)
			)
			(layer "B.Fab")
		)
		(fp_line
			(start 0.504 -0.248)
			(end -0.494 -0.248)
			(stroke
				(width 0.15)
				(type solid)
			)
			(layer "B.Fab")
		)
		(fp_line
			(start 0.504 0.25)
			(end 0.504 -0.248)
			(stroke
				(width 0.15)
				(type solid)
			)
			(layer "B.Fab")
		)
		(pad "1" smd roundrect
			(at -0.48 0)
			(size 0.59 0.64)
			(layers "B.Cu" "B.Mask" "B.Paste")
			(roundrect_rratio 0.25)
			(net 28 "GND")
			(pintype "passive")
		)
		(pad "2" smd roundrect
			(at 0.48 0)
			(size 0.59 0.64)
			(layers "B.Cu" "B.Mask" "B.Paste")
			(roundrect_rratio 0.25)
			(net 14 "P1_AVDDL")
			(pintype "passive")
		)
	)
	(footprint "antmicro-footprints:C_Pol_EIA-D"
		(layer "B.Cu")
		(at 65.25 107.55 90)
		(property "Reference" "C156"
			(at -1.45 -3.25 90)
			(layer "B.SilkS")
			(effects
				(font
					(size 0.7 0.7)
					(thickness 0.15)
				)
				(justify right top mirror)
			)
		)
		(property "Value" "C_Pol_470u_6.3V_Vishay-TR3-D"
			(at 0 -3.4 90)
			(layer "B.Fab")
			(hide yes)
			(effects
				(font
					(size 0.7 0.7)
					(thickness 0.15)
				)
				(justify right top mirror)
			)
		)
		(property "Datasheet" "https://www.vishay.com/docs/40080/tr3.pdf"
			(at 0 0 90)
			(layer "B.Fab")
			(hide yes)
			(effects
				(font
					(size 1.27 1.27)
					(thickness 0.15)
				)
				(justify mirror)
			)
		)
		(property "Description" "470 µF Molded Tantalum Capacitors 6.3 V 2917 (7343 Metric) 200mOhm"
			(at 0 0 90)
			(layer "B.Fab")
			(hide yes)
			(effects
				(font
					(size 1.27 1.27)
					(thickness 0.15)
				)
				(justify mirror)
			)
		)
		(property "Val" "470u"
			(at 0 0 90)
			(unlocked yes)
			(layer "B.Fab")
			(hide yes)
			(effects
				(font
					(size 1 1)
					(thickness 0.15)
				)
				(justify mirror)
			)
		)
		(property "MPN" "TR3D477M6R3C0200"
			(at 0 0 90)
			(unlocked yes)
			(layer "B.Fab")
			(hide yes)
			(effects
				(font
					(size 1 1)
					(thickness 0.15)
				)
				(justify mirror)
			)
		)
		(property "Manufacturer" "Vishay"
			(at 0 0 90)
			(unlocked yes)
			(layer "B.Fab")
			(hide yes)
			(effects
				(font
					(size 1 1)
					(thickness 0.15)
				)
				(justify mirror)
			)
		)
		(property "License" "Apache-2.0"
			(at 0 0 90)
			(unlocked yes)
			(layer "B.Fab")
			(hide yes)
			(effects
				(font
					(size 1 1)
					(thickness 0.15)
				)
				(justify mirror)
			)
		)
		(property "Author" "Antmicro"
			(at 0 0 90)
			(unlocked yes)
			(layer "B.Fab")
			(hide yes)
			(effects
				(font
					(size 1 1)
					(thickness 0.15)
				)
				(justify mirror)
			)
		)
		(property "Voltage" "6.3V"
			(at 0 0 90)
			(unlocked yes)
			(layer "B.Fab")
			(hide yes)
			(effects
				(font
					(size 1 1)
					(thickness 0.15)
				)
				(justify mirror)
			)
		)
		(property "Dielectric" "template_dielectric"
			(at 0 0 90)
			(unlocked yes)
			(layer "B.Fab")
			(hide yes)
			(effects
				(font
					(size 1 1)
					(thickness 0.15)
				)
				(justify mirror)
			)
		)
		(sheetname "/X710-AT2 power/")
		(sheetfile "x710-at2-power.kicad_sch")
		(attr smd)
		(fp_line
			(start 3.6 -2.2)
			(end -3.58 -2.2)
			(stroke
				(width 0.15)
				(type solid)
			)
			(layer "B.SilkS")
		)
		(fp_line
			(start -3.58 -2.2)
			(end -3.58 -1.6)
			(stroke
				(width 0.15)
				(type solid)
			)
			(layer "B.SilkS")
		)
		(fp_line
			(start 3.6 -1.6)
			(end 3.6 -2.2)
			(stroke
				(width 0.15)
				(type solid)
			)
			(layer "B.SilkS")
		)
		(fp_line
			(start -3.58 1.6)
			(end -3.58 2.2)
			(stroke
				(width 0.15)
				(type solid)
			)
			(layer "B.SilkS")
		)
		(fp_line
			(start -4.3 1.825)
			(end -3.9 1.825)
			(stroke
				(width 0.12)
				(type solid)
			)
			(layer "B.SilkS")
		)
		(fp_line
			(start -4.1 2.025)
			(end -4.1 1.625)
			(stroke
				(width 0.12)
				(type solid)
			)
			(layer "B.SilkS")
		)
		(fp_line
			(start 3.6 2.2)
			(end 3.6 1.6)
			(stroke
				(width 0.15)
				(type solid)
			)
			(layer "B.SilkS")
		)
		(fp_line
			(start -3.58 2.2)
			(end 3.6 2.2)
			(stroke
				(width 0.15)
				(type solid)
			)
			(layer "B.SilkS")
		)
		(fp_line
			(start 3.77 -2.4)
			(end -3.77 -2.4)
			(stroke
				(width 0.05)
				(type solid)
			)
			(layer "B.CrtYd")
		)
		(fp_line
			(start -3.77 -2.4)
			(end -3.77 -1.51)
			(stroke
				(width 0.05)
				(type solid)
			)
			(layer "B.CrtYd")
		)
		(fp_line
			(start 4.505 -1.51)
			(end 3.77 -1.51)
			(stroke
				(width 0.05)
				(type solid)
			)
			(layer "B.CrtYd")
		)
		(fp_line
			(start 3.77 -1.51)
			(end 3.77 -2.4)
			(stroke
				(width 0.05)
				(type solid)
			)
			(layer "B.CrtYd")
		)
		(fp_line
			(start -3.77 -1.51)
			(end -4.505 -1.51)
			(stroke
				(width 0.05)
				(type solid)
			)
			(layer "B.CrtYd")
		)
		(fp_line
			(start -4.505 -1.51)
			(end -4.505 1.5)
			(stroke
				(width 0.05)
				(type solid)
			)
			(layer "B.CrtYd")
		)
		(fp_line
			(start -3.775 1.5)
			(end -4.505 1.5)
			(stroke
				(width 0.05)
				(type solid)
			)
			(layer "B.CrtYd")
		)
		(fp_line
			(start 4.505 1.51)
			(end 4.505 -1.5)
			(stroke
				(width 0.05)
				(type solid)
			)
			(layer "B.CrtYd")
		)
		(fp_line
			(start 3.77 1.51)
			(end 4.505 1.51)
			(stroke
				(width 0.05)
				(type solid)
			)
			(layer "B.CrtYd")
		)
		(fp_line
			(start 3.77 2.4)
			(end 3.77 1.51)
			(stroke
				(width 0.05)
				(type solid)
			)
			(layer "B.CrtYd")
		)
		(fp_line
			(start -3.775 2.4)
			(end -3.775 1.5)
			(stroke
				(width 0.05)
				(type solid)
			)
			(layer "B.CrtYd")
		)
		(fp_line
			(start -3.775 2.4)
			(end 3.77 2.4)
			(stroke
				(width 0.05)
				(type solid)
			)
			(layer "B.CrtYd")
		)
		(fp_rect
			(start -3.65 2.15)
			(end 3.65 -2.15)
			(stroke
				(width 0.15)
				(type solid)
			)
			(fill no)
			(layer "B.Fab")
		)
		(pad "1" smd roundrect
			(at -3.1 0 90)
			(size 2.31 2.52)
			(layers "B.Cu" "B.Mask" "B.Paste")
			(roundrect_rratio 0.1)
			(net 302 "+1V0")
			(pintype "passive")
		)
		(pad "2" smd roundrect
			(at 3.1 0 90)
			(size 2.31 2.52)
			(layers "B.Cu" "B.Mask" "B.Paste")
			(roundrect_rratio 0.1)
			(net 28 "GND")
			(pintype "passive")
		)
	)
	(footprint "antmicro-footprints:C_0402_1005Metric"
		(layer "B.Cu")
		(at 83.24 105.08 90)
		(descr "Capacitor SMD 0402")
		(tags "capacitor SMD 0402")
		(property "Reference" "C103"
			(at -1.29 0.6 90)
			(layer "B.SilkS")
			(effects
				(font
					(size 0.7 0.7)
					(thickness 0.15)
				)
				(justify right top mirror)
			)
		)
		(property "Value" "C_1u_25V_0402"
			(at -1.022927 -2.155213 90)
			(layer "B.Fab")
			(hide yes)
			(effects
				(font
					(size 0.7 0.7)
					(thickness 0.15)
				)
				(justify right top mirror)
			)
		)
		(property "Datasheet" "https://www.murata.com/products/productdetail?partno=GRM155R61E105KE11%23"
			(at 0 0 90)
			(layer "B.Fab")
			(hide yes)
			(effects
				(font
					(size 1.27 1.27)
					(thickness 0.15)
				)
				(justify mirror)
			)
		)
		(property "Description" "SMD Multilayer Ceramic Capacitor, 1 µF, 25 V, 0402 [1005 Metric], ± 10%, X5R, GRM Series"
			(at 0 0 90)
			(layer "B.Fab")
			(hide yes)
			(effects
				(font
					(size 1.27 1.27)
					(thickness 0.15)
				)
				(justify mirror)
			)
		)
		(property "MPN" "GRM155R61E105KE11J"
			(at 0 0 90)
			(unlocked yes)
			(layer "B.Fab")
			(hide yes)
			(effects
				(font
					(size 1 1)
					(thickness 0.15)
				)
				(justify mirror)
			)
		)
		(property "Manufacturer" "Murata"
			(at 0 0 90)
			(unlocked yes)
			(layer "B.Fab")
			(hide yes)
			(effects
				(font
					(size 1 1)
					(thickness 0.15)
				)
				(justify mirror)
			)
		)
		(property "License" "Apache-2.0"
			(at 0 0 90)
			(unlocked yes)
			(layer "B.Fab")
			(hide yes)
			(effects
				(font
					(size 1 1)
					(thickness 0.15)
				)
				(justify mirror)
			)
		)
		(property "Author" "Antmicro"
			(at 0 0 90)
			(unlocked yes)
			(layer "B.Fab")
			(hide yes)
			(effects
				(font
					(size 1 1)
					(thickness 0.15)
				)
				(justify mirror)
			)
		)
		(property "Val" "1u"
			(at 0 0 90)
			(unlocked yes)
			(layer "B.Fab")
			(hide yes)
			(effects
				(font
					(size 1 1)
					(thickness 0.15)
				)
				(justify mirror)
			)
		)
		(property "Voltage" "25V"
			(at 0 0 90)
			(unlocked yes)
			(layer "B.Fab")
			(hide yes)
			(effects
				(font
					(size 1 1)
					(thickness 0.15)
				)
				(justify mirror)
			)
		)
		(property "Dielectric" "X5R"
			(at 0 0 90)
			(unlocked yes)
			(layer "B.Fab")
			(hide yes)
			(effects
				(font
					(size 1 1)
					(thickness 0.15)
				)
				(justify mirror)
			)
		)
		(sheetname "/X710-AT2 power/")
		(sheetfile "x710-at2-power.kicad_sch")
		(attr smd)
		(fp_rect
			(start -0.925 0.47)
			(end 0.925 -0.47)
			(stroke
				(width 0.05)
				(type default)
			)
			(fill no)
			(layer "B.CrtYd")
		)
		(fp_line
			(start 0.504 -0.248)
			(end -0.494 -0.248)
			(stroke
				(width 0.15)
				(type solid)
			)
			(layer "B.Fab")
		)
		(fp_line
			(start -0.494 -0.248)
			(end -0.494 0.25)
			(stroke
				(width 0.15)
				(type solid)
			)
			(layer "B.Fab")
		)
		(fp_line
			(start 0.504 0.25)
			(end 0.504 -0.248)
			(stroke
				(width 0.15)
				(type solid)
			)
			(layer "B.Fab")
		)
		(fp_line
			(start -0.494 0.25)
			(end 0.504 0.25)
			(stroke
				(width 0.15)
				(type solid)
			)
			(layer "B.Fab")
		)
		(pad "1" smd roundrect
			(at -0.48 0 90)
			(size 0.59 0.64)
			(layers "B.Cu" "B.Mask" "B.Paste")
			(roundrect_rratio 0.25)
			(net 28 "GND")
			(pintype "passive")
		)
		(pad "2" smd roundrect
			(at 0.48 0 90)
			(size 0.59 0.64)
			(layers "B.Cu" "B.Mask" "B.Paste")
			(roundrect_rratio 0.25)
			(net 18 "+1V88")
			(pintype "passive")
		)
	)
	(footprint "antmicro-footprints:C_0402_1005Metric"
		(layer "B.Cu")
		(at 86.225 94.6 90)
		(descr "Capacitor SMD 0402")
		(tags "capacitor SMD 0402")
		(property "Reference" "C93"
			(at 12.5 -0.462343 90)
			(layer "B.SilkS")
			(effects
				(font
					(size 0.7 0.7)
					(thickness 0.15)
				)
				(justify right top mirror)
			)
		)
		(property "Value" "C_1u_25V_0402"
			(at -1.022927 -2.155213 90)
			(layer "B.Fab")
			(hide yes)
			(effects
				(font
					(size 0.7 0.7)
					(thickness 0.15)
				)
				(justify right top mirror)
			)
		)
		(property "Datasheet" "https://www.murata.com/products/productdetail?partno=GRM155R61E105KE11%23"
			(at 0 0 90)
			(layer "B.Fab")
			(hide yes)
			(effects
				(font
					(size 1.27 1.27)
					(thickness 0.15)
				)
				(justify mirror)
			)
		)
		(property "Description" "SMD Multilayer Ceramic Capacitor, 1 µF, 25 V, 0402 [1005 Metric], ± 10%, X5R, GRM Series"
			(at 0 0 90)
			(layer "B.Fab")
			(hide yes)
			(effects
				(font
					(size 1.27 1.27)
					(thickness 0.15)
				)
				(justify mirror)
			)
		)
		(property "MPN" "GRM155R61E105KE11J"
			(at 0 0 90)
			(unlocked yes)
			(layer "B.Fab")
			(hide yes)
			(effects
				(font
					(size 1 1)
					(thickness 0.15)
				)
				(justify mirror)
			)
		)
		(property "Manufacturer" "Murata"
			(at 0 0 90)
			(unlocked yes)
			(layer "B.Fab")
			(hide yes)
			(effects
				(font
					(size 1 1)
					(thickness 0.15)
				)
				(justify mirror)
			)
		)
		(property "License" "Apache-2.0"
			(at 0 0 90)
			(unlocked yes)
			(layer "B.Fab")
			(hide yes)
			(effects
				(font
					(size 1 1)
					(thickness 0.15)
				)
				(justify mirror)
			)
		)
		(property "Author" "Antmicro"
			(at 0 0 90)
			(unlocked yes)
			(layer "B.Fab")
			(hide yes)
			(effects
				(font
					(size 1 1)
					(thickness 0.15)
				)
				(justify mirror)
			)
		)
		(property "Val" "1u"
			(at 0 0 90)
			(unlocked yes)
			(layer "B.Fab")
			(hide yes)
			(effects
				(font
					(size 1 1)
					(thickness 0.15)
				)
				(justify mirror)
			)
		)
		(property "Voltage" "25V"
			(at 0 0 90)
			(unlocked yes)
			(layer "B.Fab")
			(hide yes)
			(effects
				(font
					(size 1 1)
					(thickness 0.15)
				)
				(justify mirror)
			)
		)
		(property "Dielectric" "X5R"
			(at 0 0 90)
			(unlocked yes)
			(layer "B.Fab")
			(hide yes)
			(effects
				(font
					(size 1 1)
					(thickness 0.15)
				)
				(justify mirror)
			)
		)
		(sheetname "/X710-AT2 power/")
		(sheetfile "x710-at2-power.kicad_sch")
		(attr smd)
		(fp_rect
			(start -0.925 0.47)
			(end 0.925 -0.47)
			(stroke
				(width 0.05)
				(type default)
			)
			(fill no)
			(layer "B.CrtYd")
		)
		(fp_line
			(start 0.504 -0.248)
			(end -0.494 -0.248)
			(stroke
				(width 0.15)
				(type solid)
			)
			(layer "B.Fab")
		)
		(fp_line
			(start -0.494 -0.248)
			(end -0.494 0.25)
			(stroke
				(width 0.15)
				(type solid)
			)
			(layer "B.Fab")
		)
		(fp_line
			(start 0.504 0.25)
			(end 0.504 -0.248)
			(stroke
				(width 0.15)
				(type solid)
			)
			(layer "B.Fab")
		)
		(fp_line
			(start -0.494 0.25)
			(end 0.504 0.25)
			(stroke
				(width 0.15)
				(type solid)
			)
			(layer "B.Fab")
		)
		(pad "1" smd roundrect
			(at -0.48 0 90)
			(size 0.59 0.64)
			(layers "B.Cu" "B.Mask" "B.Paste")
			(roundrect_rratio 0.25)
			(net 28 "GND")
			(pintype "passive")
		)
		(pad "2" smd roundrect
			(at 0.48 0 90)
			(size 0.59 0.64)
			(layers "B.Cu" "B.Mask" "B.Paste")
			(roundrect_rratio 0.25)
			(net 1 "VCCA")
			(pintype "passive")
		)
	)
	(footprint "antmicro-footprints:R_0402_1005Metric"
		(layer "B.Cu")
		(at 99.16 89.214 180)
		(descr "Resistor SMD 0402")
		(tags "resistor SMD 0402")
		(property "Reference" "R122"
			(at 0.85 -0.436 0)
			(layer "B.SilkS")
			(effects
				(font
					(size 0.7 0.7)
					(thickness 0.15)
				)
				(justify left bottom mirror)
			)
		)
		(property "Value" "R_0R_0402"
			(at -1.011843 -1.772047 0)
			(layer "B.Fab")
			(hide yes)
			(effects
				(font
					(size 0.7 0.7)
					(thickness 0.15)
				)
				(justify left bottom mirror)
			)
		)
		(property "Datasheet" "https://industrial.panasonic.com/cdbs/www-data/pdf/RDA0000/AOA0000C301.pdf"
			(at 0 0 0)
			(layer "B.Fab")
			(hide yes)
			(effects
				(font
					(size 1.27 1.27)
					(thickness 0.15)
				)
				(justify mirror)
			)
		)
		(property "Description" "SMD Chip Resistor, Jumper, 0 ohm, 100 mW, 0402 [1005 Metric], Thick Film, General Purpose"
			(at 0 0 0)
			(layer "B.Fab")
			(hide yes)
			(effects
				(font
					(size 1.27 1.27)
					(thickness 0.15)
				)
				(justify mirror)
			)
		)
		(property "MPN" "ERJ2GE0R00X"
			(at 0 0 0)
			(unlocked yes)
			(layer "B.Fab")
			(hide yes)
			(effects
				(font
					(size 1 1)
					(thickness 0.15)
				)
				(justify mirror)
			)
		)
		(property "Manufacturer" "Panasonic"
			(at 0 0 0)
			(unlocked yes)
			(layer "B.Fab")
			(hide yes)
			(effects
				(font
					(size 1 1)
					(thickness 0.15)
				)
				(justify mirror)
			)
		)
		(property "License" "Apache-2.0"
			(at 0 0 0)
			(unlocked yes)
			(layer "B.Fab")
			(hide yes)
			(effects
				(font
					(size 1 1)
					(thickness 0.15)
				)
				(justify mirror)
			)
		)
		(property "Author" "Antmicro"
			(at 0 0 0)
			(unlocked yes)
			(layer "B.Fab")
			(hide yes)
			(effects
				(font
					(size 1 1)
					(thickness 0.15)
				)
				(justify mirror)
			)
		)
		(property "Val" "0R"
			(at 0 0 0)
			(unlocked yes)
			(layer "B.Fab")
			(hide yes)
			(effects
				(font
					(size 1 1)
					(thickness 0.15)
				)
				(justify mirror)
			)
		)
		(property "Tolerance" "~"
			(at 0 0 0)
			(unlocked yes)
			(layer "B.Fab")
			(hide yes)
			(effects
				(font
					(size 1 1)
					(thickness 0.15)
				)
				(justify mirror)
			)
		)
		(property "Current" "1A"
			(at 0 0 0)
			(unlocked yes)
			(layer "B.Fab")
			(hide yes)
			(effects
				(font
					(size 1 1)
					(thickness 0.15)
				)
				(justify mirror)
			)
		)
		(sheetname "/X710-AT2 PCIe/")
		(sheetfile "x710-at2-pcie.kicad_sch")
		(attr smd exclude_from_pos_files exclude_from_bom dnp)
		(fp_rect
			(start -0.925 0.47)
			(end 0.925 -0.47)
			(stroke
				(width 0.05)
				(type default)
			)
			(fill no)
			(layer "B.CrtYd")
		)
		(fp_rect
			(start -0.5 0.25)
			(end 0.5 -0.25)
			(stroke
				(width 0.15)
				(type solid)
			)
			(fill no)
			(layer "B.Fab")
		)
		(pad "1" smd roundrect
			(at -0.48 0 180)
			(size 0.59 0.64)
			(layers "B.Cu" "B.Mask" "B.Paste")
			(roundrect_rratio 0.25)
			(net 406 "/X710-AT2 PCIe/GEN_F_CLK-")
			(pintype "passive")
		)
		(pad "2" smd roundrect
			(at 0.48 0 180)
			(size 0.59 0.64)
			(layers "B.Cu" "B.Mask" "B.Paste")
			(roundrect_rratio 0.25)
			(net 403 "/X710-AT2 PCIe/CLK-")
			(pintype "passive")
		)
	)
	(footprint "antmicro-footprints:R_0402_1005Metric"
		(layer "B.Cu")
		(at 96.88 111.960001 180)
		(descr "Resistor SMD 0402")
		(tags "resistor SMD 0402")
		(property "Reference" "R49"
			(at 0.84 -0.509999 0)
			(layer "B.SilkS")
			(effects
				(font
					(size 0.7 0.7)
					(thickness 0.15)
				)
				(justify left bottom mirror)
			)
		)
		(property "Value" "R_100R_0402"
			(at -1.011843 -1.772046 0)
			(layer "B.Fab")
			(hide yes)
			(effects
				(font
					(size 0.7 0.7)
					(thickness 0.15)
				)
				(justify left bottom mirror)
			)
		)
		(property "Datasheet" "https://www.bourns.com/docs/product-datasheets/cr.pdf"
			(at 0 0 0)
			(layer "B.Fab")
			(hide yes)
			(effects
				(font
					(size 1.27 1.27)
					(thickness 0.15)
				)
				(justify mirror)
			)
		)
		(property "Description" "SMD Chip Resistor, 100 ohm, ± 1%, 62.5 mW, 0402 [1005 Metric], Thick Film, General Purpose"
			(at 0 0 0)
			(layer "B.Fab")
			(hide yes)
			(effects
				(font
					(size 1.27 1.27)
					(thickness 0.15)
				)
				(justify mirror)
			)
		)
		(property "MPN" "CR0402-FX-1000GLF"
			(at 0 0 180)
			(unlocked yes)
			(layer "B.Fab")
			(hide yes)
			(effects
				(font
					(size 1 1)
					(thickness 0.15)
				)
				(justify mirror)
			)
		)
		(property "Manufacturer" "Bourns"
			(at 0 0 180)
			(unlocked yes)
			(layer "B.Fab")
			(hide yes)
			(effects
				(font
					(size 1 1)
					(thickness 0.15)
				)
				(justify mirror)
			)
		)
		(property "License" "Apache-2.0"
			(at 0 0 180)
			(unlocked yes)
			(layer "B.Fab")
			(hide yes)
			(effects
				(font
					(size 1 1)
					(thickness 0.15)
				)
				(justify mirror)
			)
		)
		(property "Author" "Antmicro"
			(at 0 0 180)
			(unlocked yes)
			(layer "B.Fab")
			(hide yes)
			(effects
				(font
					(size 1 1)
					(thickness 0.15)
				)
				(justify mirror)
			)
		)
		(property "Val" "100R"
			(at 0 0 180)
			(unlocked yes)
			(layer "B.Fab")
			(hide yes)
			(effects
				(font
					(size 1 1)
					(thickness 0.15)
				)
				(justify mirror)
			)
		)
		(property "Tolerance" "1%"
			(at 0 0 180)
			(unlocked yes)
			(layer "B.Fab")
			(hide yes)
			(effects
				(font
					(size 1 1)
					(thickness 0.15)
				)
				(justify mirror)
			)
		)
		(sheetname "/X710-AT2 Misc/")
		(sheetfile "x710-at2-mics.kicad_sch")
		(attr smd)
		(fp_rect
			(start -0.925 0.47)
			(end 0.925 -0.47)
			(stroke
				(width 0.05)
				(type default)
			)
			(fill no)
			(layer "B.CrtYd")
		)
		(fp_rect
			(start -0.5 0.25)
			(end 0.5 -0.25)
			(stroke
				(width 0.15)
				(type solid)
			)
			(fill no)
			(layer "B.Fab")
		)
		(pad "1" smd roundrect
			(at -0.48 0 180)
			(size 0.59 0.64)
			(layers "B.Cu" "B.Mask" "B.Paste")
			(roundrect_rratio 0.25)
			(net 157 "Net-(U7-A_{2})")
			(pintype "passive")
		)
		(pad "2" smd roundrect
			(at 0.48 0 180)
			(size 0.59 0.64)
			(layers "B.Cu" "B.Mask" "B.Paste")
			(roundrect_rratio 0.25)
			(net 28 "GND")
			(pintype "passive")
		)
	)
	(footprint "antmicro-footprints:TP_SMD_1mm"
		(layer "B.Cu")
		(at 80.24 74.55 -90)
		(property "Reference" "TP33"
			(at -1.07 7.15 90)
			(layer "B.SilkS")
			(effects
				(font
					(size 0.7 0.7)
					(thickness 0.15)
				)
				(justify left bottom mirror)
			)
		)
		(property "Value" "TP_1mm_SMD"
			(at 0 -1.4 90)
			(layer "B.Fab")
			(hide yes)
			(effects
				(font
					(size 0.7 0.7)
					(thickness 0.15)
				)
				(justify left bottom mirror)
			)
		)
		(property "Description" "Test point 1mm SMD"
			(at 0 0 90)
			(layer "B.Fab")
			(hide yes)
			(effects
				(font
					(size 1.27 1.27)
					(thickness 0.15)
				)
				(justify mirror)
			)
		)
		(property "MPN" ""
			(at 0 0 90)
			(unlocked yes)
			(layer "B.Fab")
			(hide yes)
			(effects
				(font
					(size 1 1)
					(thickness 0.15)
				)
				(justify mirror)
			)
		)
		(property "Manufacturer" ""
			(at 0 0 90)
			(unlocked yes)
			(layer "B.Fab")
			(hide yes)
			(effects
				(font
					(size 1 1)
					(thickness 0.15)
				)
				(justify mirror)
			)
		)
		(property "Author" "Antmicro"
			(at 0 0 90)
			(unlocked yes)
			(layer "B.Fab")
			(hide yes)
			(effects
				(font
					(size 1 1)
					(thickness 0.15)
				)
				(justify mirror)
			)
		)
		(property "License" "Apache-2.0"
			(at 0 0 90)
			(unlocked yes)
			(layer "B.Fab")
			(hide yes)
			(effects
				(font
					(size 1 1)
					(thickness 0.15)
				)
				(justify mirror)
			)
		)
		(sheetname "/Power/")
		(sheetfile "power.kicad_sch")
		(attr exclude_from_pos_files exclude_from_bom)
		(fp_circle
			(center 0 0)
			(end 0.6 0)
			(stroke
				(width 0.05)
				(type default)
			)
			(fill no)
			(layer "B.CrtYd")
		)
		(pad "1" smd circle
			(at 0 0 270)
			(size 1 1)
			(layers "B.Cu" "B.Mask")
			(net 302 "+1V0")
			(pinfunction "1")
			(pintype "passive")
		)
	)
	(footprint "antmicro-footprints:TP_SMD_0.75mm"
		(layer "B.Cu")
		(at 87.725 104.85 90)
		(property "Reference" "TP13"
			(at 1.37 -2.115 180)
			(layer "B.SilkS")
			(effects
				(font
					(size 0.7 0.7)
					(thickness 0.15)
				)
				(justify right top mirror)
			)
		)
		(property "Value" "TP_0.75mm_SMD"
			(at 0 -1.2 90)
			(layer "B.Fab")
			(hide yes)
			(effects
				(font
					(size 0.7 0.7)
					(thickness 0.15)
				)
				(justify right top mirror)
			)
		)
		(property "Description" "SMT test point"
			(at 0 0 90)
			(layer "B.Fab")
			(hide yes)
			(effects
				(font
					(size 1.27 1.27)
					(thickness 0.15)
				)
				(justify mirror)
			)
		)
		(property "MPN" ""
			(at 0 0 90)
			(unlocked yes)
			(layer "B.Fab")
			(hide yes)
			(effects
				(font
					(size 1 1)
					(thickness 0.15)
				)
				(justify mirror)
			)
		)
		(property "Manufacturer" ""
			(at 0 0 90)
			(unlocked yes)
			(layer "B.Fab")
			(hide yes)
			(effects
				(font
					(size 1 1)
					(thickness 0.15)
				)
				(justify mirror)
			)
		)
		(property "Author" "Antmicro"
			(at 0 0 90)
			(unlocked yes)
			(layer "B.Fab")
			(hide yes)
			(effects
				(font
					(size 1 1)
					(thickness 0.15)
				)
				(justify mirror)
			)
		)
		(property "License" "Apache-2.0"
			(at 0 0 90)
			(unlocked yes)
			(layer "B.Fab")
			(hide yes)
			(effects
				(font
					(size 1 1)
					(thickness 0.15)
				)
				(justify mirror)
			)
		)
		(sheetname "/X710-AT2 Misc/")
		(sheetfile "x710-at2-mics.kicad_sch")
		(attr exclude_from_pos_files exclude_from_bom)
		(fp_circle
			(center 0 0)
			(end 0.475 0)
			(stroke
				(width 0.05)
				(type default)
			)
			(fill no)
			(layer "B.CrtYd")
		)
		(pad "1" smd circle
			(at 0 0 90)
			(size 0.75 0.75)
			(layers "B.Cu" "B.Mask")
			(net 137 "/X710-AT2 Misc/PHY_TDO")
			(pinfunction "1")
			(pintype "passive")
		)
	)
	(footprint "antmicro-footprints:C_0402_1005Metric"
		(layer "B.Cu")
		(at 81.22 103.23 90)
		(descr "Capacitor SMD 0402")
		(tags "capacitor SMD 0402")
		(property "Reference" "C184"
			(at -11.62 -0.04 90)
			(layer "B.SilkS")
			(effects
				(font
					(size 0.7 0.7)
					(thickness 0.15)
				)
				(justify right top mirror)
			)
		)
		(property "Value" "C_1u_25V_0402"
			(at -1.022927 -2.155213 90)
			(layer "B.Fab")
			(hide yes)
			(effects
				(font
					(size 0.7 0.7)
					(thickness 0.15)
				)
				(justify right top mirror)
			)
		)
		(property "Datasheet" "https://www.murata.com/products/productdetail?partno=GRM155R61E105KE11%23"
			(at 0 0 90)
			(layer "B.Fab")
			(hide yes)
			(effects
				(font
					(size 1.27 1.27)
					(thickness 0.15)
				)
				(justify mirror)
			)
		)
		(property "Description" "SMD Multilayer Ceramic Capacitor, 1 µF, 25 V, 0402 [1005 Metric], ± 10%, X5R, GRM Series"
			(at 0 0 90)
			(layer "B.Fab")
			(hide yes)
			(effects
				(font
					(size 1.27 1.27)
					(thickness 0.15)
				)
				(justify mirror)
			)
		)
		(property "MPN" "GRM155R61E105KE11J"
			(at 0 0 90)
			(unlocked yes)
			(layer "B.Fab")
			(hide yes)
			(effects
				(font
					(size 1 1)
					(thickness 0.15)
				)
				(justify mirror)
			)
		)
		(property "Manufacturer" "Murata"
			(at 0 0 90)
			(unlocked yes)
			(layer "B.Fab")
			(hide yes)
			(effects
				(font
					(size 1 1)
					(thickness 0.15)
				)
				(justify mirror)
			)
		)
		(property "License" "Apache-2.0"
			(at 0 0 90)
			(unlocked yes)
			(layer "B.Fab")
			(hide yes)
			(effects
				(font
					(size 1 1)
					(thickness 0.15)
				)
				(justify mirror)
			)
		)
		(property "Author" "Antmicro"
			(at 0 0 90)
			(unlocked yes)
			(layer "B.Fab")
			(hide yes)
			(effects
				(font
					(size 1 1)
					(thickness 0.15)
				)
				(justify mirror)
			)
		)
		(property "Val" "1u"
			(at 0 0 90)
			(unlocked yes)
			(layer "B.Fab")
			(hide yes)
			(effects
				(font
					(size 1 1)
					(thickness 0.15)
				)
				(justify mirror)
			)
		)
		(property "Voltage" "25V"
			(at 0 0 90)
			(unlocked yes)
			(layer "B.Fab")
			(hide yes)
			(effects
				(font
					(size 1 1)
					(thickness 0.15)
				)
				(justify mirror)
			)
		)
		(property "Dielectric" "X5R"
			(at 0 0 90)
			(unlocked yes)
			(layer "B.Fab")
			(hide yes)
			(effects
				(font
					(size 1 1)
					(thickness 0.15)
				)
				(justify mirror)
			)
		)
		(sheetname "/X710-AT2 power/")
		(sheetfile "x710-at2-power.kicad_sch")
		(attr smd)
		(fp_rect
			(start -0.925 0.47)
			(end 0.925 -0.47)
			(stroke
				(width 0.05)
				(type default)
			)
			(fill no)
			(layer "B.CrtYd")
		)
		(fp_line
			(start 0.504 -0.248)
			(end -0.494 -0.248)
			(stroke
				(width 0.15)
				(type solid)
			)
			(layer "B.Fab")
		)
		(fp_line
			(start -0.494 -0.248)
			(end -0.494 0.25)
			(stroke
				(width 0.15)
				(type solid)
			)
			(layer "B.Fab")
		)
		(fp_line
			(start 0.504 0.25)
			(end 0.504 -0.248)
			(stroke
				(width 0.15)
				(type solid)
			)
			(layer "B.Fab")
		)
		(fp_line
			(start -0.494 0.25)
			(end 0.504 0.25)
			(stroke
				(width 0.15)
				(type solid)
			)
			(layer "B.Fab")
		)
		(pad "1" smd roundrect
			(at -0.48 0 90)
			(size 0.59 0.64)
			(layers "B.Cu" "B.Mask" "B.Paste")
			(roundrect_rratio 0.25)
			(net 28 "GND")
			(pintype "passive")
		)
		(pad "2" smd roundrect
			(at 0.48 0 90)
			(size 0.59 0.64)
			(layers "B.Cu" "B.Mask" "B.Paste")
			(roundrect_rratio 0.25)
			(net 12 "XFI_VDD")
			(pintype "passive")
		)
	)
	(footprint "antmicro-footprints:C_0402_1005Metric"
		(layer "B.Cu")
		(at 73.75 86.75 90)
		(descr "Capacitor SMD 0402")
		(tags "capacitor SMD 0402")
		(property "Reference" "C47"
			(at -1.1 1.91 90)
			(layer "B.SilkS")
			(effects
				(font
					(size 0.7 0.7)
					(thickness 0.15)
				)
				(justify right top mirror)
			)
		)
		(property "Value" "C_100n_0402"
			(at -1.022927 -2.155213 90)
			(layer "B.Fab")
			(hide yes)
			(effects
				(font
					(size 0.7 0.7)
					(thickness 0.15)
				)
				(justify right top mirror)
			)
		)
		(property "Datasheet" "https://www.murata.com/products/productdetail?partno=GRM155R61H104KE14%23"
			(at 0 0 90)
			(layer "B.Fab")
			(hide yes)
			(effects
				(font
					(size 1.27 1.27)
					(thickness 0.15)
				)
				(justify mirror)
			)
		)
		(property "Description" "SMD Multilayer Ceramic Capacitor, 0.1 µF, 50 V, 0402 [1005 Metric], ± 10%, X5R, GRM Series"
			(at 0 0 90)
			(layer "B.Fab")
			(hide yes)
			(effects
				(font
					(size 1.27 1.27)
					(thickness 0.15)
				)
				(justify mirror)
			)
		)
		(property "MPN" "GRM155R61H104KE14D"
			(at 0 0 90)
			(unlocked yes)
			(layer "B.Fab")
			(hide yes)
			(effects
				(font
					(size 1 1)
					(thickness 0.15)
				)
				(justify mirror)
			)
		)
		(property "Val" "100n"
			(at 0 0 90)
			(unlocked yes)
			(layer "B.Fab")
			(hide yes)
			(effects
				(font
					(size 1 1)
					(thickness 0.15)
				)
				(justify mirror)
			)
		)
		(property "Voltage" "50V"
			(at 0 0 90)
			(unlocked yes)
			(layer "B.Fab")
			(hide yes)
			(effects
				(font
					(size 1 1)
					(thickness 0.15)
				)
				(justify mirror)
			)
		)
		(property "Dielectric" "X5R"
			(at 0 0 90)
			(unlocked yes)
			(layer "B.Fab")
			(hide yes)
			(effects
				(font
					(size 1 1)
					(thickness 0.15)
				)
				(justify mirror)
			)
		)
		(property "Manufacturer" "Murata"
			(at 0 0 90)
			(unlocked yes)
			(layer "B.Fab")
			(hide yes)
			(effects
				(font
					(size 1 1)
					(thickness 0.15)
				)
				(justify mirror)
			)
		)
		(property "License" "Apache-2.0"
			(at 0 0 90)
			(unlocked yes)
			(layer "B.Fab")
			(hide yes)
			(effects
				(font
					(size 1 1)
					(thickness 0.15)
				)
				(justify mirror)
			)
		)
		(property "Author" "Antmicro"
			(at 0 0 90)
			(unlocked yes)
			(layer "B.Fab")
			(hide yes)
			(effects
				(font
					(size 1 1)
					(thickness 0.15)
				)
				(justify mirror)
			)
		)
		(sheetname "/Flash memory/")
		(sheetfile "flash-memory.kicad_sch")
		(attr smd)
		(fp_rect
			(start -0.925 0.47)
			(end 0.925 -0.47)
			(stroke
				(width 0.05)
				(type default)
			)
			(fill no)
			(layer "B.CrtYd")
		)
		(fp_line
			(start 0.504 -0.248)
			(end -0.494 -0.248)
			(stroke
				(width 0.15)
				(type solid)
			)
			(layer "B.Fab")
		)
		(fp_line
			(start -0.494 -0.248)
			(end -0.494 0.25)
			(stroke
				(width 0.15)
				(type solid)
			)
			(layer "B.Fab")
		)
		(fp_line
			(start 0.504 0.25)
			(end 0.504 -0.248)
			(stroke
				(width 0.15)
				(type solid)
			)
			(layer "B.Fab")
		)
		(fp_line
			(start -0.494 0.25)
			(end 0.504 0.25)
			(stroke
				(width 0.15)
				(type solid)
			)
			(layer "B.Fab")
		)
		(pad "1" smd roundrect
			(at -0.48 0 90)
			(size 0.59 0.64)
			(layers "B.Cu" "B.Mask" "B.Paste")
			(roundrect_rratio 0.25)
			(net 28 "GND")
			(pintype "passive")
		)
		(pad "2" smd roundrect
			(at 0.48 0 90)
			(size 0.59 0.64)
			(layers "B.Cu" "B.Mask" "B.Paste")
			(roundrect_rratio 0.25)
			(net 110 "/Flash memory/+3V3_FLASH")
			(pintype "passive")
		)
	)
	(footprint "antmicro-footprints:C_0402_1005Metric"
		(layer "B.Cu")
		(at 60.670001 96.149997)
		(descr "Capacitor SMD 0402")
		(tags "capacitor SMD 0402")
		(property "Reference" "C46"
			(at -0.890001 0.560003 0)
			(layer "B.SilkS")
			(effects
				(font
					(size 0.7 0.7)
					(thickness 0.15)
				)
				(justify right top mirror)
			)
		)
		(property "Value" "C_100n_0402"
			(at -1.022927 -2.155213 0)
			(layer "B.Fab")
			(hide yes)
			(effects
				(font
					(size 0.7 0.7)
					(thickness 0.15)
				)
				(justify right top mirror)
			)
		)
		(property "Datasheet" "https://www.murata.com/products/productdetail?partno=GRM155R61H104KE14%23"
			(at 0 0 0)
			(layer "B.Fab")
			(hide yes)
			(effects
				(font
					(size 1.27 1.27)
					(thickness 0.15)
				)
				(justify mirror)
			)
		)
		(property "Description" "SMD Multilayer Ceramic Capacitor, 0.1 µF, 50 V, 0402 [1005 Metric], ± 10%, X5R, GRM Series"
			(at 0 0 0)
			(layer "B.Fab")
			(hide yes)
			(effects
				(font
					(size 1.27 1.27)
					(thickness 0.15)
				)
				(justify mirror)
			)
		)
		(property "MPN" "GRM155R61H104KE14D"
			(at 0 0 0)
			(unlocked yes)
			(layer "B.Fab")
			(hide yes)
			(effects
				(font
					(size 1 1)
					(thickness 0.15)
				)
				(justify mirror)
			)
		)
		(property "Manufacturer" "Murata"
			(at 0 0 0)
			(unlocked yes)
			(layer "B.Fab")
			(hide yes)
			(effects
				(font
					(size 1 1)
					(thickness 0.15)
				)
				(justify mirror)
			)
		)
		(property "License" "Apache-2.0"
			(at 0 0 0)
			(unlocked yes)
			(layer "B.Fab")
			(hide yes)
			(effects
				(font
					(size 1 1)
					(thickness 0.15)
				)
				(justify mirror)
			)
		)
		(property "Author" "Antmicro"
			(at 0 0 0)
			(unlocked yes)
			(layer "B.Fab")
			(hide yes)
			(effects
				(font
					(size 1 1)
					(thickness 0.15)
				)
				(justify mirror)
			)
		)
		(property "Val" "100n"
			(at 0 0 0)
			(unlocked yes)
			(layer "B.Fab")
			(hide yes)
			(effects
				(font
					(size 1 1)
					(thickness 0.15)
				)
				(justify mirror)
			)
		)
		(property "Voltage" "50V"
			(at 0 0 0)
			(unlocked yes)
			(layer "B.Fab")
			(hide yes)
			(effects
				(font
					(size 1 1)
					(thickness 0.15)
				)
				(justify mirror)
			)
		)
		(property "Dielectric" "X5R"
			(at 0 0 0)
			(unlocked yes)
			(layer "B.Fab")
			(hide yes)
			(effects
				(font
					(size 1 1)
					(thickness 0.15)
				)
				(justify mirror)
			)
		)
		(sheetname "/Power/")
		(sheetfile "power.kicad_sch")
		(attr smd)
		(fp_rect
			(start -0.925 0.47)
			(end 0.925 -0.47)
			(stroke
				(width 0.05)
				(type default)
			)
			(fill no)
			(layer "B.CrtYd")
		)
		(fp_line
			(start -0.494 -0.248)
			(end -0.494 0.25)
			(stroke
				(width 0.15)
				(type solid)
			)
			(layer "B.Fab")
		)
		(fp_line
			(start -0.494 0.25)
			(end 0.504 0.25)
			(stroke
				(width 0.15)
				(type solid)
			)
			(layer "B.Fab")
		)
		(fp_line
			(start 0.504 -0.248)
			(end -0.494 -0.248)
			(stroke
				(width 0.15)
				(type solid)
			)
			(layer "B.Fab")
		)
		(fp_line
			(start 0.504 0.25)
			(end 0.504 -0.248)
			(stroke
				(width 0.15)
				(type solid)
			)
			(layer "B.Fab")
		)
		(pad "1" smd roundrect
			(at -0.48 0)
			(size 0.59 0.64)
			(layers "B.Cu" "B.Mask" "B.Paste")
			(roundrect_rratio 0.25)
			(net 28 "GND")
			(pintype "passive")
		)
		(pad "2" smd roundrect
			(at 0.48 0)
			(size 0.59 0.64)
			(layers "B.Cu" "B.Mask" "B.Paste")
			(roundrect_rratio 0.25)
			(net 311 "/Power/+DVDD_OUT")
			(pintype "passive")
		)
	)
	(footprint "antmicro-footprints:R_0402_1005Metric"
		(layer "B.Cu")
		(at 74 96.65 180)
		(descr "Resistor SMD 0402")
		(tags "resistor SMD 0402")
		(property "Reference" "R97"
			(at 0.85 -0.45 0)
			(layer "B.SilkS")
			(effects
				(font
					(size 0.7 0.7)
					(thickness 0.15)
				)
				(justify left bottom mirror)
			)
		)
		(property "Value" "R_10k_0402"
			(at -1.011843 -1.772047 0)
			(layer "B.Fab")
			(hide yes)
			(effects
				(font
					(size 0.7 0.7)
					(thickness 0.15)
				)
				(justify left bottom mirror)
			)
		)
		(property "Datasheet" "https://www.bourns.com/docs/product-datasheets/cr.pdf"
			(at 0 0 0)
			(layer "B.Fab")
			(hide yes)
			(effects
				(font
					(size 1.27 1.27)
					(thickness 0.15)
				)
				(justify mirror)
			)
		)
		(property "Description" "SMD Chip Resistor, 10 kohm, ± 1%, 62.5 mW, 0402 [1005 Metric], Thick Film, General Purpose"
			(at 0 0 0)
			(layer "B.Fab")
			(hide yes)
			(effects
				(font
					(size 1.27 1.27)
					(thickness 0.15)
				)
				(justify mirror)
			)
		)
		(property "MPN" "CR0402-FX-1002GLF"
			(at 0 0 180)
			(unlocked yes)
			(layer "B.Fab")
			(hide yes)
			(effects
				(font
					(size 1 1)
					(thickness 0.15)
				)
				(justify mirror)
			)
		)
		(property "Manufacturer" "Bourns"
			(at 0 0 180)
			(unlocked yes)
			(layer "B.Fab")
			(hide yes)
			(effects
				(font
					(size 1 1)
					(thickness 0.15)
				)
				(justify mirror)
			)
		)
		(property "License" "Apache-2.0"
			(at 0 0 180)
			(unlocked yes)
			(layer "B.Fab")
			(hide yes)
			(effects
				(font
					(size 1 1)
					(thickness 0.15)
				)
				(justify mirror)
			)
		)
		(property "Author" "Antmicro"
			(at 0 0 180)
			(unlocked yes)
			(layer "B.Fab")
			(hide yes)
			(effects
				(font
					(size 1 1)
					(thickness 0.15)
				)
				(justify mirror)
			)
		)
		(property "Val" "10k"
			(at 0 0 180)
			(unlocked yes)
			(layer "B.Fab")
			(hide yes)
			(effects
				(font
					(size 1 1)
					(thickness 0.15)
				)
				(justify mirror)
			)
		)
		(property "Tolerance" "1%"
			(at 0 0 180)
			(unlocked yes)
			(layer "B.Fab")
			(hide yes)
			(effects
				(font
					(size 1 1)
					(thickness 0.15)
				)
				(justify mirror)
			)
		)
		(sheetname "/X710-AT2 Misc/")
		(sheetfile "x710-at2-mics.kicad_sch")
		(attr smd exclude_from_pos_files exclude_from_bom dnp)
		(fp_rect
			(start -0.925 0.47)
			(end 0.925 -0.47)
			(stroke
				(width 0.05)
				(type default)
			)
			(fill no)
			(layer "B.CrtYd")
		)
		(fp_rect
			(start -0.5 0.25)
			(end 0.5 -0.25)
			(stroke
				(width 0.15)
				(type solid)
			)
			(fill no)
			(layer "B.Fab")
		)
		(pad "1" smd roundrect
			(at -0.48 0 180)
			(size 0.59 0.64)
			(layers "B.Cu" "B.Mask" "B.Paste")
			(roundrect_rratio 0.25)
			(net 47 "/X710-AT2 Misc/POR_BYPASS")
			(pintype "passive")
		)
		(pad "2" smd roundrect
			(at 0.48 0 180)
			(size 0.59 0.64)
			(layers "B.Cu" "B.Mask" "B.Paste")
			(roundrect_rratio 0.25)
			(net 7 "+3V3")
			(pintype "passive")
		)
	)
	(footprint "antmicro-footprints:C_0402_1005Metric"
		(layer "B.Cu")
		(at 82.22 103.23 90)
		(descr "Capacitor SMD 0402")
		(tags "capacitor SMD 0402")
		(property "Reference" "C181"
			(at -11.62 -0.04 90)
			(layer "B.SilkS")
			(effects
				(font
					(size 0.7 0.7)
					(thickness 0.15)
				)
				(justify right top mirror)
			)
		)
		(property "Value" "C_1u_25V_0402"
			(at -1.022927 -2.155213 90)
			(layer "B.Fab")
			(hide yes)
			(effects
				(font
					(size 0.7 0.7)
					(thickness 0.15)
				)
				(justify right top mirror)
			)
		)
		(property "Datasheet" "https://www.murata.com/products/productdetail?partno=GRM155R61E105KE11%23"
			(at 0 0 90)
			(layer "B.Fab")
			(hide yes)
			(effects
				(font
					(size 1.27 1.27)
					(thickness 0.15)
				)
				(justify mirror)
			)
		)
		(property "Description" "SMD Multilayer Ceramic Capacitor, 1 µF, 25 V, 0402 [1005 Metric], ± 10%, X5R, GRM Series"
			(at 0 0 90)
			(layer "B.Fab")
			(hide yes)
			(effects
				(font
					(size 1.27 1.27)
					(thickness 0.15)
				)
				(justify mirror)
			)
		)
		(property "MPN" "GRM155R61E105KE11J"
			(at 0 0 90)
			(unlocked yes)
			(layer "B.Fab")
			(hide yes)
			(effects
				(font
					(size 1 1)
					(thickness 0.15)
				)
				(justify mirror)
			)
		)
		(property "Manufacturer" "Murata"
			(at 0 0 90)
			(unlocked yes)
			(layer "B.Fab")
			(hide yes)
			(effects
				(font
					(size 1 1)
					(thickness 0.15)
				)
				(justify mirror)
			)
		)
		(property "License" "Apache-2.0"
			(at 0 0 90)
			(unlocked yes)
			(layer "B.Fab")
			(hide yes)
			(effects
				(font
					(size 1 1)
					(thickness 0.15)
				)
				(justify mirror)
			)
		)
		(property "Author" "Antmicro"
			(at 0 0 90)
			(unlocked yes)
			(layer "B.Fab")
			(hide yes)
			(effects
				(font
					(size 1 1)
					(thickness 0.15)
				)
				(justify mirror)
			)
		)
		(property "Val" "1u"
			(at 0 0 90)
			(unlocked yes)
			(layer "B.Fab")
			(hide yes)
			(effects
				(font
					(size 1 1)
					(thickness 0.15)
				)
				(justify mirror)
			)
		)
		(property "Voltage" "25V"
			(at 0 0 90)
			(unlocked yes)
			(layer "B.Fab")
			(hide yes)
			(effects
				(font
					(size 1 1)
					(thickness 0.15)
				)
				(justify mirror)
			)
		)
		(property "Dielectric" "X5R"
			(at 0 0 90)
			(unlocked yes)
			(layer "B.Fab")
			(hide yes)
			(effects
				(font
					(size 1 1)
					(thickness 0.15)
				)
				(justify mirror)
			)
		)
		(sheetname "/X710-AT2 power/")
		(sheetfile "x710-at2-power.kicad_sch")
		(attr smd)
		(fp_rect
			(start -0.925 0.47)
			(end 0.925 -0.47)
			(stroke
				(width 0.05)
				(type default)
			)
			(fill no)
			(layer "B.CrtYd")
		)
		(fp_line
			(start 0.504 -0.248)
			(end -0.494 -0.248)
			(stroke
				(width 0.15)
				(type solid)
			)
			(layer "B.Fab")
		)
		(fp_line
			(start -0.494 -0.248)
			(end -0.494 0.25)
			(stroke
				(width 0.15)
				(type solid)
			)
			(layer "B.Fab")
		)
		(fp_line
			(start 0.504 0.25)
			(end 0.504 -0.248)
			(stroke
				(width 0.15)
				(type solid)
			)
			(layer "B.Fab")
		)
		(fp_line
			(start -0.494 0.25)
			(end 0.504 0.25)
			(stroke
				(width 0.15)
				(type solid)
			)
			(layer "B.Fab")
		)
		(pad "1" smd roundrect
			(at -0.48 0 90)
			(size 0.59 0.64)
			(layers "B.Cu" "B.Mask" "B.Paste")
			(roundrect_rratio 0.25)
			(net 28 "GND")
			(pintype "passive")
		)
		(pad "2" smd roundrect
			(at 0.48 0 90)
			(size 0.59 0.64)
			(layers "B.Cu" "B.Mask" "B.Paste")
			(roundrect_rratio 0.25)
			(net 12 "XFI_VDD")
			(pintype "passive")
		)
	)
	(footprint "antmicro-footprints:C_0402_1005Metric"
		(layer "B.Cu")
		(at 77.225 104.2 -90)
		(descr "Capacitor SMD 0402")
		(tags "capacitor SMD 0402")
		(property "Reference" "C104"
			(at 9 0.485 90)
			(layer "B.SilkS")
			(effects
				(font
					(size 0.7 0.7)
					(thickness 0.15)
				)
				(justify left bottom mirror)
			)
		)
		(property "Value" "C_1u_25V_0402"
			(at -1.022927 -2.155213 90)
			(layer "B.Fab")
			(hide yes)
			(effects
				(font
					(size 0.7 0.7)
					(thickness 0.15)
				)
				(justify left bottom mirror)
			)
		)
		(property "Datasheet" "https://www.murata.com/products/productdetail?partno=GRM155R61E105KE11%23"
			(at 0 0 90)
			(layer "B.Fab")
			(hide yes)
			(effects
				(font
					(size 1.27 1.27)
					(thickness 0.15)
				)
				(justify mirror)
			)
		)
		(property "Description" "SMD Multilayer Ceramic Capacitor, 1 µF, 25 V, 0402 [1005 Metric], ± 10%, X5R, GRM Series"
			(at 0 0 90)
			(layer "B.Fab")
			(hide yes)
			(effects
				(font
					(size 1.27 1.27)
					(thickness 0.15)
				)
				(justify mirror)
			)
		)
		(property "MPN" "GRM155R61E105KE11J"
			(at 0 0 270)
			(unlocked yes)
			(layer "B.Fab")
			(hide yes)
			(effects
				(font
					(size 1 1)
					(thickness 0.15)
				)
				(justify mirror)
			)
		)
		(property "Manufacturer" "Murata"
			(at 0 0 270)
			(unlocked yes)
			(layer "B.Fab")
			(hide yes)
			(effects
				(font
					(size 1 1)
					(thickness 0.15)
				)
				(justify mirror)
			)
		)
		(property "License" "Apache-2.0"
			(at 0 0 270)
			(unlocked yes)
			(layer "B.Fab")
			(hide yes)
			(effects
				(font
					(size 1 1)
					(thickness 0.15)
				)
				(justify mirror)
			)
		)
		(property "Author" "Antmicro"
			(at 0 0 270)
			(unlocked yes)
			(layer "B.Fab")
			(hide yes)
			(effects
				(font
					(size 1 1)
					(thickness 0.15)
				)
				(justify mirror)
			)
		)
		(property "Val" "1u"
			(at 0 0 270)
			(unlocked yes)
			(layer "B.Fab")
			(hide yes)
			(effects
				(font
					(size 1 1)
					(thickness 0.15)
				)
				(justify mirror)
			)
		)
		(property "Voltage" "25V"
			(at 0 0 270)
			(unlocked yes)
			(layer "B.Fab")
			(hide yes)
			(effects
				(font
					(size 1 1)
					(thickness 0.15)
				)
				(justify mirror)
			)
		)
		(property "Dielectric" "X5R"
			(at 0 0 270)
			(unlocked yes)
			(layer "B.Fab")
			(hide yes)
			(effects
				(font
					(size 1 1)
					(thickness 0.15)
				)
				(justify mirror)
			)
		)
		(sheetname "/X710-AT2 power/")
		(sheetfile "x710-at2-power.kicad_sch")
		(attr smd)
		(fp_rect
			(start -0.925 0.47)
			(end 0.925 -0.47)
			(stroke
				(width 0.05)
				(type default)
			)
			(fill no)
			(layer "B.CrtYd")
		)
		(fp_line
			(start -0.494 0.25)
			(end 0.504 0.25)
			(stroke
				(width 0.15)
				(type solid)
			)
			(layer "B.Fab")
		)
		(fp_line
			(start 0.504 0.25)
			(end 0.504 -0.248)
			(stroke
				(width 0.15)
				(type solid)
			)
			(layer "B.Fab")
		)
		(fp_line
			(start -0.494 -0.248)
			(end -0.494 0.25)
			(stroke
				(width 0.15)
				(type solid)
			)
			(layer "B.Fab")
		)
		(fp_line
			(start 0.504 -0.248)
			(end -0.494 -0.248)
			(stroke
				(width 0.15)
				(type solid)
			)
			(layer "B.Fab")
		)
		(pad "1" smd roundrect
			(at -0.48 0 270)
			(size 0.59 0.64)
			(layers "B.Cu" "B.Mask" "B.Paste")
			(roundrect_rratio 0.25)
			(net 28 "GND")
			(pintype "passive")
		)
		(pad "2" smd roundrect
			(at 0.48 0 270)
			(size 0.59 0.64)
			(layers "B.Cu" "B.Mask" "B.Paste")
			(roundrect_rratio 0.25)
			(net 18 "+1V88")
			(pintype "passive")
		)
	)
	(footprint "antmicro-footprints:R_0402_1005Metric"
		(layer "B.Cu")
		(at 84.225 94.6 90)
		(descr "Resistor SMD 0402")
		(tags "resistor SMD 0402")
		(property "Reference" "R135"
			(at 12.5 -0.462343 90)
			(layer "B.SilkS")
			(effects
				(font
					(size 0.7 0.7)
					(thickness 0.15)
				)
				(justify right top mirror)
			)
		)
		(property "Value" "R_100R_0402"
			(at -1.011843 -1.772046 90)
			(layer "B.Fab")
			(hide yes)
			(effects
				(font
					(size 0.7 0.7)
					(thickness 0.15)
				)
				(justify right top mirror)
			)
		)
		(property "Datasheet" "https://www.bourns.com/docs/product-datasheets/cr.pdf"
			(at 0 0 90)
			(layer "B.Fab")
			(hide yes)
			(effects
				(font
					(size 1.27 1.27)
					(thickness 0.15)
				)
				(justify mirror)
			)
		)
		(property "Description" "SMD Chip Resistor, 100 ohm, ± 1%, 62.5 mW, 0402 [1005 Metric], Thick Film, General Purpose"
			(at 0 0 90)
			(layer "B.Fab")
			(hide yes)
			(effects
				(font
					(size 1.27 1.27)
					(thickness 0.15)
				)
				(justify mirror)
			)
		)
		(property "MPN" "CR0402-FX-1000GLF"
			(at 0 0 90)
			(unlocked yes)
			(layer "B.Fab")
			(hide yes)
			(effects
				(font
					(size 1 1)
					(thickness 0.15)
				)
				(justify mirror)
			)
		)
		(property "Manufacturer" "Bourns"
			(at 0 0 90)
			(unlocked yes)
			(layer "B.Fab")
			(hide yes)
			(effects
				(font
					(size 1 1)
					(thickness 0.15)
				)
				(justify mirror)
			)
		)
		(property "License" "Apache-2.0"
			(at 0 0 90)
			(unlocked yes)
			(layer "B.Fab")
			(hide yes)
			(effects
				(font
					(size 1 1)
					(thickness 0.15)
				)
				(justify mirror)
			)
		)
		(property "Author" "Antmicro"
			(at 0 0 90)
			(unlocked yes)
			(layer "B.Fab")
			(hide yes)
			(effects
				(font
					(size 1 1)
					(thickness 0.15)
				)
				(justify mirror)
			)
		)
		(property "Val" "100R"
			(at 0 0 90)
			(unlocked yes)
			(layer "B.Fab")
			(hide yes)
			(effects
				(font
					(size 1 1)
					(thickness 0.15)
				)
				(justify mirror)
			)
		)
		(property "Tolerance" "1%"
			(at 0 0 90)
			(unlocked yes)
			(layer "B.Fab")
			(hide yes)
			(effects
				(font
					(size 1 1)
					(thickness 0.15)
				)
				(justify mirror)
			)
		)
		(sheetname "/X710-AT2 RSVD/")
		(sheetfile "x710-at2-rsvd.kicad_sch")
		(attr smd)
		(fp_rect
			(start -0.925 0.47)
			(end 0.925 -0.47)
			(stroke
				(width 0.05)
				(type default)
			)
			(fill no)
			(layer "B.CrtYd")
		)
		(fp_rect
			(start -0.5 0.25)
			(end 0.5 -0.25)
			(stroke
				(width 0.15)
				(type solid)
			)
			(fill no)
			(layer "B.Fab")
		)
		(pad "1" smd roundrect
			(at -0.48 0 90)
			(size 0.59 0.64)
			(layers "B.Cu" "B.Mask" "B.Paste")
			(roundrect_rratio 0.25)
			(net 28 "GND")
			(pintype "passive")
		)
		(pad "2" smd roundrect
			(at 0.48 0 90)
			(size 0.59 0.64)
			(layers "B.Cu" "B.Mask" "B.Paste")
			(roundrect_rratio 0.25)
			(net 123 "/X710-AT2 RSVD/RSVDY22_VSS")
			(pintype "passive")
		)
	)
	(footprint "antmicro-footprints:FB_0603_1608Metric"
		(layer "B.Cu")
		(at 85 127.8 -90)
		(property "Reference" "FB1"
			(at -1 -1.6 90)
			(layer "B.SilkS")
			(effects
				(font
					(size 0.7 0.7)
					(thickness 0.15)
				)
				(justify left bottom mirror)
			)
		)
		(property "Value" "FB_33Z_3A_Murata-BLM18PG_0603"
			(at 0 -1.5 90)
			(layer "B.Fab")
			(hide yes)
			(effects
				(font
					(size 0.7 0.7)
					(thickness 0.15)
				)
				(justify left bottom mirror)
			)
		)
		(property "Datasheet" "https://www.murata.com/products/productdata/8796737273886/QNFA9101.pdf?1649080818000"
			(at 0 0 90)
			(layer "B.Fab")
			(hide yes)
			(effects
				(font
					(size 1.27 1.27)
					(thickness 0.15)
				)
				(justify mirror)
			)
		)
		(property "Description" "Ferrite Bead, 0603 [1608 Metric], 33 ohm, 3 A, BLM18PG, 0.025 ohm, ± 25%, DC power line"
			(at 0 0 90)
			(layer "B.Fab")
			(hide yes)
			(effects
				(font
					(size 1.27 1.27)
					(thickness 0.15)
				)
				(justify mirror)
			)
		)
		(property "Val" "33Z/3A"
			(at 0 0 270)
			(unlocked yes)
			(layer "B.Fab")
			(hide yes)
			(effects
				(font
					(size 1 1)
					(thickness 0.15)
				)
				(justify mirror)
			)
		)
		(property "MPN" "BLM18PG330SH1D"
			(at 0 0 270)
			(unlocked yes)
			(layer "B.Fab")
			(hide yes)
			(effects
				(font
					(size 1 1)
					(thickness 0.15)
				)
				(justify mirror)
			)
		)
		(property "Manufacturer" "Murata"
			(at 0 0 270)
			(unlocked yes)
			(layer "B.Fab")
			(hide yes)
			(effects
				(font
					(size 1 1)
					(thickness 0.15)
				)
				(justify mirror)
			)
		)
		(property "Current" ""
			(at 0 0 270)
			(unlocked yes)
			(layer "B.Fab")
			(hide yes)
			(effects
				(font
					(size 1 1)
					(thickness 0.15)
				)
				(justify mirror)
			)
		)
		(property "Author" "Antmicro"
			(at 0 0 270)
			(unlocked yes)
			(layer "B.Fab")
			(hide yes)
			(effects
				(font
					(size 1 1)
					(thickness 0.15)
				)
				(justify mirror)
			)
		)
		(property "License" "Apache-2.0"
			(at 0 0 270)
			(unlocked yes)
			(layer "B.Fab")
			(hide yes)
			(effects
				(font
					(size 1 1)
					(thickness 0.15)
				)
				(justify mirror)
			)
		)
		(sheetname "/2xRJ45/")
		(sheetfile "2xrj45.kicad_sch")
		(attr smd)
		(fp_line
			(start -0.15 0.4)
			(end 0.15 0.4)
			(stroke
				(width 0.15)
				(type solid)
			)
			(layer "B.SilkS")
		)
		(fp_line
			(start -0.15 -0.4)
			(end 0.15 -0.4)
			(stroke
				(width 0.15)
				(type solid)
			)
			(layer "B.SilkS")
		)
		(fp_rect
			(start -1.25 0.65)
			(end 1.25 -0.65)
			(stroke
				(width 0.05)
				(type solid)
			)
			(fill no)
			(layer "B.CrtYd")
		)
		(fp_line
			(start 0.8 0.408)
			(end -0.803 0.408)
			(stroke
				(width 0.15)
				(type solid)
			)
			(layer "B.Fab")
		)
		(fp_line
			(start 0.8 0.408)
			(end 0.8 -0.406)
			(stroke
				(width 0.15)
				(type solid)
			)
			(layer "B.Fab")
		)
		(fp_line
			(start -0.803 -0.406)
			(end -0.803 0.408)
			(stroke
				(width 0.15)
				(type solid)
			)
			(layer "B.Fab")
		)
		(fp_line
			(start 0.8 -0.406)
			(end -0.803 -0.406)
			(stroke
				(width 0.15)
				(type solid)
			)
			(layer "B.Fab")
		)
		(pad "1" smd roundrect
			(at -0.7 0 270)
			(size 0.8 1)
			(layers "B.Cu" "B.Mask" "B.Paste")
			(roundrect_rratio 0.2)
			(net 18 "+1V88")
			(pintype "passive")
		)
		(pad "2" smd roundrect
			(at 0.7 0 270)
			(size 0.8 1)
			(layers "B.Cu" "B.Mask" "B.Paste")
			(roundrect_rratio 0.2)
			(net 301 "+1V88_CT")
			(pintype "passive")
		)
	)
	(footprint "antmicro-footprints:R_0402_1005Metric"
		(layer "B.Cu")
		(at 107.2 68.15 -90)
		(descr "Resistor SMD 0402")
		(tags "resistor SMD 0402")
		(property "Reference" "R163"
			(at -3.64 -0.44 90)
			(layer "B.SilkS")
			(effects
				(font
					(size 0.7 0.7)
					(thickness 0.15)
				)
				(justify left bottom mirror)
			)
		)
		(property "Value" "R_0R_0402"
			(at -1.011843 -1.772046 90)
			(layer "B.Fab")
			(hide yes)
			(effects
				(font
					(size 0.7 0.7)
					(thickness 0.15)
				)
				(justify left bottom mirror)
			)
		)
		(property "Datasheet" "https://industrial.panasonic.com/cdbs/www-data/pdf/RDA0000/AOA0000C301.pdf"
			(at 0 0 90)
			(layer "B.Fab")
			(hide yes)
			(effects
				(font
					(size 1.27 1.27)
					(thickness 0.15)
				)
				(justify mirror)
			)
		)
		(property "Description" "SMD Chip Resistor, Jumper, 0 ohm, 100 mW, 0402 [1005 Metric], Thick Film, General Purpose"
			(at 0 0 90)
			(layer "B.Fab")
			(hide yes)
			(effects
				(font
					(size 1.27 1.27)
					(thickness 0.15)
				)
				(justify mirror)
			)
		)
		(property "MPN" "ERJ2GE0R00X"
			(at 0 0 270)
			(unlocked yes)
			(layer "B.Fab")
			(hide yes)
			(effects
				(font
					(size 1 1)
					(thickness 0.15)
				)
				(justify mirror)
			)
		)
		(property "Manufacturer" "Panasonic"
			(at 0 0 270)
			(unlocked yes)
			(layer "B.Fab")
			(hide yes)
			(effects
				(font
					(size 1 1)
					(thickness 0.15)
				)
				(justify mirror)
			)
		)
		(property "License" "Apache-2.0"
			(at 0 0 270)
			(unlocked yes)
			(layer "B.Fab")
			(hide yes)
			(effects
				(font
					(size 1 1)
					(thickness 0.15)
				)
				(justify mirror)
			)
		)
		(property "Author" "Antmicro"
			(at 0 0 270)
			(unlocked yes)
			(layer "B.Fab")
			(hide yes)
			(effects
				(font
					(size 1 1)
					(thickness 0.15)
				)
				(justify mirror)
			)
		)
		(property "Val" "0R"
			(at 0 0 270)
			(unlocked yes)
			(layer "B.Fab")
			(hide yes)
			(effects
				(font
					(size 1 1)
					(thickness 0.15)
				)
				(justify mirror)
			)
		)
		(property "Tolerance" "~"
			(at 0 0 270)
			(unlocked yes)
			(layer "B.Fab")
			(hide yes)
			(effects
				(font
					(size 1 1)
					(thickness 0.15)
				)
				(justify mirror)
			)
		)
		(property "Current" "1A"
			(at 0 0 270)
			(unlocked yes)
			(layer "B.Fab")
			(hide yes)
			(effects
				(font
					(size 1 1)
					(thickness 0.15)
				)
				(justify mirror)
			)
		)
		(sheetname "/OCuLink/")
		(sheetfile "oculink.kicad_sch")
		(attr smd)
		(fp_rect
			(start -0.925 0.47)
			(end 0.925 -0.47)
			(stroke
				(width 0.05)
				(type default)
			)
			(fill no)
			(layer "B.CrtYd")
		)
		(fp_rect
			(start -0.5 0.25)
			(end 0.5 -0.25)
			(stroke
				(width 0.15)
				(type solid)
			)
			(fill no)
			(layer "B.Fab")
		)
		(pad "1" smd roundrect
			(at -0.48 0 270)
			(size 0.59 0.64)
			(layers "B.Cu" "B.Mask" "B.Paste")
			(roundrect_rratio 0.25)
			(net 226 "/OCuLink/SDA")
			(pintype "passive")
		)
		(pad "2" smd roundrect
			(at 0.48 0 270)
			(size 0.59 0.64)
			(layers "B.Cu" "B.Mask" "B.Paste")
			(roundrect_rratio 0.25)
			(net 395 "/OCuLink/SMBus.SDA")
			(pintype "passive")
		)
	)
	(footprint "antmicro-footprints:R_0402_1005Metric"
		(layer "B.Cu")
		(at 76.03 106.48)
		(descr "Resistor SMD 0402")
		(tags "resistor SMD 0402")
		(property "Reference" "R58"
			(at -2.72 0.72 0)
			(layer "B.SilkS")
			(effects
				(font
					(size 0.7 0.7)
					(thickness 0.15)
				)
				(justify right top mirror)
			)
		)
		(property "Value" "R_6k04_0.1%_0402"
			(at -1.011843 -1.772046 0)
			(layer "B.Fab")
			(hide yes)
			(effects
				(font
					(size 0.7 0.7)
					(thickness 0.15)
				)
				(justify right top mirror)
			)
		)
		(property "Datasheet" "https://www.vishay.com/docs/28758/tnpw_e3.pdf"
			(at 0 0 0)
			(layer "B.Fab")
			(hide yes)
			(effects
				(font
					(size 1.27 1.27)
					(thickness 0.15)
				)
				(justify mirror)
			)
		)
		(property "Description" "SMD Chip Resistor, 6.49 kohm, ± 1%, 62.5 mW, 0402 [1005 Metric], Thick Film, General Purpose"
			(at 0 0 0)
			(layer "B.Fab")
			(hide yes)
			(effects
				(font
					(size 1.27 1.27)
					(thickness 0.15)
				)
				(justify mirror)
			)
		)
		(property "MPN" "TNPW04026K04BEED"
			(at 0 0 0)
			(unlocked yes)
			(layer "B.Fab")
			(hide yes)
			(effects
				(font
					(size 1 1)
					(thickness 0.15)
				)
				(justify mirror)
			)
		)
		(property "Manufacturer" "Vishay"
			(at 0 0 0)
			(unlocked yes)
			(layer "B.Fab")
			(hide yes)
			(effects
				(font
					(size 1 1)
					(thickness 0.15)
				)
				(justify mirror)
			)
		)
		(property "License" "Apache-2.0"
			(at 0 0 0)
			(unlocked yes)
			(layer "B.Fab")
			(hide yes)
			(effects
				(font
					(size 1 1)
					(thickness 0.15)
				)
				(justify mirror)
			)
		)
		(property "Author" "Antmicro"
			(at 0 0 0)
			(unlocked yes)
			(layer "B.Fab")
			(hide yes)
			(effects
				(font
					(size 1 1)
					(thickness 0.15)
				)
				(justify mirror)
			)
		)
		(property "Val" "6k04"
			(at 0 0 0)
			(unlocked yes)
			(layer "B.Fab")
			(hide yes)
			(effects
				(font
					(size 1 1)
					(thickness 0.15)
				)
				(justify mirror)
			)
		)
		(property "Tolerance" "0.1%"
			(at 0 0 0)
			(unlocked yes)
			(layer "B.Fab")
			(hide yes)
			(effects
				(font
					(size 1 1)
					(thickness 0.15)
				)
				(justify mirror)
			)
		)
		(sheetname "/X710-AT2 10GbE/")
		(sheetfile "x710-at2-10gbe.kicad_sch")
		(attr smd)
		(fp_rect
			(start -0.925 0.47)
			(end 0.925 -0.47)
			(stroke
				(width 0.05)
				(type default)
			)
			(fill no)
			(layer "B.CrtYd")
		)
		(fp_rect
			(start -0.5 0.25)
			(end 0.5 -0.25)
			(stroke
				(width 0.15)
				(type solid)
			)
			(fill no)
			(layer "B.Fab")
		)
		(pad "1" smd roundrect
			(at -0.48 0)
			(size 0.59 0.64)
			(layers "B.Cu" "B.Mask" "B.Paste")
			(roundrect_rratio 0.25)
			(net 28 "GND")
			(pintype "passive")
		)
		(pad "2" smd roundrect
			(at 0.48 0)
			(size 0.59 0.64)
			(layers "B.Cu" "B.Mask" "B.Paste")
			(roundrect_rratio 0.25)
			(net 84 "/X710-AT2 10GbE/BIAS_RDAC")
			(pintype "passive")
		)
	)
	(footprint "antmicro-footprints:R_0402_1005Metric"
		(layer "B.Cu")
		(at 96.48 145.34 90)
		(descr "Resistor SMD 0402")
		(tags "resistor SMD 0402")
		(property "Reference" "R40"
			(at 0.75 -0.35 90)
			(layer "B.SilkS")
			(effects
				(font
					(size 0.7 0.7)
					(thickness 0.15)
				)
				(justify right top mirror)
			)
		)
		(property "Value" "R_220R_0402"
			(at -1.011843 -1.772046 90)
			(layer "B.Fab")
			(hide yes)
			(effects
				(font
					(size 0.7 0.7)
					(thickness 0.15)
				)
				(justify right top mirror)
			)
		)
		(property "Datasheet" "https://www.bourns.com/docs/product-datasheets/cr.pdf"
			(at 0 0 90)
			(layer "B.Fab")
			(hide yes)
			(effects
				(font
					(size 1.27 1.27)
					(thickness 0.15)
				)
				(justify mirror)
			)
		)
		(property "Description" "SMD Chip Resistor, 220 ohm, ± 1%, 62.5 mW, 0402 [1005 Metric], Thick Film, General Purpose"
			(at 0 0 90)
			(layer "B.Fab")
			(hide yes)
			(effects
				(font
					(size 1.27 1.27)
					(thickness 0.15)
				)
				(justify mirror)
			)
		)
		(property "MPN" "CR0402-FX-2200GLF"
			(at 0 0 90)
			(unlocked yes)
			(layer "B.Fab")
			(hide yes)
			(effects
				(font
					(size 1 1)
					(thickness 0.15)
				)
				(justify mirror)
			)
		)
		(property "Manufacturer" "Bourns"
			(at 0 0 90)
			(unlocked yes)
			(layer "B.Fab")
			(hide yes)
			(effects
				(font
					(size 1 1)
					(thickness 0.15)
				)
				(justify mirror)
			)
		)
		(property "License" "Apache-2.0"
			(at 0 0 90)
			(unlocked yes)
			(layer "B.Fab")
			(hide yes)
			(effects
				(font
					(size 1 1)
					(thickness 0.15)
				)
				(justify mirror)
			)
		)
		(property "Author" "Antmicro"
			(at 0 0 90)
			(unlocked yes)
			(layer "B.Fab")
			(hide yes)
			(effects
				(font
					(size 1 1)
					(thickness 0.15)
				)
				(justify mirror)
			)
		)
		(property "Val" "220R"
			(at 0 0 90)
			(unlocked yes)
			(layer "B.Fab")
			(hide yes)
			(effects
				(font
					(size 1 1)
					(thickness 0.15)
				)
				(justify mirror)
			)
		)
		(property "Tolerance" "1%"
			(at 0 0 90)
			(unlocked yes)
			(layer "B.Fab")
			(hide yes)
			(effects
				(font
					(size 1 1)
					(thickness 0.15)
				)
				(justify mirror)
			)
		)
		(sheetname "/2xRJ45/")
		(sheetfile "2xrj45.kicad_sch")
		(attr smd)
		(fp_rect
			(start -0.925 0.47)
			(end 0.925 -0.47)
			(stroke
				(width 0.05)
				(type default)
			)
			(fill no)
			(layer "B.CrtYd")
		)
		(fp_rect
			(start -0.5 0.25)
			(end 0.5 -0.25)
			(stroke
				(width 0.15)
				(type solid)
			)
			(fill no)
			(layer "B.Fab")
		)
		(pad "1" smd roundrect
			(at -0.48 0 90)
			(size 0.59 0.64)
			(layers "B.Cu" "B.Mask" "B.Paste")
			(roundrect_rratio 0.25)
			(net 64 "Net-(J6-LED_YG_G-)")
			(pintype "passive")
		)
		(pad "2" smd roundrect
			(at 0.48 0 90)
			(size 0.59 0.64)
			(layers "B.Cu" "B.Mask" "B.Paste")
			(roundrect_rratio 0.25)
			(net 87 "/2xRJ45/~{P1_LED_LINK_10G}")
			(pintype "passive")
		)
	)
	(footprint "antmicro-footprints:C_0402_1005Metric"
		(layer "B.Cu")
		(at 78.88 106.48 180)
		(descr "Capacitor SMD 0402")
		(tags "capacitor SMD 0402")
		(property "Reference" "C141"
			(at -1.52 -11.29 0)
			(layer "B.SilkS")
			(effects
				(font
					(size 0.7 0.7)
					(thickness 0.15)
				)
				(justify left bottom mirror)
			)
		)
		(property "Value" "C_1u_25V_0402"
			(at -1.022927 -2.155213 0)
			(layer "B.Fab")
			(hide yes)
			(effects
				(font
					(size 0.7 0.7)
					(thickness 0.15)
				)
				(justify left bottom mirror)
			)
		)
		(property "Datasheet" "https://www.murata.com/products/productdetail?partno=GRM155R61E105KE11%23"
			(at 0 0 0)
			(layer "B.Fab")
			(hide yes)
			(effects
				(font
					(size 1.27 1.27)
					(thickness 0.15)
				)
				(justify mirror)
			)
		)
		(property "Description" "SMD Multilayer Ceramic Capacitor, 1 µF, 25 V, 0402 [1005 Metric], ± 10%, X5R, GRM Series"
			(at 0 0 0)
			(layer "B.Fab")
			(hide yes)
			(effects
				(font
					(size 1.27 1.27)
					(thickness 0.15)
				)
				(justify mirror)
			)
		)
		(property "MPN" "GRM155R61E105KE11J"
			(at 0 0 180)
			(unlocked yes)
			(layer "B.Fab")
			(hide yes)
			(effects
				(font
					(size 1 1)
					(thickness 0.15)
				)
				(justify mirror)
			)
		)
		(property "Manufacturer" "Murata"
			(at 0 0 180)
			(unlocked yes)
			(layer "B.Fab")
			(hide yes)
			(effects
				(font
					(size 1 1)
					(thickness 0.15)
				)
				(justify mirror)
			)
		)
		(property "License" "Apache-2.0"
			(at 0 0 180)
			(unlocked yes)
			(layer "B.Fab")
			(hide yes)
			(effects
				(font
					(size 1 1)
					(thickness 0.15)
				)
				(justify mirror)
			)
		)
		(property "Author" "Antmicro"
			(at 0 0 180)
			(unlocked yes)
			(layer "B.Fab")
			(hide yes)
			(effects
				(font
					(size 1 1)
					(thickness 0.15)
				)
				(justify mirror)
			)
		)
		(property "Val" "1u"
			(at 0 0 180)
			(unlocked yes)
			(layer "B.Fab")
			(hide yes)
			(effects
				(font
					(size 1 1)
					(thickness 0.15)
				)
				(justify mirror)
			)
		)
		(property "Voltage" "25V"
			(at 0 0 180)
			(unlocked yes)
			(layer "B.Fab")
			(hide yes)
			(effects
				(font
					(size 1 1)
					(thickness 0.15)
				)
				(justify mirror)
			)
		)
		(property "Dielectric" "X5R"
			(at 0 0 180)
			(unlocked yes)
			(layer "B.Fab")
			(hide yes)
			(effects
				(font
					(size 1 1)
					(thickness 0.15)
				)
				(justify mirror)
			)
		)
		(sheetname "/X710-AT2 power/")
		(sheetfile "x710-at2-power.kicad_sch")
		(attr smd)
		(fp_rect
			(start -0.925 0.47)
			(end 0.925 -0.47)
			(stroke
				(width 0.05)
				(type default)
			)
			(fill no)
			(layer "B.CrtYd")
		)
		(fp_line
			(start 0.504 0.25)
			(end 0.504 -0.248)
			(stroke
				(width 0.15)
				(type solid)
			)
			(layer "B.Fab")
		)
		(fp_line
			(start 0.504 -0.248)
			(end -0.494 -0.248)
			(stroke
				(width 0.15)
				(type solid)
			)
			(layer "B.Fab")
		)
		(fp_line
			(start -0.494 0.25)
			(end 0.504 0.25)
			(stroke
				(width 0.15)
				(type solid)
			)
			(layer "B.Fab")
		)
		(fp_line
			(start -0.494 -0.248)
			(end -0.494 0.25)
			(stroke
				(width 0.15)
				(type solid)
			)
			(layer "B.Fab")
		)
		(pad "1" smd roundrect
			(at -0.48 0 180)
			(size 0.59 0.64)
			(layers "B.Cu" "B.Mask" "B.Paste")
			(roundrect_rratio 0.25)
			(net 28 "GND")
			(pintype "passive")
		)
		(pad "2" smd roundrect
			(at 0.48 0 180)
			(size 0.59 0.64)
			(layers "B.Cu" "B.Mask" "B.Paste")
			(roundrect_rratio 0.25)
			(net 10 "AVDDH")
			(pintype "passive")
		)
	)
	(footprint "antmicro-footprints:R_0402_1005Metric"
		(layer "B.Cu")
		(at 93.225 94 -90)
		(descr "Resistor SMD 0402")
		(tags "resistor SMD 0402")
		(property "Reference" "R136"
			(at -1.38 -0.575 90)
			(layer "B.SilkS")
			(effects
				(font
					(size 0.7 0.7)
					(thickness 0.15)
				)
				(justify left top mirror)
			)
		)
		(property "Value" "R_100R_0402"
			(at -1.011843 -1.772046 90)
			(layer "B.Fab")
			(hide yes)
			(effects
				(font
					(size 0.7 0.7)
					(thickness 0.15)
				)
				(justify left bottom mirror)
			)
		)
		(property "Datasheet" "https://www.bourns.com/docs/product-datasheets/cr.pdf"
			(at 0 0 90)
			(layer "B.Fab")
			(hide yes)
			(effects
				(font
					(size 1.27 1.27)
					(thickness 0.15)
				)
				(justify mirror)
			)
		)
		(property "Description" "SMD Chip Resistor, 100 ohm, ± 1%, 62.5 mW, 0402 [1005 Metric], Thick Film, General Purpose"
			(at 0 0 90)
			(layer "B.Fab")
			(hide yes)
			(effects
				(font
					(size 1.27 1.27)
					(thickness 0.15)
				)
				(justify mirror)
			)
		)
		(property "MPN" "CR0402-FX-1000GLF"
			(at 0 0 270)
			(unlocked yes)
			(layer "B.Fab")
			(hide yes)
			(effects
				(font
					(size 1 1)
					(thickness 0.15)
				)
				(justify mirror)
			)
		)
		(property "Manufacturer" "Bourns"
			(at 0 0 270)
			(unlocked yes)
			(layer "B.Fab")
			(hide yes)
			(effects
				(font
					(size 1 1)
					(thickness 0.15)
				)
				(justify mirror)
			)
		)
		(property "License" "Apache-2.0"
			(at 0 0 270)
			(unlocked yes)
			(layer "B.Fab")
			(hide yes)
			(effects
				(font
					(size 1 1)
					(thickness 0.15)
				)
				(justify mirror)
			)
		)
		(property "Author" "Antmicro"
			(at 0 0 270)
			(unlocked yes)
			(layer "B.Fab")
			(hide yes)
			(effects
				(font
					(size 1 1)
					(thickness 0.15)
				)
				(justify mirror)
			)
		)
		(property "Val" "100R"
			(at 0 0 270)
			(unlocked yes)
			(layer "B.Fab")
			(hide yes)
			(effects
				(font
					(size 1 1)
					(thickness 0.15)
				)
				(justify mirror)
			)
		)
		(property "Tolerance" "1%"
			(at 0 0 270)
			(unlocked yes)
			(layer "B.Fab")
			(hide yes)
			(effects
				(font
					(size 1 1)
					(thickness 0.15)
				)
				(justify mirror)
			)
		)
		(sheetname "/X710-AT2 RSVD/")
		(sheetfile "x710-at2-rsvd.kicad_sch")
		(attr smd)
		(fp_rect
			(start -0.925 0.47)
			(end 0.925 -0.47)
			(stroke
				(width 0.05)
				(type default)
			)
			(fill no)
			(layer "B.CrtYd")
		)
		(fp_rect
			(start -0.5 0.25)
			(end 0.5 -0.25)
			(stroke
				(width 0.15)
				(type solid)
			)
			(fill no)
			(layer "B.Fab")
		)
		(pad "1" smd roundrect
			(at -0.48 0 270)
			(size 0.59 0.64)
			(layers "B.Cu" "B.Mask" "B.Paste")
			(roundrect_rratio 0.25)
			(net 28 "GND")
			(pintype "passive")
		)
		(pad "2" smd roundrect
			(at 0.48 0 270)
			(size 0.59 0.64)
			(layers "B.Cu" "B.Mask" "B.Paste")
			(roundrect_rratio 0.25)
			(net 124 "/X710-AT2 RSVD/RSVDW5_VSS")
			(pintype "passive")
		)
	)
	(footprint "antmicro-footprints:C_0402_1005Metric"
		(layer "B.Cu")
		(at 106.635 92.32 90)
		(descr "Capacitor SMD 0402")
		(tags "capacitor SMD 0402")
		(property "Reference" "C76"
			(at -0.85 0.585 90)
			(layer "B.SilkS")
			(effects
				(font
					(size 0.7 0.7)
					(thickness 0.15)
				)
				(justify right top mirror)
			)
		)
		(property "Value" "C_100n_0402"
			(at -1.022927 -2.155213 90)
			(layer "B.Fab")
			(hide yes)
			(effects
				(font
					(size 0.7 0.7)
					(thickness 0.15)
				)
				(justify right top mirror)
			)
		)
		(property "Datasheet" "https://www.murata.com/products/productdetail?partno=GRM155R61H104KE14%23"
			(at 0 0 90)
			(layer "B.Fab")
			(hide yes)
			(effects
				(font
					(size 1.27 1.27)
					(thickness 0.15)
				)
				(justify mirror)
			)
		)
		(property "Description" "SMD Multilayer Ceramic Capacitor, 0.1 µF, 50 V, 0402 [1005 Metric], ± 10%, X5R, GRM Series"
			(at 0 0 90)
			(layer "B.Fab")
			(hide yes)
			(effects
				(font
					(size 1.27 1.27)
					(thickness 0.15)
				)
				(justify mirror)
			)
		)
		(property "MPN" "GRM155R61H104KE14D"
			(at 0 0 90)
			(unlocked yes)
			(layer "B.Fab")
			(hide yes)
			(effects
				(font
					(size 1 1)
					(thickness 0.15)
				)
				(justify mirror)
			)
		)
		(property "Val" "100n"
			(at 0 0 90)
			(unlocked yes)
			(layer "B.Fab")
			(hide yes)
			(effects
				(font
					(size 1 1)
					(thickness 0.15)
				)
				(justify mirror)
			)
		)
		(property "Voltage" "50V"
			(at 0 0 90)
			(unlocked yes)
			(layer "B.Fab")
			(hide yes)
			(effects
				(font
					(size 1 1)
					(thickness 0.15)
				)
				(justify mirror)
			)
		)
		(property "Dielectric" "X5R"
			(at 0 0 90)
			(unlocked yes)
			(layer "B.Fab")
			(hide yes)
			(effects
				(font
					(size 1 1)
					(thickness 0.15)
				)
				(justify mirror)
			)
		)
		(property "Manufacturer" "Murata"
			(at 0 0 90)
			(unlocked yes)
			(layer "B.Fab")
			(hide yes)
			(effects
				(font
					(size 1 1)
					(thickness 0.15)
				)
				(justify mirror)
			)
		)
		(property "License" "Apache-2.0"
			(at 0 0 90)
			(unlocked yes)
			(layer "B.Fab")
			(hide yes)
			(effects
				(font
					(size 1 1)
					(thickness 0.15)
				)
				(justify mirror)
			)
		)
		(property "Author" "Antmicro"
			(at 0 0 90)
			(unlocked yes)
			(layer "B.Fab")
			(hide yes)
			(effects
				(font
					(size 1 1)
					(thickness 0.15)
				)
				(justify mirror)
			)
		)
		(sheetname "/X710-AT2 Misc/")
		(sheetfile "x710-at2-mics.kicad_sch")
		(attr smd)
		(fp_rect
			(start -0.925 0.47)
			(end 0.925 -0.47)
			(stroke
				(width 0.05)
				(type default)
			)
			(fill no)
			(layer "B.CrtYd")
		)
		(fp_line
			(start 0.504 -0.248)
			(end -0.494 -0.248)
			(stroke
				(width 0.15)
				(type solid)
			)
			(layer "B.Fab")
		)
		(fp_line
			(start -0.494 -0.248)
			(end -0.494 0.25)
			(stroke
				(width 0.15)
				(type solid)
			)
			(layer "B.Fab")
		)
		(fp_line
			(start 0.504 0.25)
			(end 0.504 -0.248)
			(stroke
				(width 0.15)
				(type solid)
			)
			(layer "B.Fab")
		)
		(fp_line
			(start -0.494 0.25)
			(end 0.504 0.25)
			(stroke
				(width 0.15)
				(type solid)
			)
			(layer "B.Fab")
		)
		(pad "1" smd roundrect
			(at -0.48 0 90)
			(size 0.59 0.64)
			(layers "B.Cu" "B.Mask" "B.Paste")
			(roundrect_rratio 0.25)
			(net 28 "GND")
			(pintype "passive")
		)
		(pad "2" smd roundrect
			(at 0.48 0 90)
			(size 0.59 0.64)
			(layers "B.Cu" "B.Mask" "B.Paste")
			(roundrect_rratio 0.25)
			(net 18 "+1V88")
			(pintype "passive")
		)
	)
	(footprint "antmicro-footprints:C_0402_1005Metric"
		(layer "B.Cu")
		(at 85.8 108.35 180)
		(descr "Capacitor SMD 0402")
		(tags "capacitor SMD 0402")
		(property "Reference" "C176"
			(at -1.72 -1.3 0)
			(layer "B.SilkS")
			(effects
				(font
					(size 0.7 0.7)
					(thickness 0.15)
				)
				(justify left bottom mirror)
			)
		)
		(property "Value" "C_1u_25V_0402"
			(at -1.022927 -2.155213 0)
			(layer "B.Fab")
			(hide yes)
			(effects
				(font
					(size 0.7 0.7)
					(thickness 0.15)
				)
				(justify left bottom mirror)
			)
		)
		(property "Datasheet" "https://www.murata.com/products/productdetail?partno=GRM155R61E105KE11%23"
			(at 0 0 0)
			(layer "B.Fab")
			(hide yes)
			(effects
				(font
					(size 1.27 1.27)
					(thickness 0.15)
				)
				(justify mirror)
			)
		)
		(property "Description" "SMD Multilayer Ceramic Capacitor, 1 µF, 25 V, 0402 [1005 Metric], ± 10%, X5R, GRM Series"
			(at 0 0 0)
			(layer "B.Fab")
			(hide yes)
			(effects
				(font
					(size 1.27 1.27)
					(thickness 0.15)
				)
				(justify mirror)
			)
		)
		(property "MPN" "GRM155R61E105KE11J"
			(at 0 0 180)
			(unlocked yes)
			(layer "B.Fab")
			(hide yes)
			(effects
				(font
					(size 1 1)
					(thickness 0.15)
				)
				(justify mirror)
			)
		)
		(property "Manufacturer" "Murata"
			(at 0 0 180)
			(unlocked yes)
			(layer "B.Fab")
			(hide yes)
			(effects
				(font
					(size 1 1)
					(thickness 0.15)
				)
				(justify mirror)
			)
		)
		(property "License" "Apache-2.0"
			(at 0 0 180)
			(unlocked yes)
			(layer "B.Fab")
			(hide yes)
			(effects
				(font
					(size 1 1)
					(thickness 0.15)
				)
				(justify mirror)
			)
		)
		(property "Author" "Antmicro"
			(at 0 0 180)
			(unlocked yes)
			(layer "B.Fab")
			(hide yes)
			(effects
				(font
					(size 1 1)
					(thickness 0.15)
				)
				(justify mirror)
			)
		)
		(property "Val" "1u"
			(at 0 0 180)
			(unlocked yes)
			(layer "B.Fab")
			(hide yes)
			(effects
				(font
					(size 1 1)
					(thickness 0.15)
				)
				(justify mirror)
			)
		)
		(property "Voltage" "25V"
			(at 0 0 180)
			(unlocked yes)
			(layer "B.Fab")
			(hide yes)
			(effects
				(font
					(size 1 1)
					(thickness 0.15)
				)
				(justify mirror)
			)
		)
		(property "Dielectric" "X5R"
			(at 0 0 180)
			(unlocked yes)
			(layer "B.Fab")
			(hide yes)
			(effects
				(font
					(size 1 1)
					(thickness 0.15)
				)
				(justify mirror)
			)
		)
		(sheetname "/X710-AT2 power/")
		(sheetfile "x710-at2-power.kicad_sch")
		(attr smd)
		(fp_rect
			(start -0.925 0.47)
			(end 0.925 -0.47)
			(stroke
				(width 0.05)
				(type default)
			)
			(fill no)
			(layer "B.CrtYd")
		)
		(fp_line
			(start 0.504 0.25)
			(end 0.504 -0.248)
			(stroke
				(width 0.15)
				(type solid)
			)
			(layer "B.Fab")
		)
		(fp_line
			(start 0.504 -0.248)
			(end -0.494 -0.248)
			(stroke
				(width 0.15)
				(type solid)
			)
			(layer "B.Fab")
		)
		(fp_line
			(start -0.494 0.25)
			(end 0.504 0.25)
			(stroke
				(width 0.15)
				(type solid)
			)
			(layer "B.Fab")
		)
		(fp_line
			(start -0.494 -0.248)
			(end -0.494 0.25)
			(stroke
				(width 0.15)
				(type solid)
			)
			(layer "B.Fab")
		)
		(pad "1" smd roundrect
			(at -0.48 0 180)
			(size 0.59 0.64)
			(layers "B.Cu" "B.Mask" "B.Paste")
			(roundrect_rratio 0.25)
			(net 28 "GND")
			(pintype "passive")
		)
		(pad "2" smd roundrect
			(at 0.48 0 180)
			(size 0.59 0.64)
			(layers "B.Cu" "B.Mask" "B.Paste")
			(roundrect_rratio 0.25)
			(net 14 "P1_AVDDL")
			(pintype "passive")
		)
	)
	(footprint "antmicro-footprints:FB_0603_1608Metric"
		(layer "B.Cu")
		(at 73.1 105.45)
		(property "Reference" "FB7"
			(at -3.25 -0.41 0)
			(layer "B.SilkS")
			(effects
				(font
					(size 0.7 0.7)
					(thickness 0.15)
				)
				(justify right top mirror)
			)
		)
		(property "Value" "FB_470Z_1A_Murata-BLM18PG_0603"
			(at 0 -1.5 0)
			(layer "B.Fab")
			(hide yes)
			(effects
				(font
					(size 0.7 0.7)
					(thickness 0.15)
				)
				(justify right top mirror)
			)
		)
		(property "Datasheet" "https://www.murata.com/en-us/products/productdata/8796738650142/ENFA0003.pdf"
			(at 0 0 0)
			(layer "B.Fab")
			(hide yes)
			(effects
				(font
					(size 1.27 1.27)
					(thickness 0.15)
				)
				(justify mirror)
			)
		)
		(property "Description" "Ferrite Bead, 0603 [1608 Metric], 470 ohm, 1 A, BLM18P, 0.2 ohm, ± 25%, DC power line"
			(at 0 0 0)
			(layer "B.Fab")
			(hide yes)
			(effects
				(font
					(size 1.27 1.27)
					(thickness 0.15)
				)
				(justify mirror)
			)
		)
		(property "Val" "470Z/1A"
			(at 0 0 0)
			(unlocked yes)
			(layer "B.Fab")
			(hide yes)
			(effects
				(font
					(size 1 1)
					(thickness 0.15)
				)
				(justify mirror)
			)
		)
		(property "MPN" "BLM18PG471SN1D"
			(at 0 0 0)
			(unlocked yes)
			(layer "B.Fab")
			(hide yes)
			(effects
				(font
					(size 1 1)
					(thickness 0.15)
				)
				(justify mirror)
			)
		)
		(property "Manufacturer" "Murata"
			(at 0 0 0)
			(unlocked yes)
			(layer "B.Fab")
			(hide yes)
			(effects
				(font
					(size 1 1)
					(thickness 0.15)
				)
				(justify mirror)
			)
		)
		(property "Current" ""
			(at 0 0 0)
			(unlocked yes)
			(layer "B.Fab")
			(hide yes)
			(effects
				(font
					(size 1 1)
					(thickness 0.15)
				)
				(justify mirror)
			)
		)
		(property "Author" "Antmicro"
			(at 0 0 0)
			(unlocked yes)
			(layer "B.Fab")
			(hide yes)
			(effects
				(font
					(size 1 1)
					(thickness 0.15)
				)
				(justify mirror)
			)
		)
		(property "License" "Apache-2.0"
			(at 0 0 0)
			(unlocked yes)
			(layer "B.Fab")
			(hide yes)
			(effects
				(font
					(size 1 1)
					(thickness 0.15)
				)
				(justify mirror)
			)
		)
		(sheetname "/X710-AT2 power/")
		(sheetfile "x710-at2-power.kicad_sch")
		(attr smd)
		(fp_line
			(start -0.15 -0.4)
			(end 0.15 -0.4)
			(stroke
				(width 0.15)
				(type solid)
			)
			(layer "B.SilkS")
		)
		(fp_line
			(start -0.15 0.4)
			(end 0.15 0.4)
			(stroke
				(width 0.15)
				(type solid)
			)
			(layer "B.SilkS")
		)
		(fp_rect
			(start -1.25 0.65)
			(end 1.25 -0.65)
			(stroke
				(width 0.05)
				(type solid)
			)
			(fill no)
			(layer "B.CrtYd")
		)
		(fp_line
			(start -0.803 -0.406)
			(end -0.803 0.408)
			(stroke
				(width 0.15)
				(type solid)
			)
			(layer "B.Fab")
		)
		(fp_line
			(start 0.8 -0.406)
			(end -0.803 -0.406)
			(stroke
				(width 0.15)
				(type solid)
			)
			(layer "B.Fab")
		)
		(fp_line
			(start 0.8 0.408)
			(end -0.803 0.408)
			(stroke
				(width 0.15)
				(type solid)
			)
			(layer "B.Fab")
		)
		(fp_line
			(start 0.8 0.408)
			(end 0.8 -0.406)
			(stroke
				(width 0.15)
				(type solid)
			)
			(layer "B.Fab")
		)
		(pad "1" smd roundrect
			(at -0.7 0)
			(size 0.8 1)
			(layers "B.Cu" "B.Mask" "B.Paste")
			(roundrect_rratio 0.2)
			(net 302 "+1V0")
			(pintype "passive")
		)
		(pad "2" smd roundrect
			(at 0.7 0)
			(size 0.8 1)
			(layers "B.Cu" "B.Mask" "B.Paste")
			(roundrect_rratio 0.2)
			(net 27 "PLL_VDD")
			(pintype "passive")
		)
	)
	(footprint "antmicro-footprints:C_0402_1005Metric"
		(layer "B.Cu")
		(at 83.3 127.1)
		(descr "Capacitor SMD 0402")
		(tags "capacitor SMD 0402")
		(property "Reference" "C51"
			(at -0.85 0.45 0)
			(layer "B.SilkS")
			(effects
				(font
					(size 0.7 0.7)
					(thickness 0.15)
				)
				(justify left bottom mirror)
			)
		)
		(property "Value" "C_100n_0402"
			(at -1.022927 -2.155213 0)
			(layer "B.Fab")
			(hide yes)
			(effects
				(font
					(size 0.7 0.7)
					(thickness 0.15)
				)
				(justify right top mirror)
			)
		)
		(property "Datasheet" "https://www.murata.com/products/productdetail?partno=GRM155R61H104KE14%23"
			(at 0 0 0)
			(layer "B.Fab")
			(hide yes)
			(effects
				(font
					(size 1.27 1.27)
					(thickness 0.15)
				)
				(justify mirror)
			)
		)
		(property "Description" "SMD Multilayer Ceramic Capacitor, 0.1 µF, 50 V, 0402 [1005 Metric], ± 10%, X5R, GRM Series"
			(at 0 0 0)
			(layer "B.Fab")
			(hide yes)
			(effects
				(font
					(size 1.27 1.27)
					(thickness 0.15)
				)
				(justify mirror)
			)
		)
		(property "MPN" "GRM155R61H104KE14D"
			(at 0 0 0)
			(unlocked yes)
			(layer "B.Fab")
			(hide yes)
			(effects
				(font
					(size 1 1)
					(thickness 0.15)
				)
				(justify mirror)
			)
		)
		(property "Val" "100n"
			(at 0 0 0)
			(unlocked yes)
			(layer "B.Fab")
			(hide yes)
			(effects
				(font
					(size 1 1)
					(thickness 0.15)
				)
				(justify mirror)
			)
		)
		(property "Voltage" "50V"
			(at 0 0 0)
			(unlocked yes)
			(layer "B.Fab")
			(hide yes)
			(effects
				(font
					(size 1 1)
					(thickness 0.15)
				)
				(justify mirror)
			)
		)
		(property "Dielectric" "X5R"
			(at 0 0 0)
			(unlocked yes)
			(layer "B.Fab")
			(hide yes)
			(effects
				(font
					(size 1 1)
					(thickness 0.15)
				)
				(justify mirror)
			)
		)
		(property "Manufacturer" "Murata"
			(at 0 0 0)
			(unlocked yes)
			(layer "B.Fab")
			(hide yes)
			(effects
				(font
					(size 1 1)
					(thickness 0.15)
				)
				(justify mirror)
			)
		)
		(property "License" "Apache-2.0"
			(at 0 0 0)
			(unlocked yes)
			(layer "B.Fab")
			(hide yes)
			(effects
				(font
					(size 1 1)
					(thickness 0.15)
				)
				(justify mirror)
			)
		)
		(property "Author" "Antmicro"
			(at 0 0 0)
			(unlocked yes)
			(layer "B.Fab")
			(hide yes)
			(effects
				(font
					(size 1 1)
					(thickness 0.15)
				)
				(justify mirror)
			)
		)
		(sheetname "/2xRJ45/")
		(sheetfile "2xrj45.kicad_sch")
		(attr smd)
		(fp_rect
			(start -0.925 0.47)
			(end 0.925 -0.47)
			(stroke
				(width 0.05)
				(type default)
			)
			(fill no)
			(layer "B.CrtYd")
		)
		(fp_line
			(start -0.494 -0.248)
			(end -0.494 0.25)
			(stroke
				(width 0.15)
				(type solid)
			)
			(layer "B.Fab")
		)
		(fp_line
			(start -0.494 0.25)
			(end 0.504 0.25)
			(stroke
				(width 0.15)
				(type solid)
			)
			(layer "B.Fab")
		)
		(fp_line
			(start 0.504 -0.248)
			(end -0.494 -0.248)
			(stroke
				(width 0.15)
				(type solid)
			)
			(layer "B.Fab")
		)
		(fp_line
			(start 0.504 0.25)
			(end 0.504 -0.248)
			(stroke
				(width 0.15)
				(type solid)
			)
			(layer "B.Fab")
		)
		(pad "1" smd roundrect
			(at -0.48 0)
			(size 0.59 0.64)
			(layers "B.Cu" "B.Mask" "B.Paste")
			(roundrect_rratio 0.25)
			(net 28 "GND")
			(pintype "passive")
		)
		(pad "2" smd roundrect
			(at 0.48 0)
			(size 0.59 0.64)
			(layers "B.Cu" "B.Mask" "B.Paste")
			(roundrect_rratio 0.25)
			(net 18 "+1V88")
			(pintype "passive")
		)
	)
	(footprint "antmicro-footprints:C_0402_1005Metric"
		(layer "B.Cu")
		(at 86.225 98.3 90)
		(descr "Capacitor SMD 0402")
		(tags "capacitor SMD 0402")
		(property "Reference" "C115"
			(at 10.69 -0.536429 90)
			(layer "B.SilkS")
			(effects
				(font
					(size 0.7 0.7)
					(thickness 0.15)
				)
				(justify right top mirror)
			)
		)
		(property "Value" "C_1u_25V_0402"
			(at -1.022927 -2.155213 90)
			(layer "B.Fab")
			(hide yes)
			(effects
				(font
					(size 0.7 0.7)
					(thickness 0.15)
				)
				(justify right top mirror)
			)
		)
		(property "Datasheet" "https://www.murata.com/products/productdetail?partno=GRM155R61E105KE11%23"
			(at 0 0 90)
			(layer "B.Fab")
			(hide yes)
			(effects
				(font
					(size 1.27 1.27)
					(thickness 0.15)
				)
				(justify mirror)
			)
		)
		(property "Description" "SMD Multilayer Ceramic Capacitor, 1 µF, 25 V, 0402 [1005 Metric], ± 10%, X5R, GRM Series"
			(at 0 0 90)
			(layer "B.Fab")
			(hide yes)
			(effects
				(font
					(size 1.27 1.27)
					(thickness 0.15)
				)
				(justify mirror)
			)
		)
		(property "MPN" "GRM155R61E105KE11J"
			(at 0 0 90)
			(unlocked yes)
			(layer "B.Fab")
			(hide yes)
			(effects
				(font
					(size 1 1)
					(thickness 0.15)
				)
				(justify mirror)
			)
		)
		(property "Manufacturer" "Murata"
			(at 0 0 90)
			(unlocked yes)
			(layer "B.Fab")
			(hide yes)
			(effects
				(font
					(size 1 1)
					(thickness 0.15)
				)
				(justify mirror)
			)
		)
		(property "License" "Apache-2.0"
			(at 0 0 90)
			(unlocked yes)
			(layer "B.Fab")
			(hide yes)
			(effects
				(font
					(size 1 1)
					(thickness 0.15)
				)
				(justify mirror)
			)
		)
		(property "Author" "Antmicro"
			(at 0 0 90)
			(unlocked yes)
			(layer "B.Fab")
			(hide yes)
			(effects
				(font
					(size 1 1)
					(thickness 0.15)
				)
				(justify mirror)
			)
		)
		(property "Val" "1u"
			(at 0 0 90)
			(unlocked yes)
			(layer "B.Fab")
			(hide yes)
			(effects
				(font
					(size 1 1)
					(thickness 0.15)
				)
				(justify mirror)
			)
		)
		(property "Voltage" "25V"
			(at 0 0 90)
			(unlocked yes)
			(layer "B.Fab")
			(hide yes)
			(effects
				(font
					(size 1 1)
					(thickness 0.15)
				)
				(justify mirror)
			)
		)
		(property "Dielectric" "X5R"
			(at 0 0 90)
			(unlocked yes)
			(layer "B.Fab")
			(hide yes)
			(effects
				(font
					(size 1 1)
					(thickness 0.15)
				)
				(justify mirror)
			)
		)
		(sheetname "/X710-AT2 power/")
		(sheetfile "x710-at2-power.kicad_sch")
		(attr smd)
		(fp_rect
			(start -0.925 0.47)
			(end 0.925 -0.47)
			(stroke
				(width 0.05)
				(type default)
			)
			(fill no)
			(layer "B.CrtYd")
		)
		(fp_line
			(start 0.504 -0.248)
			(end -0.494 -0.248)
			(stroke
				(width 0.15)
				(type solid)
			)
			(layer "B.Fab")
		)
		(fp_line
			(start -0.494 -0.248)
			(end -0.494 0.25)
			(stroke
				(width 0.15)
				(type solid)
			)
			(layer "B.Fab")
		)
		(fp_line
			(start 0.504 0.25)
			(end 0.504 -0.248)
			(stroke
				(width 0.15)
				(type solid)
			)
			(layer "B.Fab")
		)
		(fp_line
			(start -0.494 0.25)
			(end 0.504 0.25)
			(stroke
				(width 0.15)
				(type solid)
			)
			(layer "B.Fab")
		)
		(pad "1" smd roundrect
			(at -0.48 0 90)
			(size 0.59 0.64)
			(layers "B.Cu" "B.Mask" "B.Paste")
			(roundrect_rratio 0.25)
			(net 28 "GND")
			(pintype "passive")
		)
		(pad "2" smd roundrect
			(at 0.48 0 90)
			(size 0.59 0.64)
			(layers "B.Cu" "B.Mask" "B.Paste")
			(roundrect_rratio 0.25)
			(net 9 "VCCD")
			(pintype "passive")
		)
	)
	(footprint "antmicro-footprints:C_0402_1005Metric"
		(layer "B.Cu")
		(at 71.48 145.34 -90)
		(descr "Capacitor SMD 0402")
		(tags "capacitor SMD 0402")
		(property "Reference" "C50"
			(at -2.92 -0.45 90)
			(layer "B.SilkS")
			(effects
				(font
					(size 0.7 0.7)
					(thickness 0.15)
				)
				(justify left bottom mirror)
			)
		)
		(property "Value" "C_470p_0402"
			(at -1.022927 -2.155213 90)
			(layer "B.Fab")
			(hide yes)
			(effects
				(font
					(size 0.7 0.7)
					(thickness 0.15)
				)
				(justify left bottom mirror)
			)
		)
		(property "Datasheet" "https://www.passivecomponent.com/wp-content/uploads/datasheet/WTC_MLCC_General_Purpose.pdf"
			(at 0 0 90)
			(layer "B.Fab")
			(hide yes)
			(effects
				(font
					(size 1.27 1.27)
					(thickness 0.15)
				)
				(justify mirror)
			)
		)
		(property "Description" "SMD Multilayer Ceramic Capacitor, General Purpose, 470 pF, 25 V, 0402 [1005 Metric], ± 10%, X7R"
			(at 0 0 90)
			(layer "B.Fab")
			(hide yes)
			(effects
				(font
					(size 1.27 1.27)
					(thickness 0.15)
				)
				(justify mirror)
			)
		)
		(property "MPN" "0402B471K250CT"
			(at 0 0 270)
			(unlocked yes)
			(layer "B.Fab")
			(hide yes)
			(effects
				(font
					(size 1 1)
					(thickness 0.15)
				)
				(justify mirror)
			)
		)
		(property "Manufacturer" "Walsin"
			(at 0 0 270)
			(unlocked yes)
			(layer "B.Fab")
			(hide yes)
			(effects
				(font
					(size 1 1)
					(thickness 0.15)
				)
				(justify mirror)
			)
		)
		(property "License" "Apache-2.0"
			(at 0 0 270)
			(unlocked yes)
			(layer "B.Fab")
			(hide yes)
			(effects
				(font
					(size 1 1)
					(thickness 0.15)
				)
				(justify mirror)
			)
		)
		(property "Author" "Antmicro"
			(at 0 0 270)
			(unlocked yes)
			(layer "B.Fab")
			(hide yes)
			(effects
				(font
					(size 1 1)
					(thickness 0.15)
				)
				(justify mirror)
			)
		)
		(property "Val" "470p"
			(at 0 0 270)
			(unlocked yes)
			(layer "B.Fab")
			(hide yes)
			(effects
				(font
					(size 1 1)
					(thickness 0.15)
				)
				(justify mirror)
			)
		)
		(property "Voltage" "25V"
			(at 0 0 270)
			(unlocked yes)
			(layer "B.Fab")
			(hide yes)
			(effects
				(font
					(size 1 1)
					(thickness 0.15)
				)
				(justify mirror)
			)
		)
		(property "Dielectric" "X7R"
			(at 0 0 270)
			(unlocked yes)
			(layer "B.Fab")
			(hide yes)
			(effects
				(font
					(size 1 1)
					(thickness 0.15)
				)
				(justify mirror)
			)
		)
		(sheetname "/2xRJ45/")
		(sheetfile "2xrj45.kicad_sch")
		(attr smd)
		(fp_rect
			(start -0.925 0.47)
			(end 0.925 -0.47)
			(stroke
				(width 0.05)
				(type default)
			)
			(fill no)
			(layer "B.CrtYd")
		)
		(fp_line
			(start -0.494 0.25)
			(end 0.504 0.25)
			(stroke
				(width 0.15)
				(type solid)
			)
			(layer "B.Fab")
		)
		(fp_line
			(start 0.504 0.25)
			(end 0.504 -0.248)
			(stroke
				(width 0.15)
				(type solid)
			)
			(layer "B.Fab")
		)
		(fp_line
			(start -0.494 -0.248)
			(end -0.494 0.25)
			(stroke
				(width 0.15)
				(type solid)
			)
			(layer "B.Fab")
		)
		(fp_line
			(start 0.504 -0.248)
			(end -0.494 -0.248)
			(stroke
				(width 0.15)
				(type solid)
			)
			(layer "B.Fab")
		)
		(pad "1" smd roundrect
			(at -0.48 0 270)
			(size 0.59 0.64)
			(layers "B.Cu" "B.Mask" "B.Paste")
			(roundrect_rratio 0.25)
			(net 28 "GND")
			(pintype "passive")
		)
		(pad "2" smd roundrect
			(at 0.48 0 270)
			(size 0.59 0.64)
			(layers "B.Cu" "B.Mask" "B.Paste")
			(roundrect_rratio 0.25)
			(net 54 "Net-(J3-LED_GRN-)")
			(pintype "passive")
		)
	)
	(footprint "antmicro-footprints:C_0402_1005Metric"
		(layer "B.Cu")
		(at 79.07 107.42 180)
		(descr "Capacitor SMD 0402")
		(tags "capacitor SMD 0402")
		(property "Reference" "C129"
			(at -1.52 -11.29 0)
			(layer "B.SilkS")
			(effects
				(font
					(size 0.7 0.7)
					(thickness 0.15)
				)
				(justify left bottom mirror)
			)
		)
		(property "Value" "C_1u_25V_0402"
			(at -1.022927 -2.155213 0)
			(layer "B.Fab")
			(hide yes)
			(effects
				(font
					(size 0.7 0.7)
					(thickness 0.15)
				)
				(justify left bottom mirror)
			)
		)
		(property "Datasheet" "https://www.murata.com/products/productdetail?partno=GRM155R61E105KE11%23"
			(at 0 0 0)
			(layer "B.Fab")
			(hide yes)
			(effects
				(font
					(size 1.27 1.27)
					(thickness 0.15)
				)
				(justify mirror)
			)
		)
		(property "Description" "SMD Multilayer Ceramic Capacitor, 1 µF, 25 V, 0402 [1005 Metric], ± 10%, X5R, GRM Series"
			(at 0 0 0)
			(layer "B.Fab")
			(hide yes)
			(effects
				(font
					(size 1.27 1.27)
					(thickness 0.15)
				)
				(justify mirror)
			)
		)
		(property "MPN" "GRM155R61E105KE11J"
			(at 0 0 180)
			(unlocked yes)
			(layer "B.Fab")
			(hide yes)
			(effects
				(font
					(size 1 1)
					(thickness 0.15)
				)
				(justify mirror)
			)
		)
		(property "Manufacturer" "Murata"
			(at 0 0 180)
			(unlocked yes)
			(layer "B.Fab")
			(hide yes)
			(effects
				(font
					(size 1 1)
					(thickness 0.15)
				)
				(justify mirror)
			)
		)
		(property "License" "Apache-2.0"
			(at 0 0 180)
			(unlocked yes)
			(layer "B.Fab")
			(hide yes)
			(effects
				(font
					(size 1 1)
					(thickness 0.15)
				)
				(justify mirror)
			)
		)
		(property "Author" "Antmicro"
			(at 0 0 180)
			(unlocked yes)
			(layer "B.Fab")
			(hide yes)
			(effects
				(font
					(size 1 1)
					(thickness 0.15)
				)
				(justify mirror)
			)
		)
		(property "Val" "1u"
			(at 0 0 180)
			(unlocked yes)
			(layer "B.Fab")
			(hide yes)
			(effects
				(font
					(size 1 1)
					(thickness 0.15)
				)
				(justify mirror)
			)
		)
		(property "Voltage" "25V"
			(at 0 0 180)
			(unlocked yes)
			(layer "B.Fab")
			(hide yes)
			(effects
				(font
					(size 1 1)
					(thickness 0.15)
				)
				(justify mirror)
			)
		)
		(property "Dielectric" "X5R"
			(at 0 0 180)
			(unlocked yes)
			(layer "B.Fab")
			(hide yes)
			(effects
				(font
					(size 1 1)
					(thickness 0.15)
				)
				(justify mirror)
			)
		)
		(sheetname "/X710-AT2 power/")
		(sheetfile "x710-at2-power.kicad_sch")
		(attr smd)
		(fp_rect
			(start -0.925 0.47)
			(end 0.925 -0.47)
			(stroke
				(width 0.05)
				(type default)
			)
			(fill no)
			(layer "B.CrtYd")
		)
		(fp_line
			(start 0.504 0.25)
			(end 0.504 -0.248)
			(stroke
				(width 0.15)
				(type solid)
			)
			(layer "B.Fab")
		)
		(fp_line
			(start 0.504 -0.248)
			(end -0.494 -0.248)
			(stroke
				(width 0.15)
				(type solid)
			)
			(layer "B.Fab")
		)
		(fp_line
			(start -0.494 0.25)
			(end 0.504 0.25)
			(stroke
				(width 0.15)
				(type solid)
			)
			(layer "B.Fab")
		)
		(fp_line
			(start -0.494 -0.248)
			(end -0.494 0.25)
			(stroke
				(width 0.15)
				(type solid)
			)
			(layer "B.Fab")
		)
		(pad "1" smd roundrect
			(at -0.48 0 180)
			(size 0.59 0.64)
			(layers "B.Cu" "B.Mask" "B.Paste")
			(roundrect_rratio 0.25)
			(net 28 "GND")
			(pintype "passive")
		)
		(pad "2" smd roundrect
			(at 0.48 0 180)
			(size 0.59 0.64)
			(layers "B.Cu" "B.Mask" "B.Paste")
			(roundrect_rratio 0.25)
			(net 23 "XGB_AVDDH")
			(pintype "passive")
		)
	)
	(footprint "antmicro-footprints:TP_SMD_0.75mm"
		(layer "B.Cu")
		(at 103.55 104.2 90)
		(property "Reference" "TP1"
			(at 0.44 0.41 180)
			(layer "B.SilkS")
			(effects
				(font
					(size 0.7 0.7)
					(thickness 0.15)
				)
				(justify right top mirror)
			)
		)
		(property "Value" "TP_0.75mm_SMD"
			(at 0 -1.2 90)
			(layer "B.Fab")
			(hide yes)
			(effects
				(font
					(size 0.7 0.7)
					(thickness 0.15)
				)
				(justify right top mirror)
			)
		)
		(property "Description" "SMT test point"
			(at 0 0 90)
			(layer "B.Fab")
			(hide yes)
			(effects
				(font
					(size 1.27 1.27)
					(thickness 0.15)
				)
				(justify mirror)
			)
		)
		(property "MPN" ""
			(at 0 0 90)
			(unlocked yes)
			(layer "B.Fab")
			(hide yes)
			(effects
				(font
					(size 1 1)
					(thickness 0.15)
				)
				(justify mirror)
			)
		)
		(property "Manufacturer" ""
			(at 0 0 90)
			(unlocked yes)
			(layer "B.Fab")
			(hide yes)
			(effects
				(font
					(size 1 1)
					(thickness 0.15)
				)
				(justify mirror)
			)
		)
		(property "Author" "Antmicro"
			(at 0 0 90)
			(unlocked yes)
			(layer "B.Fab")
			(hide yes)
			(effects
				(font
					(size 1 1)
					(thickness 0.15)
				)
				(justify mirror)
			)
		)
		(property "License" "Apache-2.0"
			(at 0 0 90)
			(unlocked yes)
			(layer "B.Fab")
			(hide yes)
			(effects
				(font
					(size 1 1)
					(thickness 0.15)
				)
				(justify mirror)
			)
		)
		(sheetname "/X710-AT2 Misc/")
		(sheetfile "x710-at2-mics.kicad_sch")
		(attr exclude_from_pos_files exclude_from_bom)
		(fp_circle
			(center 0 0)
			(end 0.475 0)
			(stroke
				(width 0.05)
				(type default)
			)
			(fill no)
			(layer "B.CrtYd")
		)
		(pad "1" smd circle
			(at 0 0 90)
			(size 0.75 0.75)
			(layers "B.Cu" "B.Mask")
			(net 368 "/X710-AT2 Misc/NCSI.ARB_IN")
			(pinfunction "1")
			(pintype "passive")
		)
	)
	(footprint "antmicro-footprints:R_0402_1005Metric"
		(layer "B.Cu")
		(at 74 95.65 180)
		(descr "Resistor SMD 0402")
		(tags "resistor SMD 0402")
		(property "Reference" "R91"
			(at 0.85 -0.45 0)
			(layer "B.SilkS")
			(effects
				(font
					(size 0.7 0.7)
					(thickness 0.15)
				)
				(justify left bottom mirror)
			)
		)
		(property "Value" "R_10k_0402"
			(at -1.011843 -1.772047 0)
			(layer "B.Fab")
			(hide yes)
			(effects
				(font
					(size 0.7 0.7)
					(thickness 0.15)
				)
				(justify left bottom mirror)
			)
		)
		(property "Datasheet" "https://www.bourns.com/docs/product-datasheets/cr.pdf"
			(at 0 0 0)
			(layer "B.Fab")
			(hide yes)
			(effects
				(font
					(size 1.27 1.27)
					(thickness 0.15)
				)
				(justify mirror)
			)
		)
		(property "Description" "SMD Chip Resistor, 10 kohm, ± 1%, 62.5 mW, 0402 [1005 Metric], Thick Film, General Purpose"
			(at 0 0 0)
			(layer "B.Fab")
			(hide yes)
			(effects
				(font
					(size 1.27 1.27)
					(thickness 0.15)
				)
				(justify mirror)
			)
		)
		(property "MPN" "CR0402-FX-1002GLF"
			(at 0 0 180)
			(unlocked yes)
			(layer "B.Fab")
			(hide yes)
			(effects
				(font
					(size 1 1)
					(thickness 0.15)
				)
				(justify mirror)
			)
		)
		(property "Manufacturer" "Bourns"
			(at 0 0 180)
			(unlocked yes)
			(layer "B.Fab")
			(hide yes)
			(effects
				(font
					(size 1 1)
					(thickness 0.15)
				)
				(justify mirror)
			)
		)
		(property "License" "Apache-2.0"
			(at 0 0 180)
			(unlocked yes)
			(layer "B.Fab")
			(hide yes)
			(effects
				(font
					(size 1 1)
					(thickness 0.15)
				)
				(justify mirror)
			)
		)
		(property "Author" "Antmicro"
			(at 0 0 180)
			(unlocked yes)
			(layer "B.Fab")
			(hide yes)
			(effects
				(font
					(size 1 1)
					(thickness 0.15)
				)
				(justify mirror)
			)
		)
		(property "Val" "10k"
			(at 0 0 180)
			(unlocked yes)
			(layer "B.Fab")
			(hide yes)
			(effects
				(font
					(size 1 1)
					(thickness 0.15)
				)
				(justify mirror)
			)
		)
		(property "Tolerance" "1%"
			(at 0 0 180)
			(unlocked yes)
			(layer "B.Fab")
			(hide yes)
			(effects
				(font
					(size 1 1)
					(thickness 0.15)
				)
				(justify mirror)
			)
		)
		(sheetname "/X710-AT2 Misc/")
		(sheetfile "x710-at2-mics.kicad_sch")
		(attr smd)
		(fp_rect
			(start -0.925 0.47)
			(end 0.925 -0.47)
			(stroke
				(width 0.05)
				(type default)
			)
			(fill no)
			(layer "B.CrtYd")
		)
		(fp_rect
			(start -0.5 0.25)
			(end 0.5 -0.25)
			(stroke
				(width 0.15)
				(type solid)
			)
			(fill no)
			(layer "B.Fab")
		)
		(pad "1" smd roundrect
			(at -0.48 0 180)
			(size 0.59 0.64)
			(layers "B.Cu" "B.Mask" "B.Paste")
			(roundrect_rratio 0.25)
			(net 97 "/X710-AT2 Misc/~{SMBALRT}")
			(pintype "passive")
		)
		(pad "2" smd roundrect
			(at 0.48 0 180)
			(size 0.59 0.64)
			(layers "B.Cu" "B.Mask" "B.Paste")
			(roundrect_rratio 0.25)
			(net 7 "+3V3")
			(pintype "passive")
		)
	)
	(footprint "antmicro-footprints:C_0402_1005Metric"
		(layer "B.Cu")
		(at 82.28 105.08 90)
		(descr "Capacitor SMD 0402")
		(tags "capacitor SMD 0402")
		(property "Reference" "C86"
			(at -11.81 0.21 90)
			(layer "B.SilkS")
			(effects
				(font
					(size 0.7 0.7)
					(thickness 0.15)
				)
				(justify right top mirror)
			)
		)
		(property "Value" "C_1u_25V_0402"
			(at -1.022927 -2.155213 90)
			(layer "B.Fab")
			(hide yes)
			(effects
				(font
					(size 0.7 0.7)
					(thickness 0.15)
				)
				(justify right top mirror)
			)
		)
		(property "Datasheet" "https://www.murata.com/products/productdetail?partno=GRM155R61E105KE11%23"
			(at 0 0 90)
			(layer "B.Fab")
			(hide yes)
			(effects
				(font
					(size 1.27 1.27)
					(thickness 0.15)
				)
				(justify mirror)
			)
		)
		(property "Description" "SMD Multilayer Ceramic Capacitor, 1 µF, 25 V, 0402 [1005 Metric], ± 10%, X5R, GRM Series"
			(at 0 0 90)
			(layer "B.Fab")
			(hide yes)
			(effects
				(font
					(size 1.27 1.27)
					(thickness 0.15)
				)
				(justify mirror)
			)
		)
		(property "MPN" "GRM155R61E105KE11J"
			(at 0 0 90)
			(unlocked yes)
			(layer "B.Fab")
			(hide yes)
			(effects
				(font
					(size 1 1)
					(thickness 0.15)
				)
				(justify mirror)
			)
		)
		(property "Manufacturer" "Murata"
			(at 0 0 90)
			(unlocked yes)
			(layer "B.Fab")
			(hide yes)
			(effects
				(font
					(size 1 1)
					(thickness 0.15)
				)
				(justify mirror)
			)
		)
		(property "License" "Apache-2.0"
			(at 0 0 90)
			(unlocked yes)
			(layer "B.Fab")
			(hide yes)
			(effects
				(font
					(size 1 1)
					(thickness 0.15)
				)
				(justify mirror)
			)
		)
		(property "Author" "Antmicro"
			(at 0 0 90)
			(unlocked yes)
			(layer "B.Fab")
			(hide yes)
			(effects
				(font
					(size 1 1)
					(thickness 0.15)
				)
				(justify mirror)
			)
		)
		(property "Val" "1u"
			(at 0 0 90)
			(unlocked yes)
			(layer "B.Fab")
			(hide yes)
			(effects
				(font
					(size 1 1)
					(thickness 0.15)
				)
				(justify mirror)
			)
		)
		(property "Voltage" "25V"
			(at 0 0 90)
			(unlocked yes)
			(layer "B.Fab")
			(hide yes)
			(effects
				(font
					(size 1 1)
					(thickness 0.15)
				)
				(justify mirror)
			)
		)
		(property "Dielectric" "X5R"
			(at 0 0 90)
			(unlocked yes)
			(layer "B.Fab")
			(hide yes)
			(effects
				(font
					(size 1 1)
					(thickness 0.15)
				)
				(justify mirror)
			)
		)
		(sheetname "/X710-AT2 power/")
		(sheetfile "x710-at2-power.kicad_sch")
		(attr smd)
		(fp_rect
			(start -0.925 0.47)
			(end 0.925 -0.47)
			(stroke
				(width 0.05)
				(type default)
			)
			(fill no)
			(layer "B.CrtYd")
		)
		(fp_line
			(start 0.504 -0.248)
			(end -0.494 -0.248)
			(stroke
				(width 0.15)
				(type solid)
			)
			(layer "B.Fab")
		)
		(fp_line
			(start -0.494 -0.248)
			(end -0.494 0.25)
			(stroke
				(width 0.15)
				(type solid)
			)
			(layer "B.Fab")
		)
		(fp_line
			(start 0.504 0.25)
			(end 0.504 -0.248)
			(stroke
				(width 0.15)
				(type solid)
			)
			(layer "B.Fab")
		)
		(fp_line
			(start -0.494 0.25)
			(end 0.504 0.25)
			(stroke
				(width 0.15)
				(type solid)
			)
			(layer "B.Fab")
		)
		(pad "1" smd roundrect
			(at -0.48 0 90)
			(size 0.59 0.64)
			(layers "B.Cu" "B.Mask" "B.Paste")
			(roundrect_rratio 0.25)
			(net 28 "GND")
			(pintype "passive")
		)
		(pad "2" smd roundrect
			(at 0.48 0 90)
			(size 0.59 0.64)
			(layers "B.Cu" "B.Mask" "B.Paste")
			(roundrect_rratio 0.25)
			(net 6 "DVDD")
			(pintype "passive")
		)
	)
	(footprint "antmicro-footprints:C_0402_1005Metric"
		(layer "B.Cu")
		(at 76.73 107.9 -90)
		(descr "Capacitor SMD 0402")
		(tags "capacitor SMD 0402")
		(property "Reference" "C167"
			(at 0.84 -0.33 90)
			(layer "B.SilkS")
			(effects
				(font
					(size 0.7 0.7)
					(thickness 0.15)
				)
				(justify left bottom mirror)
			)
		)
		(property "Value" "C_1u_25V_0402"
			(at -1.022927 -2.155213 90)
			(layer "B.Fab")
			(hide yes)
			(effects
				(font
					(size 0.7 0.7)
					(thickness 0.15)
				)
				(justify left bottom mirror)
			)
		)
		(property "Datasheet" "https://www.murata.com/products/productdetail?partno=GRM155R61E105KE11%23"
			(at 0 0 90)
			(layer "B.Fab")
			(hide yes)
			(effects
				(font
					(size 1.27 1.27)
					(thickness 0.15)
				)
				(justify mirror)
			)
		)
		(property "Description" "SMD Multilayer Ceramic Capacitor, 1 µF, 25 V, 0402 [1005 Metric], ± 10%, X5R, GRM Series"
			(at 0 0 90)
			(layer "B.Fab")
			(hide yes)
			(effects
				(font
					(size 1.27 1.27)
					(thickness 0.15)
				)
				(justify mirror)
			)
		)
		(property "MPN" "GRM155R61E105KE11J"
			(at 0 0 270)
			(unlocked yes)
			(layer "B.Fab")
			(hide yes)
			(effects
				(font
					(size 1 1)
					(thickness 0.15)
				)
				(justify mirror)
			)
		)
		(property "Manufacturer" "Murata"
			(at 0 0 270)
			(unlocked yes)
			(layer "B.Fab")
			(hide yes)
			(effects
				(font
					(size 1 1)
					(thickness 0.15)
				)
				(justify mirror)
			)
		)
		(property "License" "Apache-2.0"
			(at 0 0 270)
			(unlocked yes)
			(layer "B.Fab")
			(hide yes)
			(effects
				(font
					(size 1 1)
					(thickness 0.15)
				)
				(justify mirror)
			)
		)
		(property "Author" "Antmicro"
			(at 0 0 270)
			(unlocked yes)
			(layer "B.Fab")
			(hide yes)
			(effects
				(font
					(size 1 1)
					(thickness 0.15)
				)
				(justify mirror)
			)
		)
		(property "Val" "1u"
			(at 0 0 270)
			(unlocked yes)
			(layer "B.Fab")
			(hide yes)
			(effects
				(font
					(size 1 1)
					(thickness 0.15)
				)
				(justify mirror)
			)
		)
		(property "Voltage" "25V"
			(at 0 0 270)
			(unlocked yes)
			(layer "B.Fab")
			(hide yes)
			(effects
				(font
					(size 1 1)
					(thickness 0.15)
				)
				(justify mirror)
			)
		)
		(property "Dielectric" "X5R"
			(at 0 0 270)
			(unlocked yes)
			(layer "B.Fab")
			(hide yes)
			(effects
				(font
					(size 1 1)
					(thickness 0.15)
				)
				(justify mirror)
			)
		)
		(sheetname "/X710-AT2 power/")
		(sheetfile "x710-at2-power.kicad_sch")
		(attr smd)
		(fp_rect
			(start -0.925 0.47)
			(end 0.925 -0.47)
			(stroke
				(width 0.05)
				(type default)
			)
			(fill no)
			(layer "B.CrtYd")
		)
		(fp_line
			(start -0.494 0.25)
			(end 0.504 0.25)
			(stroke
				(width 0.15)
				(type solid)
			)
			(layer "B.Fab")
		)
		(fp_line
			(start 0.504 0.25)
			(end 0.504 -0.248)
			(stroke
				(width 0.15)
				(type solid)
			)
			(layer "B.Fab")
		)
		(fp_line
			(start -0.494 -0.248)
			(end -0.494 0.25)
			(stroke
				(width 0.15)
				(type solid)
			)
			(layer "B.Fab")
		)
		(fp_line
			(start 0.504 -0.248)
			(end -0.494 -0.248)
			(stroke
				(width 0.15)
				(type solid)
			)
			(layer "B.Fab")
		)
		(pad "1" smd roundrect
			(at -0.48 0 270)
			(size 0.59 0.64)
			(layers "B.Cu" "B.Mask" "B.Paste")
			(roundrect_rratio 0.25)
			(net 28 "GND")
			(pintype "passive")
		)
		(pad "2" smd roundrect
			(at 0.48 0 270)
			(size 0.59 0.64)
			(layers "B.Cu" "B.Mask" "B.Paste")
			(roundrect_rratio 0.25)
			(net 5 "P0_AVDDL")
			(pintype "passive")
		)
	)
	(footprint "antmicro-footprints:C_0402_1005Metric"
		(layer "B.Cu")
		(at 82.43 106.93 90)
		(descr "Capacitor SMD 0402")
		(tags "capacitor SMD 0402")
		(property "Reference" "C144"
			(at -12.72 0.11 90)
			(layer "B.SilkS")
			(effects
				(font
					(size 0.7 0.7)
					(thickness 0.15)
				)
				(justify right top mirror)
			)
		)
		(property "Value" "C_1u_25V_0402"
			(at -1.022927 -2.155213 90)
			(layer "B.Fab")
			(hide yes)
			(effects
				(font
					(size 0.7 0.7)
					(thickness 0.15)
				)
				(justify right top mirror)
			)
		)
		(property "Datasheet" "https://www.murata.com/products/productdetail?partno=GRM155R61E105KE11%23"
			(at 0 0 90)
			(layer "B.Fab")
			(hide yes)
			(effects
				(font
					(size 1.27 1.27)
					(thickness 0.15)
				)
				(justify mirror)
			)
		)
		(property "Description" "SMD Multilayer Ceramic Capacitor, 1 µF, 25 V, 0402 [1005 Metric], ± 10%, X5R, GRM Series"
			(at 0 0 90)
			(layer "B.Fab")
			(hide yes)
			(effects
				(font
					(size 1.27 1.27)
					(thickness 0.15)
				)
				(justify mirror)
			)
		)
		(property "MPN" "GRM155R61E105KE11J"
			(at 0 0 90)
			(unlocked yes)
			(layer "B.Fab")
			(hide yes)
			(effects
				(font
					(size 1 1)
					(thickness 0.15)
				)
				(justify mirror)
			)
		)
		(property "Manufacturer" "Murata"
			(at 0 0 90)
			(unlocked yes)
			(layer "B.Fab")
			(hide yes)
			(effects
				(font
					(size 1 1)
					(thickness 0.15)
				)
				(justify mirror)
			)
		)
		(property "License" "Apache-2.0"
			(at 0 0 90)
			(unlocked yes)
			(layer "B.Fab")
			(hide yes)
			(effects
				(font
					(size 1 1)
					(thickness 0.15)
				)
				(justify mirror)
			)
		)
		(property "Author" "Antmicro"
			(at 0 0 90)
			(unlocked yes)
			(layer "B.Fab")
			(hide yes)
			(effects
				(font
					(size 1 1)
					(thickness 0.15)
				)
				(justify mirror)
			)
		)
		(property "Val" "1u"
			(at 0 0 90)
			(unlocked yes)
			(layer "B.Fab")
			(hide yes)
			(effects
				(font
					(size 1 1)
					(thickness 0.15)
				)
				(justify mirror)
			)
		)
		(property "Voltage" "25V"
			(at 0 0 90)
			(unlocked yes)
			(layer "B.Fab")
			(hide yes)
			(effects
				(font
					(size 1 1)
					(thickness 0.15)
				)
				(justify mirror)
			)
		)
		(property "Dielectric" "X5R"
			(at 0 0 90)
			(unlocked yes)
			(layer "B.Fab")
			(hide yes)
			(effects
				(font
					(size 1 1)
					(thickness 0.15)
				)
				(justify mirror)
			)
		)
		(sheetname "/X710-AT2 power/")
		(sheetfile "x710-at2-power.kicad_sch")
		(attr smd)
		(fp_rect
			(start -0.925 0.47)
			(end 0.925 -0.47)
			(stroke
				(width 0.05)
				(type default)
			)
			(fill no)
			(layer "B.CrtYd")
		)
		(fp_line
			(start 0.504 -0.248)
			(end -0.494 -0.248)
			(stroke
				(width 0.15)
				(type solid)
			)
			(layer "B.Fab")
		)
		(fp_line
			(start -0.494 -0.248)
			(end -0.494 0.25)
			(stroke
				(width 0.15)
				(type solid)
			)
			(layer "B.Fab")
		)
		(fp_line
			(start 0.504 0.25)
			(end 0.504 -0.248)
			(stroke
				(width 0.15)
				(type solid)
			)
			(layer "B.Fab")
		)
		(fp_line
			(start -0.494 0.25)
			(end 0.504 0.25)
			(stroke
				(width 0.15)
				(type solid)
			)
			(layer "B.Fab")
		)
		(pad "1" smd roundrect
			(at -0.48 0 90)
			(size 0.59 0.64)
			(layers "B.Cu" "B.Mask" "B.Paste")
			(roundrect_rratio 0.25)
			(net 28 "GND")
			(pintype "passive")
		)
		(pad "2" smd roundrect
			(at 0.48 0 90)
			(size 0.59 0.64)
			(layers "B.Cu" "B.Mask" "B.Paste")
			(roundrect_rratio 0.25)
			(net 10 "AVDDH")
			(pintype "passive")
		)
	)
	(footprint "antmicro-footprints:R_0402_1005Metric"
		(layer "B.Cu")
		(at 73.75 90.8 90)
		(descr "Resistor SMD 0402")
		(tags "resistor SMD 0402")
		(property "Reference" "R35"
			(at -1.35 0.6 90)
			(layer "B.SilkS")
			(effects
				(font
					(size 0.7 0.7)
					(thickness 0.15)
				)
				(justify right top mirror)
			)
		)
		(property "Value" "R_10k_0402"
			(at -1.011843 -1.772046 90)
			(layer "B.Fab")
			(hide yes)
			(effects
				(font
					(size 0.7 0.7)
					(thickness 0.15)
				)
				(justify right top mirror)
			)
		)
		(property "Datasheet" "https://www.bourns.com/docs/product-datasheets/cr.pdf"
			(at 0 0 90)
			(layer "B.Fab")
			(hide yes)
			(effects
				(font
					(size 1.27 1.27)
					(thickness 0.15)
				)
				(justify mirror)
			)
		)
		(property "Description" "SMD Chip Resistor, 10 kohm, ± 1%, 62.5 mW, 0402 [1005 Metric], Thick Film, General Purpose"
			(at 0 0 90)
			(layer "B.Fab")
			(hide yes)
			(effects
				(font
					(size 1.27 1.27)
					(thickness 0.15)
				)
				(justify mirror)
			)
		)
		(property "MPN" "CR0402-FX-1002GLF"
			(at 0 0 90)
			(unlocked yes)
			(layer "B.Fab")
			(hide yes)
			(effects
				(font
					(size 1 1)
					(thickness 0.15)
				)
				(justify mirror)
			)
		)
		(property "Manufacturer" "Bourns"
			(at 0 0 90)
			(unlocked yes)
			(layer "B.Fab")
			(hide yes)
			(effects
				(font
					(size 1 1)
					(thickness 0.15)
				)
				(justify mirror)
			)
		)
		(property "License" "Apache-2.0"
			(at 0 0 90)
			(unlocked yes)
			(layer "B.Fab")
			(hide yes)
			(effects
				(font
					(size 1 1)
					(thickness 0.15)
				)
				(justify mirror)
			)
		)
		(property "Author" "Antmicro"
			(at 0 0 90)
			(unlocked yes)
			(layer "B.Fab")
			(hide yes)
			(effects
				(font
					(size 1 1)
					(thickness 0.15)
				)
				(justify mirror)
			)
		)
		(property "Val" "10k"
			(at 0 0 90)
			(unlocked yes)
			(layer "B.Fab")
			(hide yes)
			(effects
				(font
					(size 1 1)
					(thickness 0.15)
				)
				(justify mirror)
			)
		)
		(property "Tolerance" "1%"
			(at 0 0 90)
			(unlocked yes)
			(layer "B.Fab")
			(hide yes)
			(effects
				(font
					(size 1 1)
					(thickness 0.15)
				)
				(justify mirror)
			)
		)
		(sheetname "/Flash memory/")
		(sheetfile "flash-memory.kicad_sch")
		(attr smd)
		(fp_rect
			(start -0.925 0.47)
			(end 0.925 -0.47)
			(stroke
				(width 0.05)
				(type default)
			)
			(fill no)
			(layer "B.CrtYd")
		)
		(fp_rect
			(start -0.5 0.25)
			(end 0.5 -0.25)
			(stroke
				(width 0.15)
				(type solid)
			)
			(fill no)
			(layer "B.Fab")
		)
		(pad "1" smd roundrect
			(at -0.48 0 90)
			(size 0.59 0.64)
			(layers "B.Cu" "B.Mask" "B.Paste")
			(roundrect_rratio 0.25)
			(net 72 "/Flash memory/~{WP}")
			(pintype "passive")
		)
		(pad "2" smd roundrect
			(at 0.48 0 90)
			(size 0.59 0.64)
			(layers "B.Cu" "B.Mask" "B.Paste")
			(roundrect_rratio 0.25)
			(net 110 "/Flash memory/+3V3_FLASH")
			(pintype "passive")
		)
	)
	(footprint "antmicro-footprints:C_0402_1005Metric"
		(layer "B.Cu")
		(at 94.95 96.5 -90)
		(descr "Capacitor SMD 0402")
		(tags "capacitor SMD 0402")
		(property "Reference" "C130"
			(at 1.15 -3.35 90)
			(layer "B.SilkS")
			(effects
				(font
					(size 0.7 0.7)
					(thickness 0.15)
				)
				(justify right bottom mirror)
			)
		)
		(property "Value" "C_100n_0402"
			(at -1.022927 -2.155213 90)
			(layer "B.Fab")
			(hide yes)
			(effects
				(font
					(size 0.7 0.7)
					(thickness 0.15)
				)
				(justify left bottom mirror)
			)
		)
		(property "Datasheet" "https://www.murata.com/products/productdetail?partno=GRM155R61H104KE14%23"
			(at 0 0 90)
			(layer "B.Fab")
			(hide yes)
			(effects
				(font
					(size 1.27 1.27)
					(thickness 0.15)
				)
				(justify mirror)
			)
		)
		(property "Description" "SMD Multilayer Ceramic Capacitor, 0.1 µF, 50 V, 0402 [1005 Metric], ± 10%, X5R, GRM Series"
			(at 0 0 90)
			(layer "B.Fab")
			(hide yes)
			(effects
				(font
					(size 1.27 1.27)
					(thickness 0.15)
				)
				(justify mirror)
			)
		)
		(property "MPN" "GRM155R61H104KE14D"
			(at 0 0 270)
			(unlocked yes)
			(layer "B.Fab")
			(hide yes)
			(effects
				(font
					(size 1 1)
					(thickness 0.15)
				)
				(justify mirror)
			)
		)
		(property "Val" "100n"
			(at 0 0 270)
			(unlocked yes)
			(layer "B.Fab")
			(hide yes)
			(effects
				(font
					(size 1 1)
					(thickness 0.15)
				)
				(justify mirror)
			)
		)
		(property "Voltage" "50V"
			(at 0 0 270)
			(unlocked yes)
			(layer "B.Fab")
			(hide yes)
			(effects
				(font
					(size 1 1)
					(thickness 0.15)
				)
				(justify mirror)
			)
		)
		(property "Dielectric" "X5R"
			(at 0 0 270)
			(unlocked yes)
			(layer "B.Fab")
			(hide yes)
			(effects
				(font
					(size 1 1)
					(thickness 0.15)
				)
				(justify mirror)
			)
		)
		(property "Manufacturer" "Murata"
			(at 0 0 270)
			(unlocked yes)
			(layer "B.Fab")
			(hide yes)
			(effects
				(font
					(size 1 1)
					(thickness 0.15)
				)
				(justify mirror)
			)
		)
		(property "License" "Apache-2.0"
			(at 0 0 270)
			(unlocked yes)
			(layer "B.Fab")
			(hide yes)
			(effects
				(font
					(size 1 1)
					(thickness 0.15)
				)
				(justify mirror)
			)
		)
		(property "Author" "Antmicro"
			(at 0 0 270)
			(unlocked yes)
			(layer "B.Fab")
			(hide yes)
			(effects
				(font
					(size 1 1)
					(thickness 0.15)
				)
				(justify mirror)
			)
		)
		(sheetname "/X710-AT2 power/")
		(sheetfile "x710-at2-power.kicad_sch")
		(attr smd)
		(fp_rect
			(start -0.925 0.47)
			(end 0.925 -0.47)
			(stroke
				(width 0.05)
				(type default)
			)
			(fill no)
			(layer "B.CrtYd")
		)
		(fp_line
			(start -0.494 0.25)
			(end 0.504 0.25)
			(stroke
				(width 0.15)
				(type solid)
			)
			(layer "B.Fab")
		)
		(fp_line
			(start 0.504 0.25)
			(end 0.504 -0.248)
			(stroke
				(width 0.15)
				(type solid)
			)
			(layer "B.Fab")
		)
		(fp_line
			(start -0.494 -0.248)
			(end -0.494 0.25)
			(stroke
				(width 0.15)
				(type solid)
			)
			(layer "B.Fab")
		)
		(fp_line
			(start 0.504 -0.248)
			(end -0.494 -0.248)
			(stroke
				(width 0.15)
				(type solid)
			)
			(layer "B.Fab")
		)
		(pad "1" smd roundrect
			(at -0.48 0 270)
			(size 0.59 0.64)
			(layers "B.Cu" "B.Mask" "B.Paste")
			(roundrect_rratio 0.25)
			(net 28 "GND")
			(pintype "passive")
		)
		(pad "2" smd roundrect
			(at 0.48 0 270)
			(size 0.59 0.64)
			(layers "B.Cu" "B.Mask" "B.Paste")
			(roundrect_rratio 0.25)
			(net 7 "+3V3")
			(pintype "passive")
		)
	)
	(footprint "antmicro-footprints:C_0402_1005Metric"
		(layer "B.Cu")
		(at 89.225 100.15 90)
		(descr "Capacitor SMD 0402")
		(tags "capacitor SMD 0402")
		(property "Reference" "C90"
			(at 9.87 -0.39901 90)
			(layer "B.SilkS")
			(effects
				(font
					(size 0.7 0.7)
					(thickness 0.15)
				)
				(justify right top mirror)
			)
		)
		(property "Value" "C_1u_25V_0402"
			(at -1.022927 -2.155213 90)
			(layer "B.Fab")
			(hide yes)
			(effects
				(font
					(size 0.7 0.7)
					(thickness 0.15)
				)
				(justify right top mirror)
			)
		)
		(property "Datasheet" "https://www.murata.com/products/productdetail?partno=GRM155R61E105KE11%23"
			(at 0 0 90)
			(layer "B.Fab")
			(hide yes)
			(effects
				(font
					(size 1.27 1.27)
					(thickness 0.15)
				)
				(justify mirror)
			)
		)
		(property "Description" "SMD Multilayer Ceramic Capacitor, 1 µF, 25 V, 0402 [1005 Metric], ± 10%, X5R, GRM Series"
			(at 0 0 90)
			(layer "B.Fab")
			(hide yes)
			(effects
				(font
					(size 1.27 1.27)
					(thickness 0.15)
				)
				(justify mirror)
			)
		)
		(property "MPN" "GRM155R61E105KE11J"
			(at 0 0 90)
			(unlocked yes)
			(layer "B.Fab")
			(hide yes)
			(effects
				(font
					(size 1 1)
					(thickness 0.15)
				)
				(justify mirror)
			)
		)
		(property "Manufacturer" "Murata"
			(at 0 0 90)
			(unlocked yes)
			(layer "B.Fab")
			(hide yes)
			(effects
				(font
					(size 1 1)
					(thickness 0.15)
				)
				(justify mirror)
			)
		)
		(property "License" "Apache-2.0"
			(at 0 0 90)
			(unlocked yes)
			(layer "B.Fab")
			(hide yes)
			(effects
				(font
					(size 1 1)
					(thickness 0.15)
				)
				(justify mirror)
			)
		)
		(property "Author" "Antmicro"
			(at 0 0 90)
			(unlocked yes)
			(layer "B.Fab")
			(hide yes)
			(effects
				(font
					(size 1 1)
					(thickness 0.15)
				)
				(justify mirror)
			)
		)
		(property "Val" "1u"
			(at 0 0 90)
			(unlocked yes)
			(layer "B.Fab")
			(hide yes)
			(effects
				(font
					(size 1 1)
					(thickness 0.15)
				)
				(justify mirror)
			)
		)
		(property "Voltage" "25V"
			(at 0 0 90)
			(unlocked yes)
			(layer "B.Fab")
			(hide yes)
			(effects
				(font
					(size 1 1)
					(thickness 0.15)
				)
				(justify mirror)
			)
		)
		(property "Dielectric" "X5R"
			(at 0 0 90)
			(unlocked yes)
			(layer "B.Fab")
			(hide yes)
			(effects
				(font
					(size 1 1)
					(thickness 0.15)
				)
				(justify mirror)
			)
		)
		(sheetname "/X710-AT2 power/")
		(sheetfile "x710-at2-power.kicad_sch")
		(attr smd)
		(fp_rect
			(start -0.925 0.47)
			(end 0.925 -0.47)
			(stroke
				(width 0.05)
				(type default)
			)
			(fill no)
			(layer "B.CrtYd")
		)
		(fp_line
			(start 0.504 -0.248)
			(end -0.494 -0.248)
			(stroke
				(width 0.15)
				(type solid)
			)
			(layer "B.Fab")
		)
		(fp_line
			(start -0.494 -0.248)
			(end -0.494 0.25)
			(stroke
				(width 0.15)
				(type solid)
			)
			(layer "B.Fab")
		)
		(fp_line
			(start 0.504 0.25)
			(end 0.504 -0.248)
			(stroke
				(width 0.15)
				(type solid)
			)
			(layer "B.Fab")
		)
		(fp_line
			(start -0.494 0.25)
			(end 0.504 0.25)
			(stroke
				(width 0.15)
				(type solid)
			)
			(layer "B.Fab")
		)
		(pad "1" smd roundrect
			(at -0.48 0 90)
			(size 0.59 0.64)
			(layers "B.Cu" "B.Mask" "B.Paste")
			(roundrect_rratio 0.25)
			(net 28 "GND")
			(pintype "passive")
		)
		(pad "2" smd roundrect
			(at 0.48 0 90)
			(size 0.59 0.64)
			(layers "B.Cu" "B.Mask" "B.Paste")
			(roundrect_rratio 0.25)
			(net 1 "VCCA")
			(pintype "passive")
		)
	)
	(footprint "antmicro-footprints:C_0402_1005Metric"
		(layer "B.Cu")
		(at 76.95 101.35 180)
		(descr "Capacitor SMD 0402")
		(tags "capacitor SMD 0402")
		(property "Reference" "C102"
			(at 0.85 -0.4 0)
			(layer "B.SilkS")
			(effects
				(font
					(size 0.7 0.7)
					(thickness 0.15)
				)
				(justify left bottom mirror)
			)
		)
		(property "Value" "C_1u_25V_0402"
			(at -1.022927 -2.155213 0)
			(layer "B.Fab")
			(hide yes)
			(effects
				(font
					(size 0.7 0.7)
					(thickness 0.15)
				)
				(justify left bottom mirror)
			)
		)
		(property "Datasheet" "https://www.murata.com/products/productdetail?partno=GRM155R61E105KE11%23"
			(at 0 0 0)
			(layer "B.Fab")
			(hide yes)
			(effects
				(font
					(size 1.27 1.27)
					(thickness 0.15)
				)
				(justify mirror)
			)
		)
		(property "Description" "SMD Multilayer Ceramic Capacitor, 1 µF, 25 V, 0402 [1005 Metric], ± 10%, X5R, GRM Series"
			(at 0 0 0)
			(layer "B.Fab")
			(hide yes)
			(effects
				(font
					(size 1.27 1.27)
					(thickness 0.15)
				)
				(justify mirror)
			)
		)
		(property "MPN" "GRM155R61E105KE11J"
			(at 0 0 180)
			(unlocked yes)
			(layer "B.Fab")
			(hide yes)
			(effects
				(font
					(size 1 1)
					(thickness 0.15)
				)
				(justify mirror)
			)
		)
		(property "Manufacturer" "Murata"
			(at 0 0 180)
			(unlocked yes)
			(layer "B.Fab")
			(hide yes)
			(effects
				(font
					(size 1 1)
					(thickness 0.15)
				)
				(justify mirror)
			)
		)
		(property "License" "Apache-2.0"
			(at 0 0 180)
			(unlocked yes)
			(layer "B.Fab")
			(hide yes)
			(effects
				(font
					(size 1 1)
					(thickness 0.15)
				)
				(justify mirror)
			)
		)
		(property "Author" "Antmicro"
			(at 0 0 180)
			(unlocked yes)
			(layer "B.Fab")
			(hide yes)
			(effects
				(font
					(size 1 1)
					(thickness 0.15)
				)
				(justify mirror)
			)
		)
		(property "Val" "1u"
			(at 0 0 180)
			(unlocked yes)
			(layer "B.Fab")
			(hide yes)
			(effects
				(font
					(size 1 1)
					(thickness 0.15)
				)
				(justify mirror)
			)
		)
		(property "Voltage" "25V"
			(at 0 0 180)
			(unlocked yes)
			(layer "B.Fab")
			(hide yes)
			(effects
				(font
					(size 1 1)
					(thickness 0.15)
				)
				(justify mirror)
			)
		)
		(property "Dielectric" "X5R"
			(at 0 0 180)
			(unlocked yes)
			(layer "B.Fab")
			(hide yes)
			(effects
				(font
					(size 1 1)
					(thickness 0.15)
				)
				(justify mirror)
			)
		)
		(sheetname "/X710-AT2 power/")
		(sheetfile "x710-at2-power.kicad_sch")
		(attr smd)
		(fp_rect
			(start -0.925 0.47)
			(end 0.925 -0.47)
			(stroke
				(width 0.05)
				(type default)
			)
			(fill no)
			(layer "B.CrtYd")
		)
		(fp_line
			(start 0.504 0.25)
			(end 0.504 -0.248)
			(stroke
				(width 0.15)
				(type solid)
			)
			(layer "B.Fab")
		)
		(fp_line
			(start 0.504 -0.248)
			(end -0.494 -0.248)
			(stroke
				(width 0.15)
				(type solid)
			)
			(layer "B.Fab")
		)
		(fp_line
			(start -0.494 0.25)
			(end 0.504 0.25)
			(stroke
				(width 0.15)
				(type solid)
			)
			(layer "B.Fab")
		)
		(fp_line
			(start -0.494 -0.248)
			(end -0.494 0.25)
			(stroke
				(width 0.15)
				(type solid)
			)
			(layer "B.Fab")
		)
		(pad "1" smd roundrect
			(at -0.48 0 180)
			(size 0.59 0.64)
			(layers "B.Cu" "B.Mask" "B.Paste")
			(roundrect_rratio 0.25)
			(net 28 "GND")
			(pintype "passive")
		)
		(pad "2" smd roundrect
			(at 0.48 0 180)
			(size 0.59 0.64)
			(layers "B.Cu" "B.Mask" "B.Paste")
			(roundrect_rratio 0.25)
			(net 18 "+1V88")
			(pintype "passive")
		)
	)
	(footprint "antmicro-footprints:C_0603_1608Metric"
		(layer "B.Cu")
		(at 68.45 98.45 90)
		(descr "Capacitor SMD 0603")
		(tags "capacitor 0603")
		(property "Reference" "C100"
			(at -1.4 0.75 90)
			(layer "B.SilkS")
			(effects
				(font
					(size 0.7 0.7)
					(thickness 0.15)
				)
				(justify right top mirror)
			)
		)
		(property "Value" "C_10u_10V_X7R_0603"
			(at -1.42757 -1.770288 90)
			(layer "B.Fab")
			(hide yes)
			(effects
				(font
					(size 0.7 0.7)
					(thickness 0.15)
				)
				(justify right top mirror)
			)
		)
		(property "Datasheet" "https://www.murata.com/products/productdetail?partno=GRM188Z71A106KA73%23"
			(at 0 0 90)
			(layer "B.Fab")
			(hide yes)
			(effects
				(font
					(size 1.27 1.27)
					(thickness 0.15)
				)
				(justify mirror)
			)
		)
		(property "Description" "SMD Multilayer Ceramic Capacitor,  10µF, 10V, 0603, ±10%, X7R"
			(at 0 0 90)
			(layer "B.Fab")
			(hide yes)
			(effects
				(font
					(size 1.27 1.27)
					(thickness 0.15)
				)
				(justify mirror)
			)
		)
		(property "MPN" "GRM188Z71A106KA73D"
			(at 0 0 90)
			(unlocked yes)
			(layer "B.Fab")
			(hide yes)
			(effects
				(font
					(size 1 1)
					(thickness 0.15)
				)
				(justify mirror)
			)
		)
		(property "Val" "10u"
			(at 0 0 90)
			(unlocked yes)
			(layer "B.Fab")
			(hide yes)
			(effects
				(font
					(size 1 1)
					(thickness 0.15)
				)
				(justify mirror)
			)
		)
		(property "Voltage" "10V"
			(at 0 0 90)
			(unlocked yes)
			(layer "B.Fab")
			(hide yes)
			(effects
				(font
					(size 1 1)
					(thickness 0.15)
				)
				(justify mirror)
			)
		)
		(property "Dielectric" "X7R"
			(at 0 0 90)
			(unlocked yes)
			(layer "B.Fab")
			(hide yes)
			(effects
				(font
					(size 1 1)
					(thickness 0.15)
				)
				(justify mirror)
			)
		)
		(property "Manufacturer" "Murata"
			(at 0 0 90)
			(unlocked yes)
			(layer "B.Fab")
			(hide yes)
			(effects
				(font
					(size 1 1)
					(thickness 0.15)
				)
				(justify mirror)
			)
		)
		(property "License" "Apache-2.0"
			(at 0 0 90)
			(unlocked yes)
			(layer "B.Fab")
			(hide yes)
			(effects
				(font
					(size 1 1)
					(thickness 0.15)
				)
				(justify mirror)
			)
		)
		(property "Author" "Antmicro"
			(at 0 0 90)
			(unlocked yes)
			(layer "B.Fab")
			(hide yes)
			(effects
				(font
					(size 1 1)
					(thickness 0.15)
				)
				(justify mirror)
			)
		)
		(sheetname "/X710-AT2 power/")
		(sheetfile "x710-at2-power.kicad_sch")
		(attr smd)
		(fp_line
			(start -0.15 -0.4)
			(end 0.15 -0.4)
			(stroke
				(width 0.15)
				(type solid)
			)
			(layer "B.SilkS")
		)
		(fp_line
			(start -0.15 0.4)
			(end 0.15 0.4)
			(stroke
				(width 0.15)
				(type solid)
			)
			(layer "B.SilkS")
		)
		(fp_rect
			(start -1.25 0.65)
			(end 1.25 -0.65)
			(stroke
				(width 0.05)
				(type solid)
			)
			(fill no)
			(layer "B.CrtYd")
		)
		(fp_rect
			(start -0.8 0.4)
			(end 0.8 -0.4)
			(stroke
				(width 0.15)
				(type solid)
			)
			(fill no)
			(layer "B.Fab")
		)
		(pad "1" smd roundrect
			(at -0.7 0 90)
			(size 0.8 1)
			(layers "B.Cu" "B.Mask" "B.Paste")
			(roundrect_rratio 0.2)
			(net 28 "GND")
			(pintype "passive")
		)
		(pad "2" smd roundrect
			(at 0.7 0 90)
			(size 0.8 1)
			(layers "B.Cu" "B.Mask" "B.Paste")
			(roundrect_rratio 0.2)
			(net 18 "+1V88")
			(pintype "passive")
		)
	)
	(footprint "antmicro-footprints:C_0402_1005Metric"
		(layer "B.Cu")
		(at 81.32 105.08 90)
		(descr "Capacitor SMD 0402")
		(tags "capacitor SMD 0402")
		(property "Reference" "C85"
			(at -11.81 0.1475 90)
			(layer "B.SilkS")
			(effects
				(font
					(size 0.7 0.7)
					(thickness 0.15)
				)
				(justify right top mirror)
			)
		)
		(property "Value" "C_1u_25V_0402"
			(at -1.022927 -2.155213 90)
			(layer "B.Fab")
			(hide yes)
			(effects
				(font
					(size 0.7 0.7)
					(thickness 0.15)
				)
				(justify right top mirror)
			)
		)
		(property "Datasheet" "https://www.murata.com/products/productdetail?partno=GRM155R61E105KE11%23"
			(at 0 0 90)
			(layer "B.Fab")
			(hide yes)
			(effects
				(font
					(size 1.27 1.27)
					(thickness 0.15)
				)
				(justify mirror)
			)
		)
		(property "Description" "SMD Multilayer Ceramic Capacitor, 1 µF, 25 V, 0402 [1005 Metric], ± 10%, X5R, GRM Series"
			(at 0 0 90)
			(layer "B.Fab")
			(hide yes)
			(effects
				(font
					(size 1.27 1.27)
					(thickness 0.15)
				)
				(justify mirror)
			)
		)
		(property "MPN" "GRM155R61E105KE11J"
			(at 0 0 90)
			(unlocked yes)
			(layer "B.Fab")
			(hide yes)
			(effects
				(font
					(size 1 1)
					(thickness 0.15)
				)
				(justify mirror)
			)
		)
		(property "Manufacturer" "Murata"
			(at 0 0 90)
			(unlocked yes)
			(layer "B.Fab")
			(hide yes)
			(effects
				(font
					(size 1 1)
					(thickness 0.15)
				)
				(justify mirror)
			)
		)
		(property "License" "Apache-2.0"
			(at 0 0 90)
			(unlocked yes)
			(layer "B.Fab")
			(hide yes)
			(effects
				(font
					(size 1 1)
					(thickness 0.15)
				)
				(justify mirror)
			)
		)
		(property "Author" "Antmicro"
			(at 0 0 90)
			(unlocked yes)
			(layer "B.Fab")
			(hide yes)
			(effects
				(font
					(size 1 1)
					(thickness 0.15)
				)
				(justify mirror)
			)
		)
		(property "Val" "1u"
			(at 0 0 90)
			(unlocked yes)
			(layer "B.Fab")
			(hide yes)
			(effects
				(font
					(size 1 1)
					(thickness 0.15)
				)
				(justify mirror)
			)
		)
		(property "Voltage" "25V"
			(at 0 0 90)
			(unlocked yes)
			(layer "B.Fab")
			(hide yes)
			(effects
				(font
					(size 1 1)
					(thickness 0.15)
				)
				(justify mirror)
			)
		)
		(property "Dielectric" "X5R"
			(at 0 0 90)
			(unlocked yes)
			(layer "B.Fab")
			(hide yes)
			(effects
				(font
					(size 1 1)
					(thickness 0.15)
				)
				(justify mirror)
			)
		)
		(sheetname "/X710-AT2 power/")
		(sheetfile "x710-at2-power.kicad_sch")
		(attr smd)
		(fp_rect
			(start -0.925 0.47)
			(end 0.925 -0.47)
			(stroke
				(width 0.05)
				(type default)
			)
			(fill no)
			(layer "B.CrtYd")
		)
		(fp_line
			(start 0.504 -0.248)
			(end -0.494 -0.248)
			(stroke
				(width 0.15)
				(type solid)
			)
			(layer "B.Fab")
		)
		(fp_line
			(start -0.494 -0.248)
			(end -0.494 0.25)
			(stroke
				(width 0.15)
				(type solid)
			)
			(layer "B.Fab")
		)
		(fp_line
			(start 0.504 0.25)
			(end 0.504 -0.248)
			(stroke
				(width 0.15)
				(type solid)
			)
			(layer "B.Fab")
		)
		(fp_line
			(start -0.494 0.25)
			(end 0.504 0.25)
			(stroke
				(width 0.15)
				(type solid)
			)
			(layer "B.Fab")
		)
		(pad "1" smd roundrect
			(at -0.48 0 90)
			(size 0.59 0.64)
			(layers "B.Cu" "B.Mask" "B.Paste")
			(roundrect_rratio 0.25)
			(net 28 "GND")
			(pintype "passive")
		)
		(pad "2" smd roundrect
			(at 0.48 0 90)
			(size 0.59 0.64)
			(layers "B.Cu" "B.Mask" "B.Paste")
			(roundrect_rratio 0.25)
			(net 6 "DVDD")
			(pintype "passive")
		)
	)
	(footprint "antmicro-footprints:R_0402_1005Metric"
		(layer "B.Cu")
		(at 94.48 145.34 90)
		(descr "Resistor SMD 0402")
		(tags "resistor SMD 0402")
		(property "Reference" "R41"
			(at 0.71 -0.38 90)
			(layer "B.SilkS")
			(effects
				(font
					(size 0.7 0.7)
					(thickness 0.15)
				)
				(justify right top mirror)
			)
		)
		(property "Value" "R_220R_0402"
			(at -1.011843 -1.772046 90)
			(layer "B.Fab")
			(hide yes)
			(effects
				(font
					(size 0.7 0.7)
					(thickness 0.15)
				)
				(justify right top mirror)
			)
		)
		(property "Datasheet" "https://www.bourns.com/docs/product-datasheets/cr.pdf"
			(at 0 0 90)
			(layer "B.Fab")
			(hide yes)
			(effects
				(font
					(size 1.27 1.27)
					(thickness 0.15)
				)
				(justify mirror)
			)
		)
		(property "Description" "SMD Chip Resistor, 220 ohm, ± 1%, 62.5 mW, 0402 [1005 Metric], Thick Film, General Purpose"
			(at 0 0 90)
			(layer "B.Fab")
			(hide yes)
			(effects
				(font
					(size 1.27 1.27)
					(thickness 0.15)
				)
				(justify mirror)
			)
		)
		(property "MPN" "CR0402-FX-2200GLF"
			(at 0 0 90)
			(unlocked yes)
			(layer "B.Fab")
			(hide yes)
			(effects
				(font
					(size 1 1)
					(thickness 0.15)
				)
				(justify mirror)
			)
		)
		(property "Manufacturer" "Bourns"
			(at 0 0 90)
			(unlocked yes)
			(layer "B.Fab")
			(hide yes)
			(effects
				(font
					(size 1 1)
					(thickness 0.15)
				)
				(justify mirror)
			)
		)
		(property "License" "Apache-2.0"
			(at 0 0 90)
			(unlocked yes)
			(layer "B.Fab")
			(hide yes)
			(effects
				(font
					(size 1 1)
					(thickness 0.15)
				)
				(justify mirror)
			)
		)
		(property "Author" "Antmicro"
			(at 0 0 90)
			(unlocked yes)
			(layer "B.Fab")
			(hide yes)
			(effects
				(font
					(size 1 1)
					(thickness 0.15)
				)
				(justify mirror)
			)
		)
		(property "Val" "220R"
			(at 0 0 90)
			(unlocked yes)
			(layer "B.Fab")
			(hide yes)
			(effects
				(font
					(size 1 1)
					(thickness 0.15)
				)
				(justify mirror)
			)
		)
		(property "Tolerance" "1%"
			(at 0 0 90)
			(unlocked yes)
			(layer "B.Fab")
			(hide yes)
			(effects
				(font
					(size 1 1)
					(thickness 0.15)
				)
				(justify mirror)
			)
		)
		(sheetname "/2xRJ45/")
		(sheetfile "2xrj45.kicad_sch")
		(attr smd)
		(fp_rect
			(start -0.925 0.47)
			(end 0.925 -0.47)
			(stroke
				(width 0.05)
				(type default)
			)
			(fill no)
			(layer "B.CrtYd")
		)
		(fp_rect
			(start -0.5 0.25)
			(end 0.5 -0.25)
			(stroke
				(width 0.15)
				(type solid)
			)
			(fill no)
			(layer "B.Fab")
		)
		(pad "1" smd roundrect
			(at -0.48 0 90)
			(size 0.59 0.64)
			(layers "B.Cu" "B.Mask" "B.Paste")
			(roundrect_rratio 0.25)
			(net 66 "Net-(J6-LED_GRN-)")
			(pintype "passive")
		)
		(pad "2" smd roundrect
			(at 0.48 0 90)
			(size 0.59 0.64)
			(layers "B.Cu" "B.Mask" "B.Paste")
			(roundrect_rratio 0.25)
			(net 88 "/2xRJ45/~{P1_LED_ACT}")
			(pintype "passive")
		)
	)
	(footprint "antmicro-footprints:TP_SMD_0.75mm"
		(layer "B.Cu")
		(at 103.55 108.7)
		(property "Reference" "TP7"
			(at -0.28 2.5 90)
			(layer "B.SilkS")
			(effects
				(font
					(size 0.7 0.7)
					(thickness 0.15)
				)
				(justify right top mirror)
			)
		)
		(property "Value" "TP_0.75mm_SMD"
			(at 0 -1.2 0)
			(layer "B.Fab")
			(hide yes)
			(effects
				(font
					(size 0.7 0.7)
					(thickness 0.15)
				)
				(justify right top mirror)
			)
		)
		(property "Description" "SMT test point"
			(at 0 0 0)
			(layer "B.Fab")
			(hide yes)
			(effects
				(font
					(size 1.27 1.27)
					(thickness 0.15)
				)
				(justify mirror)
			)
		)
		(property "MPN" ""
			(at 0 0 0)
			(unlocked yes)
			(layer "B.Fab")
			(hide yes)
			(effects
				(font
					(size 1 1)
					(thickness 0.15)
				)
				(justify mirror)
			)
		)
		(property "Manufacturer" ""
			(at 0 0 0)
			(unlocked yes)
			(layer "B.Fab")
			(hide yes)
			(effects
				(font
					(size 1 1)
					(thickness 0.15)
				)
				(justify mirror)
			)
		)
		(property "Author" "Antmicro"
			(at 0 0 0)
			(unlocked yes)
			(layer "B.Fab")
			(hide yes)
			(effects
				(font
					(size 1 1)
					(thickness 0.15)
				)
				(justify mirror)
			)
		)
		(property "License" "Apache-2.0"
			(at 0 0 0)
			(unlocked yes)
			(layer "B.Fab")
			(hide yes)
			(effects
				(font
					(size 1 1)
					(thickness 0.15)
				)
				(justify mirror)
			)
		)
		(sheetname "/X710-AT2 Misc/")
		(sheetfile "x710-at2-mics.kicad_sch")
		(attr exclude_from_pos_files exclude_from_bom)
		(fp_circle
			(center 0 0)
			(end 0.475 0)
			(stroke
				(width 0.05)
				(type default)
			)
			(fill no)
			(layer "B.CrtYd")
		)
		(pad "1" smd circle
			(at 0 0)
			(size 0.75 0.75)
			(layers "B.Cu" "B.Mask")
			(net 362 "/X710-AT2 Misc/NCSI.RXD_0")
			(pinfunction "1")
			(pintype "passive")
		)
	)
	(footprint "antmicro-footprints:R_0402_1005Metric"
		(layer "B.Cu")
		(at 92 111.15 -90)
		(descr "Resistor SMD 0402")
		(tags "resistor SMD 0402")
		(property "Reference" "R70"
			(at -1.13 -1.32 90)
			(layer "B.SilkS")
			(effects
				(font
					(size 0.7 0.7)
					(thickness 0.15)
				)
				(justify left bottom mirror)
			)
		)
		(property "Value" "R_0R_0402"
			(at -1.011843 -1.772046 90)
			(layer "B.Fab")
			(hide yes)
			(effects
				(font
					(size 0.7 0.7)
					(thickness 0.15)
				)
				(justify left bottom mirror)
			)
		)
		(property "Datasheet" "https://industrial.panasonic.com/cdbs/www-data/pdf/RDA0000/AOA0000C301.pdf"
			(at 0 0 90)
			(layer "B.Fab")
			(hide yes)
			(effects
				(font
					(size 1.27 1.27)
					(thickness 0.15)
				)
				(justify mirror)
			)
		)
		(property "Description" "SMD Chip Resistor, Jumper, 0 ohm, 100 mW, 0402 [1005 Metric], Thick Film, General Purpose"
			(at 0 0 90)
			(layer "B.Fab")
			(hide yes)
			(effects
				(font
					(size 1.27 1.27)
					(thickness 0.15)
				)
				(justify mirror)
			)
		)
		(property "MPN" "ERJ2GE0R00X"
			(at 0 0 270)
			(unlocked yes)
			(layer "B.Fab")
			(hide yes)
			(effects
				(font
					(size 1 1)
					(thickness 0.15)
				)
				(justify mirror)
			)
		)
		(property "Manufacturer" "Panasonic"
			(at 0 0 270)
			(unlocked yes)
			(layer "B.Fab")
			(hide yes)
			(effects
				(font
					(size 1 1)
					(thickness 0.15)
				)
				(justify mirror)
			)
		)
		(property "License" "Apache-2.0"
			(at 0 0 270)
			(unlocked yes)
			(layer "B.Fab")
			(hide yes)
			(effects
				(font
					(size 1 1)
					(thickness 0.15)
				)
				(justify mirror)
			)
		)
		(property "Author" "Antmicro"
			(at 0 0 270)
			(unlocked yes)
			(layer "B.Fab")
			(hide yes)
			(effects
				(font
					(size 1 1)
					(thickness 0.15)
				)
				(justify mirror)
			)
		)
		(property "Val" "0R"
			(at 0 0 270)
			(unlocked yes)
			(layer "B.Fab")
			(hide yes)
			(effects
				(font
					(size 1 1)
					(thickness 0.15)
				)
				(justify mirror)
			)
		)
		(property "Tolerance" "~"
			(at 0 0 270)
			(unlocked yes)
			(layer "B.Fab")
			(hide yes)
			(effects
				(font
					(size 1 1)
					(thickness 0.15)
				)
				(justify mirror)
			)
		)
		(property "Current" "1A"
			(at 0 0 270)
			(unlocked yes)
			(layer "B.Fab")
			(hide yes)
			(effects
				(font
					(size 1 1)
					(thickness 0.15)
				)
				(justify mirror)
			)
		)
		(sheetname "/X710-AT2 10GbE/")
		(sheetfile "x710-at2-10gbe.kicad_sch")
		(attr smd)
		(fp_rect
			(start -0.925 0.47)
			(end 0.925 -0.47)
			(stroke
				(width 0.05)
				(type default)
			)
			(fill no)
			(layer "B.CrtYd")
		)
		(fp_rect
			(start -0.5 0.25)
			(end 0.5 -0.25)
			(stroke
				(width 0.15)
				(type solid)
			)
			(fill no)
			(layer "B.Fab")
		)
		(pad "1" smd roundrect
			(at -0.48 0 270)
			(size 0.59 0.64)
			(layers "B.Cu" "B.Mask" "B.Paste")
			(roundrect_rratio 0.25)
			(net 142 "/X710-AT2 10GbE/~{P0_INT}")
			(pintype "passive")
		)
		(pad "2" smd roundrect
			(at 0.48 0 270)
			(size 0.59 0.64)
			(layers "B.Cu" "B.Mask" "B.Paste")
			(roundrect_rratio 0.25)
			(net 198 "/X710-AT2 10GbE/~{P0_INT_R}")
			(pintype "passive")
		)
	)
	(footprint "antmicro-footprints:C_0402_1005Metric"
		(layer "B.Cu")
		(at 97.479998 145.34 -90)
		(descr "Capacitor SMD 0402")
		(tags "capacitor SMD 0402")
		(property "Reference" "C60"
			(at -2.96 -0.480002 90)
			(layer "B.SilkS")
			(effects
				(font
					(size 0.7 0.7)
					(thickness 0.15)
				)
				(justify left bottom mirror)
			)
		)
		(property "Value" "C_470p_0402"
			(at -1.022927 -2.155213 90)
			(layer "B.Fab")
			(hide yes)
			(effects
				(font
					(size 0.7 0.7)
					(thickness 0.15)
				)
				(justify left bottom mirror)
			)
		)
		(property "Datasheet" "https://www.passivecomponent.com/wp-content/uploads/datasheet/WTC_MLCC_General_Purpose.pdf"
			(at 0 0 90)
			(layer "B.Fab")
			(hide yes)
			(effects
				(font
					(size 1.27 1.27)
					(thickness 0.15)
				)
				(justify mirror)
			)
		)
		(property "Description" "SMD Multilayer Ceramic Capacitor, General Purpose, 470 pF, 25 V, 0402 [1005 Metric], ± 10%, X7R"
			(at 0 0 90)
			(layer "B.Fab")
			(hide yes)
			(effects
				(font
					(size 1.27 1.27)
					(thickness 0.15)
				)
				(justify mirror)
			)
		)
		(property "MPN" "0402B471K250CT"
			(at 0 0 270)
			(unlocked yes)
			(layer "B.Fab")
			(hide yes)
			(effects
				(font
					(size 1 1)
					(thickness 0.15)
				)
				(justify mirror)
			)
		)
		(property "Manufacturer" "Walsin"
			(at 0 0 270)
			(unlocked yes)
			(layer "B.Fab")
			(hide yes)
			(effects
				(font
					(size 1 1)
					(thickness 0.15)
				)
				(justify mirror)
			)
		)
		(property "License" "Apache-2.0"
			(at 0 0 270)
			(unlocked yes)
			(layer "B.Fab")
			(hide yes)
			(effects
				(font
					(size 1 1)
					(thickness 0.15)
				)
				(justify mirror)
			)
		)
		(property "Author" "Antmicro"
			(at 0 0 270)
			(unlocked yes)
			(layer "B.Fab")
			(hide yes)
			(effects
				(font
					(size 1 1)
					(thickness 0.15)
				)
				(justify mirror)
			)
		)
		(property "Val" "470p"
			(at 0 0 270)
			(unlocked yes)
			(layer "B.Fab")
			(hide yes)
			(effects
				(font
					(size 1 1)
					(thickness 0.15)
				)
				(justify mirror)
			)
		)
		(property "Voltage" "25V"
			(at 0 0 270)
			(unlocked yes)
			(layer "B.Fab")
			(hide yes)
			(effects
				(font
					(size 1 1)
					(thickness 0.15)
				)
				(justify mirror)
			)
		)
		(property "Dielectric" "X7R"
			(at 0 0 270)
			(unlocked yes)
			(layer "B.Fab")
			(hide yes)
			(effects
				(font
					(size 1 1)
					(thickness 0.15)
				)
				(justify mirror)
			)
		)
		(sheetname "/2xRJ45/")
		(sheetfile "2xrj45.kicad_sch")
		(attr smd)
		(fp_rect
			(start -0.925 0.47)
			(end 0.925 -0.47)
			(stroke
				(width 0.05)
				(type default)
			)
			(fill no)
			(layer "B.CrtYd")
		)
		(fp_line
			(start -0.494 0.25)
			(end 0.504 0.25)
			(stroke
				(width 0.15)
				(type solid)
			)
			(layer "B.Fab")
		)
		(fp_line
			(start 0.504 0.25)
			(end 0.504 -0.248)
			(stroke
				(width 0.15)
				(type solid)
			)
			(layer "B.Fab")
		)
		(fp_line
			(start -0.494 -0.248)
			(end -0.494 0.25)
			(stroke
				(width 0.15)
				(type solid)
			)
			(layer "B.Fab")
		)
		(fp_line
			(start 0.504 -0.248)
			(end -0.494 -0.248)
			(stroke
				(width 0.15)
				(type solid)
			)
			(layer "B.Fab")
		)
		(pad "1" smd roundrect
			(at -0.48 0 270)
			(size 0.59 0.64)
			(layers "B.Cu" "B.Mask" "B.Paste")
			(roundrect_rratio 0.25)
			(net 28 "GND")
			(pintype "passive")
		)
		(pad "2" smd roundrect
			(at 0.48 0 270)
			(size 0.59 0.64)
			(layers "B.Cu" "B.Mask" "B.Paste")
			(roundrect_rratio 0.25)
			(net 61 "Net-(J6-LED_YG_Y-)")
			(pintype "passive")
		)
	)
	(footprint "antmicro-footprints:TP_SMD_0.75mm"
		(layer "B.Cu")
		(at 103.55 107.2 90)
		(property "Reference" "TP6"
			(at 0.45 0.54 180)
			(layer "B.SilkS")
			(effects
				(font
					(size 0.7 0.7)
					(thickness 0.15)
				)
				(justify right top mirror)
			)
		)
		(property "Value" "TP_0.75mm_SMD"
			(at 0 -1.2 90)
			(layer "B.Fab")
			(hide yes)
			(effects
				(font
					(size 0.7 0.7)
					(thickness 0.15)
				)
				(justify right top mirror)
			)
		)
		(property "Description" "SMT test point"
			(at 0 0 90)
			(layer "B.Fab")
			(hide yes)
			(effects
				(font
					(size 1.27 1.27)
					(thickness 0.15)
				)
				(justify mirror)
			)
		)
		(property "MPN" ""
			(at 0 0 90)
			(unlocked yes)
			(layer "B.Fab")
			(hide yes)
			(effects
				(font
					(size 1 1)
					(thickness 0.15)
				)
				(justify mirror)
			)
		)
		(property "Manufacturer" ""
			(at 0 0 90)
			(unlocked yes)
			(layer "B.Fab")
			(hide yes)
			(effects
				(font
					(size 1 1)
					(thickness 0.15)
				)
				(justify mirror)
			)
		)
		(property "Author" "Antmicro"
			(at 0 0 90)
			(unlocked yes)
			(layer "B.Fab")
			(hide yes)
			(effects
				(font
					(size 1 1)
					(thickness 0.15)
				)
				(justify mirror)
			)
		)
		(property "License" "Apache-2.0"
			(at 0 0 90)
			(unlocked yes)
			(layer "B.Fab")
			(hide yes)
			(effects
				(font
					(size 1 1)
					(thickness 0.15)
				)
				(justify mirror)
			)
		)
		(sheetname "/X710-AT2 Misc/")
		(sheetfile "x710-at2-mics.kicad_sch")
		(attr exclude_from_pos_files exclude_from_bom)
		(fp_circle
			(center 0 0)
			(end 0.475 0)
			(stroke
				(width 0.05)
				(type default)
			)
			(fill no)
			(layer "B.CrtYd")
		)
		(pad "1" smd circle
			(at 0 0 90)
			(size 0.75 0.75)
			(layers "B.Cu" "B.Mask")
			(net 363 "/X710-AT2 Misc/NCSI.TXD_0")
			(pinfunction "1")
			(pintype "passive")
		)
	)
	(footprint "antmicro-footprints:R_0402_1005Metric"
		(layer "B.Cu")
		(at 102.08 90.164 180)
		(descr "Resistor SMD 0402")
		(tags "resistor SMD 0402")
		(property "Reference" "R123"
			(at -1.87 -2.736 0)
			(layer "B.SilkS")
			(effects
				(font
					(size 0.7 0.7)
					(thickness 0.15)
				)
				(justify left bottom mirror)
			)
		)
		(property "Value" "R_33R_0402"
			(at -1.011843 -1.772047 0)
			(layer "B.Fab")
			(hide yes)
			(effects
				(font
					(size 0.7 0.7)
					(thickness 0.15)
				)
				(justify left bottom mirror)
			)
		)
		(property "Datasheet" "https://www.bourns.com/docs/product-datasheets/cr.pdf"
			(at 0 0 0)
			(layer "B.Fab")
			(hide yes)
			(effects
				(font
					(size 1.27 1.27)
					(thickness 0.15)
				)
				(justify mirror)
			)
		)
		(property "Description" "SMD Chip Resistor, 33 ohm, ± 1%, 62.5 mW, 0402 [1005 Metric], Thick Film, General Purpose"
			(at 0 0 0)
			(layer "B.Fab")
			(hide yes)
			(effects
				(font
					(size 1.27 1.27)
					(thickness 0.15)
				)
				(justify mirror)
			)
		)
		(property "MPN" "CR0402-FX-33R0GLF"
			(at 0 0 0)
			(unlocked yes)
			(layer "B.Fab")
			(hide yes)
			(effects
				(font
					(size 1 1)
					(thickness 0.15)
				)
				(justify mirror)
			)
		)
		(property "Manufacturer" "Bourns"
			(at 0 0 0)
			(unlocked yes)
			(layer "B.Fab")
			(hide yes)
			(effects
				(font
					(size 1 1)
					(thickness 0.15)
				)
				(justify mirror)
			)
		)
		(property "License" "Apache-2.0"
			(at 0 0 0)
			(unlocked yes)
			(layer "B.Fab")
			(hide yes)
			(effects
				(font
					(size 1 1)
					(thickness 0.15)
				)
				(justify mirror)
			)
		)
		(property "Author" "Antmicro"
			(at 0 0 0)
			(unlocked yes)
			(layer "B.Fab")
			(hide yes)
			(effects
				(font
					(size 1 1)
					(thickness 0.15)
				)
				(justify mirror)
			)
		)
		(property "Val" "33R"
			(at 0 0 0)
			(unlocked yes)
			(layer "B.Fab")
			(hide yes)
			(effects
				(font
					(size 1 1)
					(thickness 0.15)
				)
				(justify mirror)
			)
		)
		(property "Tolerance" "1%"
			(at 0 0 0)
			(unlocked yes)
			(layer "B.Fab")
			(hide yes)
			(effects
				(font
					(size 1 1)
					(thickness 0.15)
				)
				(justify mirror)
			)
		)
		(sheetname "/X710-AT2 PCIe/")
		(sheetfile "x710-at2-pcie.kicad_sch")
		(attr smd exclude_from_pos_files exclude_from_bom dnp)
		(fp_rect
			(start -0.925 0.47)
			(end 0.925 -0.47)
			(stroke
				(width 0.05)
				(type default)
			)
			(fill no)
			(layer "B.CrtYd")
		)
		(fp_rect
			(start -0.5 0.25)
			(end 0.5 -0.25)
			(stroke
				(width 0.15)
				(type solid)
			)
			(fill no)
			(layer "B.Fab")
		)
		(pad "1" smd roundrect
			(at -0.48 0 180)
			(size 0.59 0.64)
			(layers "B.Cu" "B.Mask" "B.Paste")
			(roundrect_rratio 0.25)
			(net 407 "/X710-AT2 PCIe/GEN_CLK+")
			(pintype "passive")
		)
		(pad "2" smd roundrect
			(at 0.48 0 180)
			(size 0.59 0.64)
			(layers "B.Cu" "B.Mask" "B.Paste")
			(roundrect_rratio 0.25)
			(net 405 "/X710-AT2 PCIe/GEN_F_CLK+")
			(pintype "passive")
		)
	)
	(footprint "antmicro-footprints:C_0402_1005Metric"
		(layer "B.Cu")
		(at 88.225 94.6 90)
		(descr "Capacitor SMD 0402")
		(tags "capacitor SMD 0402")
		(property "Reference" "C97"
			(at 12.5 -0.462343 90)
			(layer "B.SilkS")
			(effects
				(font
					(size 0.7 0.7)
					(thickness 0.15)
				)
				(justify right top mirror)
			)
		)
		(property "Value" "C_1u_25V_0402"
			(at -1.022927 -2.155213 90)
			(layer "B.Fab")
			(hide yes)
			(effects
				(font
					(size 0.7 0.7)
					(thickness 0.15)
				)
				(justify right top mirror)
			)
		)
		(property "Datasheet" "https://www.murata.com/products/productdetail?partno=GRM155R61E105KE11%23"
			(at 0 0 90)
			(layer "B.Fab")
			(hide yes)
			(effects
				(font
					(size 1.27 1.27)
					(thickness 0.15)
				)
				(justify mirror)
			)
		)
		(property "Description" "SMD Multilayer Ceramic Capacitor, 1 µF, 25 V, 0402 [1005 Metric], ± 10%, X5R, GRM Series"
			(at 0 0 90)
			(layer "B.Fab")
			(hide yes)
			(effects
				(font
					(size 1.27 1.27)
					(thickness 0.15)
				)
				(justify mirror)
			)
		)
		(property "MPN" "GRM155R61E105KE11J"
			(at 0 0 90)
			(unlocked yes)
			(layer "B.Fab")
			(hide yes)
			(effects
				(font
					(size 1 1)
					(thickness 0.15)
				)
				(justify mirror)
			)
		)
		(property "Manufacturer" "Murata"
			(at 0 0 90)
			(unlocked yes)
			(layer "B.Fab")
			(hide yes)
			(effects
				(font
					(size 1 1)
					(thickness 0.15)
				)
				(justify mirror)
			)
		)
		(property "License" "Apache-2.0"
			(at 0 0 90)
			(unlocked yes)
			(layer "B.Fab")
			(hide yes)
			(effects
				(font
					(size 1 1)
					(thickness 0.15)
				)
				(justify mirror)
			)
		)
		(property "Author" "Antmicro"
			(at 0 0 90)
			(unlocked yes)
			(layer "B.Fab")
			(hide yes)
			(effects
				(font
					(size 1 1)
					(thickness 0.15)
				)
				(justify mirror)
			)
		)
		(property "Val" "1u"
			(at 0 0 90)
			(unlocked yes)
			(layer "B.Fab")
			(hide yes)
			(effects
				(font
					(size 1 1)
					(thickness 0.15)
				)
				(justify mirror)
			)
		)
		(property "Voltage" "25V"
			(at 0 0 90)
			(unlocked yes)
			(layer "B.Fab")
			(hide yes)
			(effects
				(font
					(size 1 1)
					(thickness 0.15)
				)
				(justify mirror)
			)
		)
		(property "Dielectric" "X5R"
			(at 0 0 90)
			(unlocked yes)
			(layer "B.Fab")
			(hide yes)
			(effects
				(font
					(size 1 1)
					(thickness 0.15)
				)
				(justify mirror)
			)
		)
		(sheetname "/X710-AT2 power/")
		(sheetfile "x710-at2-power.kicad_sch")
		(attr smd)
		(fp_rect
			(start -0.925 0.47)
			(end 0.925 -0.47)
			(stroke
				(width 0.05)
				(type default)
			)
			(fill no)
			(layer "B.CrtYd")
		)
		(fp_line
			(start 0.504 -0.248)
			(end -0.494 -0.248)
			(stroke
				(width 0.15)
				(type solid)
			)
			(layer "B.Fab")
		)
		(fp_line
			(start -0.494 -0.248)
			(end -0.494 0.25)
			(stroke
				(width 0.15)
				(type solid)
			)
			(layer "B.Fab")
		)
		(fp_line
			(start 0.504 0.25)
			(end 0.504 -0.248)
			(stroke
				(width 0.15)
				(type solid)
			)
			(layer "B.Fab")
		)
		(fp_line
			(start -0.494 0.25)
			(end 0.504 0.25)
			(stroke
				(width 0.15)
				(type solid)
			)
			(layer "B.Fab")
		)
		(pad "1" smd roundrect
			(at -0.48 0 90)
			(size 0.59 0.64)
			(layers "B.Cu" "B.Mask" "B.Paste")
			(roundrect_rratio 0.25)
			(net 28 "GND")
			(pintype "passive")
		)
		(pad "2" smd roundrect
			(at 0.48 0 90)
			(size 0.59 0.64)
			(layers "B.Cu" "B.Mask" "B.Paste")
			(roundrect_rratio 0.25)
			(net 1 "VCCA")
			(pintype "passive")
		)
	)
	(footprint "antmicro-footprints:C_0402_1005Metric"
		(layer "B.Cu")
		(at 73.1 106.65 180)
		(descr "Capacitor SMD 0402")
		(tags "capacitor SMD 0402")
		(property "Reference" "C188"
			(at 0.88 -0.35 0)
			(layer "B.SilkS")
			(effects
				(font
					(size 0.7 0.7)
					(thickness 0.15)
				)
				(justify left bottom mirror)
			)
		)
		(property "Value" "C_100n_0402"
			(at -1.022927 -2.155213 0)
			(layer "B.Fab")
			(hide yes)
			(effects
				(font
					(size 0.7 0.7)
					(thickness 0.15)
				)
				(justify left bottom mirror)
			)
		)
		(property "Datasheet" "https://www.murata.com/products/productdetail?partno=GRM155R61H104KE14%23"
			(at 0 0 0)
			(layer "B.Fab")
			(hide yes)
			(effects
				(font
					(size 1.27 1.27)
					(thickness 0.15)
				)
				(justify mirror)
			)
		)
		(property "Description" "SMD Multilayer Ceramic Capacitor, 0.1 µF, 50 V, 0402 [1005 Metric], ± 10%, X5R, GRM Series"
			(at 0 0 0)
			(layer "B.Fab")
			(hide yes)
			(effects
				(font
					(size 1.27 1.27)
					(thickness 0.15)
				)
				(justify mirror)
			)
		)
		(property "MPN" "GRM155R61H104KE14D"
			(at 0 0 180)
			(unlocked yes)
			(layer "B.Fab")
			(hide yes)
			(effects
				(font
					(size 1 1)
					(thickness 0.15)
				)
				(justify mirror)
			)
		)
		(property "Val" "100n"
			(at 0 0 180)
			(unlocked yes)
			(layer "B.Fab")
			(hide yes)
			(effects
				(font
					(size 1 1)
					(thickness 0.15)
				)
				(justify mirror)
			)
		)
		(property "Voltage" "50V"
			(at 0 0 180)
			(unlocked yes)
			(layer "B.Fab")
			(hide yes)
			(effects
				(font
					(size 1 1)
					(thickness 0.15)
				)
				(justify mirror)
			)
		)
		(property "Dielectric" "X5R"
			(at 0 0 180)
			(unlocked yes)
			(layer "B.Fab")
			(hide yes)
			(effects
				(font
					(size 1 1)
					(thickness 0.15)
				)
				(justify mirror)
			)
		)
		(property "Manufacturer" "Murata"
			(at 0 0 180)
			(unlocked yes)
			(layer "B.Fab")
			(hide yes)
			(effects
				(font
					(size 1 1)
					(thickness 0.15)
				)
				(justify mirror)
			)
		)
		(property "License" "Apache-2.0"
			(at 0 0 180)
			(unlocked yes)
			(layer "B.Fab")
			(hide yes)
			(effects
				(font
					(size 1 1)
					(thickness 0.15)
				)
				(justify mirror)
			)
		)
		(property "Author" "Antmicro"
			(at 0 0 180)
			(unlocked yes)
			(layer "B.Fab")
			(hide yes)
			(effects
				(font
					(size 1 1)
					(thickness 0.15)
				)
				(justify mirror)
			)
		)
		(sheetname "/X710-AT2 power/")
		(sheetfile "x710-at2-power.kicad_sch")
		(attr smd)
		(fp_rect
			(start -0.925 0.47)
			(end 0.925 -0.47)
			(stroke
				(width 0.05)
				(type default)
			)
			(fill no)
			(layer "B.CrtYd")
		)
		(fp_line
			(start 0.504 0.25)
			(end 0.504 -0.248)
			(stroke
				(width 0.15)
				(type solid)
			)
			(layer "B.Fab")
		)
		(fp_line
			(start 0.504 -0.248)
			(end -0.494 -0.248)
			(stroke
				(width 0.15)
				(type solid)
			)
			(layer "B.Fab")
		)
		(fp_line
			(start -0.494 0.25)
			(end 0.504 0.25)
			(stroke
				(width 0.15)
				(type solid)
			)
			(layer "B.Fab")
		)
		(fp_line
			(start -0.494 -0.248)
			(end -0.494 0.25)
			(stroke
				(width 0.15)
				(type solid)
			)
			(layer "B.Fab")
		)
		(pad "1" smd roundrect
			(at -0.48 0 180)
			(size 0.59 0.64)
			(layers "B.Cu" "B.Mask" "B.Paste")
			(roundrect_rratio 0.25)
			(net 28 "GND")
			(pintype "passive")
		)
		(pad "2" smd roundrect
			(at 0.48 0 180)
			(size 0.59 0.64)
			(layers "B.Cu" "B.Mask" "B.Paste")
			(roundrect_rratio 0.25)
			(net 302 "+1V0")
			(pintype "passive")
		)
	)
	(footprint "antmicro-footprints:USON-10_2.5x1mm_P0.5mm"
		(layer "B.Cu")
		(at 96.747999 55.88366 90)
		(descr "USON-10 2.5x1mm_ Pitch 0.5mm")
		(tags "USON-10 2.5x1mm Pitch 0.5mm")
		(property "Reference" "D7"
			(at -0.90134 -0.697999 0)
			(layer "B.SilkS")
			(effects
				(font
					(size 0.7 0.7)
					(thickness 0.15)
				)
				(justify right top mirror)
			)
		)
		(property "Value" "ESD204DQAR"
			(at 0.018 -2.499 90)
			(layer "B.Fab")
			(hide yes)
			(effects
				(font
					(size 0.7 0.7)
					(thickness 0.15)
				)
				(justify right top mirror)
			)
		)
		(property "Datasheet" "https://www.ti.com/lit/ds/symlink/esd204.pdf?ts=1706004844383&ref_url=https%253A%252F%252Fwww.ti.com%252Finterface%252Fdiodes%252Fesd-protection-diodes%252Fproducts.html"
			(at 0 0 90)
			(layer "B.Fab")
			(hide yes)
			(effects
				(font
					(size 1.27 1.27)
					(thickness 0.15)
				)
				(justify mirror)
			)
		)
		(property "Description" "TVS diode array, 30 kV, USON-10, 3.6 V, 0.55 pF"
			(at 0 0 90)
			(layer "B.Fab")
			(hide yes)
			(effects
				(font
					(size 1.27 1.27)
					(thickness 0.15)
				)
				(justify mirror)
			)
		)
		(property "MPN" "ESD204DQAR"
			(at 0 0 90)
			(unlocked yes)
			(layer "B.Fab")
			(hide yes)
			(effects
				(font
					(size 1 1)
					(thickness 0.15)
				)
				(justify mirror)
			)
		)
		(property "Manufacturer" "Texas Instruments"
			(at 0 0 90)
			(unlocked yes)
			(layer "B.Fab")
			(hide yes)
			(effects
				(font
					(size 1 1)
					(thickness 0.15)
				)
				(justify mirror)
			)
		)
		(property "Author" "Antmicro"
			(at 0 0 90)
			(unlocked yes)
			(layer "B.Fab")
			(hide yes)
			(effects
				(font
					(size 1 1)
					(thickness 0.15)
				)
				(justify mirror)
			)
		)
		(property "License" "Apache-2.0"
			(at 0 0 90)
			(unlocked yes)
			(layer "B.Fab")
			(hide yes)
			(effects
				(font
					(size 1 1)
					(thickness 0.15)
				)
				(justify mirror)
			)
		)
		(sheetname "/OCuLink/")
		(sheetfile "oculink.kicad_sch")
		(attr smd)
		(fp_line
			(start 0.498 -1.398)
			(end -0.5 -1.398)
			(stroke
				(width 0.15)
				(type solid)
			)
			(layer "B.SilkS")
		)
		(fp_line
			(start 0.498 1.401)
			(end -0.5 1.401)
			(stroke
				(width 0.15)
				(type solid)
			)
			(layer "B.SilkS")
		)
		(fp_circle
			(center -0.68 1.27)
			(end -0.63 1.27)
			(stroke
				(width 0.15)
				(type solid)
			)
			(fill yes)
			(layer "B.SilkS")
		)
		(fp_rect
			(start -0.8 1.5)
			(end 0.8 -1.499)
			(stroke
				(width 0.05)
				(type solid)
			)
			(fill no)
			(layer "B.CrtYd")
		)
		(fp_line
			(start -0.5 -1.249)
			(end 0.498 -1.249)
			(stroke
				(width 0.15)
				(type solid)
			)
			(layer "B.Fab")
		)
		(fp_line
			(start -0.5 1)
			(end -0.5 -1.249)
			(stroke
				(width 0.15)
				(type solid)
			)
			(layer "B.Fab")
		)
		(fp_line
			(start 0.498 1.25)
			(end 0.498 -1.249)
			(stroke
				(width 0.15)
				(type solid)
			)
			(layer "B.Fab")
		)
		(fp_line
			(start 0.498 1.25)
			(end -0.25 1.25)
			(stroke
				(width 0.15)
				(type solid)
			)
			(layer "B.Fab")
		)
		(fp_line
			(start -0.25 1.25)
			(end -0.5 1)
			(stroke
				(width 0.15)
				(type solid)
			)
			(layer "B.Fab")
		)
		(pad "1" smd roundrect
			(at -0.387 1 180)
			(size 0.25 0.55)
			(layers "B.Cu" "B.Mask" "B.Paste")
			(roundrect_rratio 0.25)
			(net 80 "/OCuLink/PCIe_{x4}.RX2+")
			(pintype "passive")
		)
		(pad "2" smd roundrect
			(at -0.387 0.5 180)
			(size 0.25 0.55)
			(layers "B.Cu" "B.Mask" "B.Paste")
			(roundrect_rratio 0.25)
			(net 104 "/OCuLink/PCIe_{x4}.RX2-")
			(pintype "passive")
		)
		(pad "3" smd roundrect
			(at -0.387 0 180)
			(size 0.4 0.55)
			(layers "B.Cu" "B.Mask" "B.Paste")
			(roundrect_rratio 0.25)
			(net 28 "GND")
			(pintype "power_in")
		)
		(pad "4" smd roundrect
			(at -0.387 -0.498 180)
			(size 0.25 0.55)
			(layers "B.Cu" "B.Mask" "B.Paste")
			(roundrect_rratio 0.25)
			(net 98 "/OCuLink/PCIe_{x4}.RX3+")
			(pintype "passive")
		)
		(pad "5" smd roundrect
			(at -0.387 -0.998 180)
			(size 0.25 0.55)
			(layers "B.Cu" "B.Mask" "B.Paste")
			(roundrect_rratio 0.25)
			(net 109 "/OCuLink/PCIe_{x4}.RX3-")
			(pintype "passive")
		)
		(pad "6" smd roundrect
			(at 0.385 -0.998 180)
			(size 0.25 0.55)
			(layers "B.Cu" "B.Mask" "B.Paste")
			(roundrect_rratio 0.25)
			(net 109 "/OCuLink/PCIe_{x4}.RX3-")
			(pintype "passive")
		)
		(pad "7" smd roundrect
			(at 0.385 -0.498 180)
			(size 0.25 0.55)
			(layers "B.Cu" "B.Mask" "B.Paste")
			(roundrect_rratio 0.25)
			(net 98 "/OCuLink/PCIe_{x4}.RX3+")
			(pintype "passive")
		)
		(pad "8" smd roundrect
			(at 0.385 0 180)
			(size 0.4 0.55)
			(layers "B.Cu" "B.Mask" "B.Paste")
			(roundrect_rratio 0.25)
			(net 28 "GND")
			(pintype "passive")
		)
		(pad "9" smd roundrect
			(at 0.385 0.5 180)
			(size 0.25 0.55)
			(layers "B.Cu" "B.Mask" "B.Paste")
			(roundrect_rratio 0.25)
			(net 104 "/OCuLink/PCIe_{x4}.RX2-")
			(pintype "passive")
		)
		(pad "10" smd roundrect
			(at 0.385 1 180)
			(size 0.25 0.55)
			(layers "B.Cu" "B.Mask" "B.Paste")
			(roundrect_rratio 0.25)
			(net 80 "/OCuLink/PCIe_{x4}.RX2+")
			(pintype "passive")
		)
	)
	(footprint "antmicro-footprints:TP_SMD_0.75mm"
		(layer "B.Cu")
		(at 61.299999 91.850001 180)
		(property "Reference" "TP41"
			(at 0 0.6 0)
			(layer "B.SilkS")
			(hide yes)
			(effects
				(font
					(size 0.7 0.7)
					(thickness 0.15)
				)
				(justify left bottom mirror)
			)
		)
		(property "Value" "TP_0.75mm_SMD"
			(at 0 -1.2 0)
			(layer "B.Fab")
			(hide yes)
			(effects
				(font
					(size 0.7 0.7)
					(thickness 0.15)
				)
				(justify left bottom mirror)
			)
		)
		(property "Description" "SMT test point"
			(at 0 0 0)
			(layer "B.Fab")
			(hide yes)
			(effects
				(font
					(size 1.27 1.27)
					(thickness 0.15)
				)
				(justify mirror)
			)
		)
		(property "MPN" ""
			(at 0 0 0)
			(unlocked yes)
			(layer "B.Fab")
			(hide yes)
			(effects
				(font
					(size 1 1)
					(thickness 0.15)
				)
				(justify mirror)
			)
		)
		(property "Manufacturer" ""
			(at 0 0 0)
			(unlocked yes)
			(layer "B.Fab")
			(hide yes)
			(effects
				(font
					(size 1 1)
					(thickness 0.15)
				)
				(justify mirror)
			)
		)
		(property "Author" "Antmicro"
			(at 0 0 0)
			(unlocked yes)
			(layer "B.Fab")
			(hide yes)
			(effects
				(font
					(size 1 1)
					(thickness 0.15)
				)
				(justify mirror)
			)
		)
		(property "License" "Apache-2.0"
			(at 0 0 0)
			(unlocked yes)
			(layer "B.Fab")
			(hide yes)
			(effects
				(font
					(size 1 1)
					(thickness 0.15)
				)
				(justify mirror)
			)
		)
		(sheetname "/Power/")
		(sheetfile "power.kicad_sch")
		(attr exclude_from_pos_files exclude_from_bom)
		(fp_circle
			(center 0 0)
			(end 0.475 0)
			(stroke
				(width 0.05)
				(type default)
			)
			(fill no)
			(layer "B.CrtYd")
		)
		(pad "1" smd circle
			(at 0 0 180)
			(size 0.75 0.75)
			(layers "B.Cu" "B.Mask")
			(net 311 "/Power/+DVDD_OUT")
			(pinfunction "1")
			(pintype "passive")
		)
	)
	(footprint "antmicro-footprints:TP_SMD_0.75mm"
		(layer "B.Cu")
		(at 61.304999 107.255001 180)
		(property "Reference" "TP40"
			(at 0 0.6 0)
			(layer "B.SilkS")
			(hide yes)
			(effects
				(font
					(size 0.7 0.7)
					(thickness 0.15)
				)
				(justify left bottom mirror)
			)
		)
		(property "Value" "TP_0.75mm_SMD"
			(at 0 -1.2 0)
			(layer "B.Fab")
			(hide yes)
			(effects
				(font
					(size 0.7 0.7)
					(thickness 0.15)
				)
				(justify left bottom mirror)
			)
		)
		(property "Description" "SMT test point"
			(at 0 0 0)
			(layer "B.Fab")
			(hide yes)
			(effects
				(font
					(size 1.27 1.27)
					(thickness 0.15)
				)
				(justify mirror)
			)
		)
		(property "MPN" ""
			(at 0 0 0)
			(unlocked yes)
			(layer "B.Fab")
			(hide yes)
			(effects
				(font
					(size 1 1)
					(thickness 0.15)
				)
				(justify mirror)
			)
		)
		(property "Manufacturer" ""
			(at 0 0 0)
			(unlocked yes)
			(layer "B.Fab")
			(hide yes)
			(effects
				(font
					(size 1 1)
					(thickness 0.15)
				)
				(justify mirror)
			)
		)
		(property "Author" "Antmicro"
			(at 0 0 0)
			(unlocked yes)
			(layer "B.Fab")
			(hide yes)
			(effects
				(font
					(size 1 1)
					(thickness 0.15)
				)
				(justify mirror)
			)
		)
		(property "License" "Apache-2.0"
			(at 0 0 0)
			(unlocked yes)
			(layer "B.Fab")
			(hide yes)
			(effects
				(font
					(size 1 1)
					(thickness 0.15)
				)
				(justify mirror)
			)
		)
		(sheetname "/Power/")
		(sheetfile "power.kicad_sch")
		(attr exclude_from_pos_files exclude_from_bom)
		(fp_circle
			(center 0 0)
			(end 0.475 0)
			(stroke
				(width 0.05)
				(type default)
			)
			(fill no)
			(layer "B.CrtYd")
		)
		(pad "1" smd circle
			(at 0 0 180)
			(size 0.75 0.75)
			(layers "B.Cu" "B.Mask")
			(net 312 "/Power/+1V0_OUT")
			(pinfunction "1")
			(pintype "passive")
		)
	)
	(footprint "antmicro-footprints:C_0402_1005Metric"
		(layer "B.Cu")
		(at 77.67 107.9 -90)
		(descr "Capacitor SMD 0402")
		(tags "capacitor SMD 0402")
		(property "Reference" "C169"
			(at 0.84 -0.33 90)
			(layer "B.SilkS")
			(effects
				(font
					(size 0.7 0.7)
					(thickness 0.15)
				)
				(justify left bottom mirror)
			)
		)
		(property "Value" "C_1u_25V_0402"
			(at -1.022927 -2.155213 90)
			(layer "B.Fab")
			(hide yes)
			(effects
				(font
					(size 0.7 0.7)
					(thickness 0.15)
				)
				(justify left bottom mirror)
			)
		)
		(property "Datasheet" "https://www.murata.com/products/productdetail?partno=GRM155R61E105KE11%23"
			(at 0 0 90)
			(layer "B.Fab")
			(hide yes)
			(effects
				(font
					(size 1.27 1.27)
					(thickness 0.15)
				)
				(justify mirror)
			)
		)
		(property "Description" "SMD Multilayer Ceramic Capacitor, 1 µF, 25 V, 0402 [1005 Metric], ± 10%, X5R, GRM Series"
			(at 0 0 90)
			(layer "B.Fab")
			(hide yes)
			(effects
				(font
					(size 1.27 1.27)
					(thickness 0.15)
				)
				(justify mirror)
			)
		)
		(property "MPN" "GRM155R61E105KE11J"
			(at 0 0 270)
			(unlocked yes)
			(layer "B.Fab")
			(hide yes)
			(effects
				(font
					(size 1 1)
					(thickness 0.15)
				)
				(justify mirror)
			)
		)
		(property "Manufacturer" "Murata"
			(at 0 0 270)
			(unlocked yes)
			(layer "B.Fab")
			(hide yes)
			(effects
				(font
					(size 1 1)
					(thickness 0.15)
				)
				(justify mirror)
			)
		)
		(property "License" "Apache-2.0"
			(at 0 0 270)
			(unlocked yes)
			(layer "B.Fab")
			(hide yes)
			(effects
				(font
					(size 1 1)
					(thickness 0.15)
				)
				(justify mirror)
			)
		)
		(property "Author" "Antmicro"
			(at 0 0 270)
			(unlocked yes)
			(layer "B.Fab")
			(hide yes)
			(effects
				(font
					(size 1 1)
					(thickness 0.15)
				)
				(justify mirror)
			)
		)
		(property "Val" "1u"
			(at 0 0 270)
			(unlocked yes)
			(layer "B.Fab")
			(hide yes)
			(effects
				(font
					(size 1 1)
					(thickness 0.15)
				)
				(justify mirror)
			)
		)
		(property "Voltage" "25V"
			(at 0 0 270)
			(unlocked yes)
			(layer "B.Fab")
			(hide yes)
			(effects
				(font
					(size 1 1)
					(thickness 0.15)
				)
				(justify mirror)
			)
		)
		(property "Dielectric" "X5R"
			(at 0 0 270)
			(unlocked yes)
			(layer "B.Fab")
			(hide yes)
			(effects
				(font
					(size 1 1)
					(thickness 0.15)
				)
				(justify mirror)
			)
		)
		(sheetname "/X710-AT2 power/")
		(sheetfile "x710-at2-power.kicad_sch")
		(attr smd)
		(fp_rect
			(start -0.925 0.47)
			(end 0.925 -0.47)
			(stroke
				(width 0.05)
				(type default)
			)
			(fill no)
			(layer "B.CrtYd")
		)
		(fp_line
			(start -0.494 0.25)
			(end 0.504 0.25)
			(stroke
				(width 0.15)
				(type solid)
			)
			(layer "B.Fab")
		)
		(fp_line
			(start 0.504 0.25)
			(end 0.504 -0.248)
			(stroke
				(width 0.15)
				(type solid)
			)
			(layer "B.Fab")
		)
		(fp_line
			(start -0.494 -0.248)
			(end -0.494 0.25)
			(stroke
				(width 0.15)
				(type solid)
			)
			(layer "B.Fab")
		)
		(fp_line
			(start 0.504 -0.248)
			(end -0.494 -0.248)
			(stroke
				(width 0.15)
				(type solid)
			)
			(layer "B.Fab")
		)
		(pad "1" smd roundrect
			(at -0.48 0 270)
			(size 0.59 0.64)
			(layers "B.Cu" "B.Mask" "B.Paste")
			(roundrect_rratio 0.25)
			(net 28 "GND")
			(pintype "passive")
		)
		(pad "2" smd roundrect
			(at 0.48 0 270)
			(size 0.59 0.64)
			(layers "B.Cu" "B.Mask" "B.Paste")
			(roundrect_rratio 0.25)
			(net 5 "P0_AVDDL")
			(pintype "passive")
		)
	)
	(footprint "antmicro-footprints:R_0402_1005Metric"
		(layer "B.Cu")
		(at 91.7 104.45)
		(descr "Resistor SMD 0402")
		(tags "resistor SMD 0402")
		(property "Reference" "R76"
			(at 0.91 -0.44 0)
			(layer "B.SilkS")
			(effects
				(font
					(size 0.7 0.7)
					(thickness 0.15)
				)
				(justify right top mirror)
			)
		)
		(property "Value" "R_8k2_0402"
			(at -1.011843 -1.772046 0)
			(layer "B.Fab")
			(hide yes)
			(effects
				(font
					(size 0.7 0.7)
					(thickness 0.15)
				)
				(justify right top mirror)
			)
		)
		(property "Datasheet" "https://www.bourns.com/docs/product-datasheets/cr.pdf"
			(at 0 0 0)
			(layer "B.Fab")
			(hide yes)
			(effects
				(font
					(size 1.27 1.27)
					(thickness 0.15)
				)
				(justify mirror)
			)
		)
		(property "Description" "SMD Chip Resistor"
			(at 0 0 0)
			(layer "B.Fab")
			(hide yes)
			(effects
				(font
					(size 1.27 1.27)
					(thickness 0.15)
				)
				(justify mirror)
			)
		)
		(property "MPN" "CR0402-FX-8201GLF"
			(at 0 0 0)
			(unlocked yes)
			(layer "B.Fab")
			(hide yes)
			(effects
				(font
					(size 1 1)
					(thickness 0.15)
				)
				(justify mirror)
			)
		)
		(property "Manufacturer" "Bourns"
			(at 0 0 0)
			(unlocked yes)
			(layer "B.Fab")
			(hide yes)
			(effects
				(font
					(size 1 1)
					(thickness 0.15)
				)
				(justify mirror)
			)
		)
		(property "License" "Apache-2.0"
			(at 0 0 0)
			(unlocked yes)
			(layer "B.Fab")
			(hide yes)
			(effects
				(font
					(size 1 1)
					(thickness 0.15)
				)
				(justify mirror)
			)
		)
		(property "Author" "Antmicro"
			(at 0 0 0)
			(unlocked yes)
			(layer "B.Fab")
			(hide yes)
			(effects
				(font
					(size 1 1)
					(thickness 0.15)
				)
				(justify mirror)
			)
		)
		(property "Val" "8k2"
			(at 0 0 0)
			(unlocked yes)
			(layer "B.Fab")
			(hide yes)
			(effects
				(font
					(size 1 1)
					(thickness 0.15)
				)
				(justify mirror)
			)
		)
		(property "Tolerance" "1%"
			(at 0 0 0)
			(unlocked yes)
			(layer "B.Fab")
			(hide yes)
			(effects
				(font
					(size 1 1)
					(thickness 0.15)
				)
				(justify mirror)
			)
		)
		(sheetname "/X710-AT2 10GbE/")
		(sheetfile "x710-at2-10gbe.kicad_sch")
		(attr smd)
		(fp_rect
			(start -0.925 0.47)
			(end 0.925 -0.47)
			(stroke
				(width 0.05)
				(type default)
			)
			(fill no)
			(layer "B.CrtYd")
		)
		(fp_rect
			(start -0.5 0.25)
			(end 0.5 -0.25)
			(stroke
				(width 0.15)
				(type solid)
			)
			(fill no)
			(layer "B.Fab")
		)
		(pad "1" smd roundrect
			(at -0.48 0)
			(size 0.59 0.64)
			(layers "B.Cu" "B.Mask" "B.Paste")
			(roundrect_rratio 0.25)
			(net 85 "/X710-AT2 10GbE/OSC_SEL")
			(pintype "passive")
		)
		(pad "2" smd roundrect
			(at 0.48 0)
			(size 0.59 0.64)
			(layers "B.Cu" "B.Mask" "B.Paste")
			(roundrect_rratio 0.25)
			(net 7 "+3V3")
			(pintype "passive")
		)
	)
	(footprint "antmicro-footprints:C_0402_1005Metric"
		(layer "B.Cu")
		(at 76 105.05 90)
		(descr "Capacitor SMD 0402")
		(tags "capacitor SMD 0402")
		(property "Reference" "C189"
			(at -1.21 -1.37 90)
			(layer "B.SilkS")
			(effects
				(font
					(size 0.7 0.7)
					(thickness 0.15)
				)
				(justify right top mirror)
			)
		)
		(property "Value" "C_1u_25V_0402"
			(at -1.022927 -2.155213 90)
			(layer "B.Fab")
			(hide yes)
			(effects
				(font
					(size 0.7 0.7)
					(thickness 0.15)
				)
				(justify right top mirror)
			)
		)
		(property "Datasheet" "https://www.murata.com/products/productdetail?partno=GRM155R61E105KE11%23"
			(at 0 0 90)
			(layer "B.Fab")
			(hide yes)
			(effects
				(font
					(size 1.27 1.27)
					(thickness 0.15)
				)
				(justify mirror)
			)
		)
		(property "Description" "SMD Multilayer Ceramic Capacitor, 1 µF, 25 V, 0402 [1005 Metric], ± 10%, X5R, GRM Series"
			(at 0 0 90)
			(layer "B.Fab")
			(hide yes)
			(effects
				(font
					(size 1.27 1.27)
					(thickness 0.15)
				)
				(justify mirror)
			)
		)
		(property "MPN" "GRM155R61E105KE11J"
			(at 0 0 90)
			(unlocked yes)
			(layer "B.Fab")
			(hide yes)
			(effects
				(font
					(size 1 1)
					(thickness 0.15)
				)
				(justify mirror)
			)
		)
		(property "Manufacturer" "Murata"
			(at 0 0 90)
			(unlocked yes)
			(layer "B.Fab")
			(hide yes)
			(effects
				(font
					(size 1 1)
					(thickness 0.15)
				)
				(justify mirror)
			)
		)
		(property "License" "Apache-2.0"
			(at 0 0 90)
			(unlocked yes)
			(layer "B.Fab")
			(hide yes)
			(effects
				(font
					(size 1 1)
					(thickness 0.15)
				)
				(justify mirror)
			)
		)
		(property "Author" "Antmicro"
			(at 0 0 90)
			(unlocked yes)
			(layer "B.Fab")
			(hide yes)
			(effects
				(font
					(size 1 1)
					(thickness 0.15)
				)
				(justify mirror)
			)
		)
		(property "Val" "1u"
			(at 0 0 90)
			(unlocked yes)
			(layer "B.Fab")
			(hide yes)
			(effects
				(font
					(size 1 1)
					(thickness 0.15)
				)
				(justify mirror)
			)
		)
		(property "Voltage" "25V"
			(at 0 0 90)
			(unlocked yes)
			(layer "B.Fab")
			(hide yes)
			(effects
				(font
					(size 1 1)
					(thickness 0.15)
				)
				(justify mirror)
			)
		)
		(property "Dielectric" "X5R"
			(at 0 0 90)
			(unlocked yes)
			(layer "B.Fab")
			(hide yes)
			(effects
				(font
					(size 1 1)
					(thickness 0.15)
				)
				(justify mirror)
			)
		)
		(sheetname "/X710-AT2 power/")
		(sheetfile "x710-at2-power.kicad_sch")
		(attr smd)
		(fp_rect
			(start -0.925 0.47)
			(end 0.925 -0.47)
			(stroke
				(width 0.05)
				(type default)
			)
			(fill no)
			(layer "B.CrtYd")
		)
		(fp_line
			(start 0.504 -0.248)
			(end -0.494 -0.248)
			(stroke
				(width 0.15)
				(type solid)
			)
			(layer "B.Fab")
		)
		(fp_line
			(start -0.494 -0.248)
			(end -0.494 0.25)
			(stroke
				(width 0.15)
				(type solid)
			)
			(layer "B.Fab")
		)
		(fp_line
			(start 0.504 0.25)
			(end 0.504 -0.248)
			(stroke
				(width 0.15)
				(type solid)
			)
			(layer "B.Fab")
		)
		(fp_line
			(start -0.494 0.25)
			(end 0.504 0.25)
			(stroke
				(width 0.15)
				(type solid)
			)
			(layer "B.Fab")
		)
		(pad "1" smd roundrect
			(at -0.48 0 90)
			(size 0.59 0.64)
			(layers "B.Cu" "B.Mask" "B.Paste")
			(roundrect_rratio 0.25)
			(net 28 "GND")
			(pintype "passive")
		)
		(pad "2" smd roundrect
			(at 0.48 0 90)
			(size 0.59 0.64)
			(layers "B.Cu" "B.Mask" "B.Paste")
			(roundrect_rratio 0.25)
			(net 27 "PLL_VDD")
			(pintype "passive")
		)
	)
	(footprint "antmicro-footprints:C_0402_1005Metric"
		(layer "B.Cu")
		(at 87.225 96.45 90)
		(descr "Capacitor SMD 0402")
		(tags "capacitor SMD 0402")
		(property "Reference" "C107"
			(at 14.36 0.397657 270)
			(layer "B.SilkS")
			(effects
				(font
					(size 0.7 0.7)
					(thickness 0.15)
				)
				(justify left bottom mirror)
			)
		)
		(property "Value" "C_1u_25V_0402"
			(at -1.022927 -2.155213 270)
			(layer "B.Fab")
			(hide yes)
			(effects
				(font
					(size 0.7 0.7)
					(thickness 0.15)
				)
				(justify left bottom mirror)
			)
		)
		(property "Datasheet" "https://www.murata.com/products/productdetail?partno=GRM155R61E105KE11%23"
			(at 0 0 270)
			(layer "B.Fab")
			(hide yes)
			(effects
				(font
					(size 1.27 1.27)
					(thickness 0.15)
				)
				(justify mirror)
			)
		)
		(property "Description" "SMD Multilayer Ceramic Capacitor, 1 µF, 25 V, 0402 [1005 Metric], ± 10%, X5R, GRM Series"
			(at 0 0 270)
			(layer "B.Fab")
			(hide yes)
			(effects
				(font
					(size 1.27 1.27)
					(thickness 0.15)
				)
				(justify mirror)
			)
		)
		(property "MPN" "GRM155R61E105KE11J"
			(at 0 0 90)
			(unlocked yes)
			(layer "B.Fab")
			(hide yes)
			(effects
				(font
					(size 1 1)
					(thickness 0.15)
				)
				(justify mirror)
			)
		)
		(property "Manufacturer" "Murata"
			(at 0 0 90)
			(unlocked yes)
			(layer "B.Fab")
			(hide yes)
			(effects
				(font
					(size 1 1)
					(thickness 0.15)
				)
				(justify mirror)
			)
		)
		(property "License" "Apache-2.0"
			(at 0 0 90)
			(unlocked yes)
			(layer "B.Fab")
			(hide yes)
			(effects
				(font
					(size 1 1)
					(thickness 0.15)
				)
				(justify mirror)
			)
		)
		(property "Author" "Antmicro"
			(at 0 0 90)
			(unlocked yes)
			(layer "B.Fab")
			(hide yes)
			(effects
				(font
					(size 1 1)
					(thickness 0.15)
				)
				(justify mirror)
			)
		)
		(property "Val" "1u"
			(at 0 0 90)
			(unlocked yes)
			(layer "B.Fab")
			(hide yes)
			(effects
				(font
					(size 1 1)
					(thickness 0.15)
				)
				(justify mirror)
			)
		)
		(property "Voltage" "25V"
			(at 0 0 90)
			(unlocked yes)
			(layer "B.Fab")
			(hide yes)
			(effects
				(font
					(size 1 1)
					(thickness 0.15)
				)
				(justify mirror)
			)
		)
		(property "Dielectric" "X5R"
			(at 0 0 90)
			(unlocked yes)
			(layer "B.Fab")
			(hide yes)
			(effects
				(font
					(size 1 1)
					(thickness 0.15)
				)
				(justify mirror)
			)
		)
		(sheetname "/X710-AT2 power/")
		(sheetfile "x710-at2-power.kicad_sch")
		(attr smd)
		(fp_rect
			(start -0.925 0.47)
			(end 0.925 -0.47)
			(stroke
				(width 0.05)
				(type default)
			)
			(fill no)
			(layer "B.CrtYd")
		)
		(fp_line
			(start 0.504 -0.248)
			(end -0.494 -0.248)
			(stroke
				(width 0.15)
				(type solid)
			)
			(layer "B.Fab")
		)
		(fp_line
			(start -0.494 -0.248)
			(end -0.494 0.25)
			(stroke
				(width 0.15)
				(type solid)
			)
			(layer "B.Fab")
		)
		(fp_line
			(start 0.504 0.25)
			(end 0.504 -0.248)
			(stroke
				(width 0.15)
				(type solid)
			)
			(layer "B.Fab")
		)
		(fp_line
			(start -0.494 0.25)
			(end 0.504 0.25)
			(stroke
				(width 0.15)
				(type solid)
			)
			(layer "B.Fab")
		)
		(pad "1" smd roundrect
			(at -0.48 0 90)
			(size 0.59 0.64)
			(layers "B.Cu" "B.Mask" "B.Paste")
			(roundrect_rratio 0.25)
			(net 28 "GND")
			(pintype "passive")
		)
		(pad "2" smd roundrect
			(at 0.48 0 90)
			(size 0.59 0.64)
			(layers "B.Cu" "B.Mask" "B.Paste")
			(roundrect_rratio 0.25)
			(net 9 "VCCD")
			(pintype "passive")
		)
	)
	(footprint "antmicro-footprints:C_0402_1005Metric"
		(layer "B.Cu")
		(at 83.4 107.895 -90)
		(descr "Capacitor SMD 0402")
		(tags "capacitor SMD 0402")
		(property "Reference" "C175"
			(at 0.805 -0.355 90)
			(layer "B.SilkS")
			(effects
				(font
					(size 0.7 0.7)
					(thickness 0.15)
				)
				(justify left bottom mirror)
			)
		)
		(property "Value" "C_1u_25V_0402"
			(at -1.022927 -2.155213 90)
			(layer "B.Fab")
			(hide yes)
			(effects
				(font
					(size 0.7 0.7)
					(thickness 0.15)
				)
				(justify left bottom mirror)
			)
		)
		(property "Datasheet" "https://www.murata.com/products/productdetail?partno=GRM155R61E105KE11%23"
			(at 0 0 90)
			(layer "B.Fab")
			(hide yes)
			(effects
				(font
					(size 1.27 1.27)
					(thickness 0.15)
				)
				(justify mirror)
			)
		)
		(property "Description" "SMD Multilayer Ceramic Capacitor, 1 µF, 25 V, 0402 [1005 Metric], ± 10%, X5R, GRM Series"
			(at 0 0 90)
			(layer "B.Fab")
			(hide yes)
			(effects
				(font
					(size 1.27 1.27)
					(thickness 0.15)
				)
				(justify mirror)
			)
		)
		(property "MPN" "GRM155R61E105KE11J"
			(at 0 0 270)
			(unlocked yes)
			(layer "B.Fab")
			(hide yes)
			(effects
				(font
					(size 1 1)
					(thickness 0.15)
				)
				(justify mirror)
			)
		)
		(property "Manufacturer" "Murata"
			(at 0 0 270)
			(unlocked yes)
			(layer "B.Fab")
			(hide yes)
			(effects
				(font
					(size 1 1)
					(thickness 0.15)
				)
				(justify mirror)
			)
		)
		(property "License" "Apache-2.0"
			(at 0 0 270)
			(unlocked yes)
			(layer "B.Fab")
			(hide yes)
			(effects
				(font
					(size 1 1)
					(thickness 0.15)
				)
				(justify mirror)
			)
		)
		(property "Author" "Antmicro"
			(at 0 0 270)
			(unlocked yes)
			(layer "B.Fab")
			(hide yes)
			(effects
				(font
					(size 1 1)
					(thickness 0.15)
				)
				(justify mirror)
			)
		)
		(property "Val" "1u"
			(at 0 0 270)
			(unlocked yes)
			(layer "B.Fab")
			(hide yes)
			(effects
				(font
					(size 1 1)
					(thickness 0.15)
				)
				(justify mirror)
			)
		)
		(property "Voltage" "25V"
			(at 0 0 270)
			(unlocked yes)
			(layer "B.Fab")
			(hide yes)
			(effects
				(font
					(size 1 1)
					(thickness 0.15)
				)
				(justify mirror)
			)
		)
		(property "Dielectric" "X5R"
			(at 0 0 270)
			(unlocked yes)
			(layer "B.Fab")
			(hide yes)
			(effects
				(font
					(size 1 1)
					(thickness 0.15)
				)
				(justify mirror)
			)
		)
		(sheetname "/X710-AT2 power/")
		(sheetfile "x710-at2-power.kicad_sch")
		(attr smd)
		(fp_rect
			(start -0.925 0.47)
			(end 0.925 -0.47)
			(stroke
				(width 0.05)
				(type default)
			)
			(fill no)
			(layer "B.CrtYd")
		)
		(fp_line
			(start -0.494 0.25)
			(end 0.504 0.25)
			(stroke
				(width 0.15)
				(type solid)
			)
			(layer "B.Fab")
		)
		(fp_line
			(start 0.504 0.25)
			(end 0.504 -0.248)
			(stroke
				(width 0.15)
				(type solid)
			)
			(layer "B.Fab")
		)
		(fp_line
			(start -0.494 -0.248)
			(end -0.494 0.25)
			(stroke
				(width 0.15)
				(type solid)
			)
			(layer "B.Fab")
		)
		(fp_line
			(start 0.504 -0.248)
			(end -0.494 -0.248)
			(stroke
				(width 0.15)
				(type solid)
			)
			(layer "B.Fab")
		)
		(pad "1" smd roundrect
			(at -0.48 0 270)
			(size 0.59 0.64)
			(layers "B.Cu" "B.Mask" "B.Paste")
			(roundrect_rratio 0.25)
			(net 28 "GND")
			(pintype "passive")
		)
		(pad "2" smd roundrect
			(at 0.48 0 270)
			(size 0.59 0.64)
			(layers "B.Cu" "B.Mask" "B.Paste")
			(roundrect_rratio 0.25)
			(net 14 "P1_AVDDL")
			(pintype "passive")
		)
	)
	(footprint "antmicro-footprints:C_Pol_EIA-D"
		(layer "B.Cu")
		(at 65.25 98.45 -90)
		(property "Reference" "C78"
			(at -1 2.45 90)
			(layer "B.SilkS")
			(effects
				(font
					(size 0.7 0.7)
					(thickness 0.15)
				)
				(justify left bottom mirror)
			)
		)
		(property "Value" "C_Pol_470u_6.3V_Vishay-TR3-D"
			(at 0 -3.4 90)
			(layer "B.Fab")
			(hide yes)
			(effects
				(font
					(size 0.7 0.7)
					(thickness 0.15)
				)
				(justify left bottom mirror)
			)
		)
		(property "Datasheet" "https://www.vishay.com/docs/40080/tr3.pdf"
			(at 0 0 90)
			(layer "B.Fab")
			(hide yes)
			(effects
				(font
					(size 1.27 1.27)
					(thickness 0.15)
				)
				(justify mirror)
			)
		)
		(property "Description" "470 µF Molded Tantalum Capacitors 6.3 V 2917 (7343 Metric) 200mOhm"
			(at 0 0 90)
			(layer "B.Fab")
			(hide yes)
			(effects
				(font
					(size 1.27 1.27)
					(thickness 0.15)
				)
				(justify mirror)
			)
		)
		(property "Val" "470u"
			(at 0 0 270)
			(unlocked yes)
			(layer "B.Fab")
			(hide yes)
			(effects
				(font
					(size 1 1)
					(thickness 0.15)
				)
				(justify mirror)
			)
		)
		(property "MPN" "TR3D477M6R3C0200"
			(at 0 0 270)
			(unlocked yes)
			(layer "B.Fab")
			(hide yes)
			(effects
				(font
					(size 1 1)
					(thickness 0.15)
				)
				(justify mirror)
			)
		)
		(property "Manufacturer" "Vishay"
			(at 0 0 270)
			(unlocked yes)
			(layer "B.Fab")
			(hide yes)
			(effects
				(font
					(size 1 1)
					(thickness 0.15)
				)
				(justify mirror)
			)
		)
		(property "License" "Apache-2.0"
			(at 0 0 270)
			(unlocked yes)
			(layer "B.Fab")
			(hide yes)
			(effects
				(font
					(size 1 1)
					(thickness 0.15)
				)
				(justify mirror)
			)
		)
		(property "Author" "Antmicro"
			(at 0 0 270)
			(unlocked yes)
			(layer "B.Fab")
			(hide yes)
			(effects
				(font
					(size 1 1)
					(thickness 0.15)
				)
				(justify mirror)
			)
		)
		(property "Voltage" "6.3V"
			(at 0 0 270)
			(unlocked yes)
			(layer "B.Fab")
			(hide yes)
			(effects
				(font
					(size 1 1)
					(thickness 0.15)
				)
				(justify mirror)
			)
		)
		(property "Dielectric" "template_dielectric"
			(at 0 0 270)
			(unlocked yes)
			(layer "B.Fab")
			(hide yes)
			(effects
				(font
					(size 1 1)
					(thickness 0.15)
				)
				(justify mirror)
			)
		)
		(sheetname "/X710-AT2 power/")
		(sheetfile "x710-at2-power.kicad_sch")
		(attr smd)
		(fp_line
			(start -3.58 2.2)
			(end 3.6 2.2)
			(stroke
				(width 0.15)
				(type solid)
			)
			(layer "B.SilkS")
		)
		(fp_line
			(start 3.6 2.2)
			(end 3.6 1.6)
			(stroke
				(width 0.15)
				(type solid)
			)
			(layer "B.SilkS")
		)
		(fp_line
			(start -4.1 2.025)
			(end -4.1 1.625)
			(stroke
				(width 0.12)
				(type solid)
			)
			(layer "B.SilkS")
		)
		(fp_line
			(start -4.3 1.825)
			(end -3.9 1.825)
			(stroke
				(width 0.12)
				(type solid)
			)
			(layer "B.SilkS")
		)
		(fp_line
			(start -3.58 1.6)
			(end -3.58 2.2)
			(stroke
				(width 0.15)
				(type solid)
			)
			(layer "B.SilkS")
		)
		(fp_line
			(start 3.6 -1.6)
			(end 3.6 -2.2)
			(stroke
				(width 0.15)
				(type solid)
			)
			(layer "B.SilkS")
		)
		(fp_line
			(start -3.58 -2.2)
			(end -3.58 -1.6)
			(stroke
				(width 0.15)
				(type solid)
			)
			(layer "B.SilkS")
		)
		(fp_line
			(start 3.6 -2.2)
			(end -3.58 -2.2)
			(stroke
				(width 0.15)
				(type solid)
			)
			(layer "B.SilkS")
		)
		(fp_line
			(start -3.775 2.4)
			(end 3.77 2.4)
			(stroke
				(width 0.05)
				(type solid)
			)
			(layer "B.CrtYd")
		)
		(fp_line
			(start -3.775 2.4)
			(end -3.775 1.5)
			(stroke
				(width 0.05)
				(type solid)
			)
			(layer "B.CrtYd")
		)
		(fp_line
			(start 3.77 2.4)
			(end 3.77 1.51)
			(stroke
				(width 0.05)
				(type solid)
			)
			(layer "B.CrtYd")
		)
		(fp_line
			(start 3.77 1.51)
			(end 4.505 1.51)
			(stroke
				(width 0.05)
				(type solid)
			)
			(layer "B.CrtYd")
		)
		(fp_line
			(start 4.505 1.51)
			(end 4.505 -1.5)
			(stroke
				(width 0.05)
				(type solid)
			)
			(layer "B.CrtYd")
		)
		(fp_line
			(start -3.775 1.5)
			(end -4.505 1.5)
			(stroke
				(width 0.05)
				(type solid)
			)
			(layer "B.CrtYd")
		)
		(fp_line
			(start -4.505 -1.51)
			(end -4.505 1.5)
			(stroke
				(width 0.05)
				(type solid)
			)
			(layer "B.CrtYd")
		)
		(fp_line
			(start -3.77 -1.51)
			(end -4.505 -1.51)
			(stroke
				(width 0.05)
				(type solid)
			)
			(layer "B.CrtYd")
		)
		(fp_line
			(start 3.77 -1.51)
			(end 3.77 -2.4)
			(stroke
				(width 0.05)
				(type solid)
			)
			(layer "B.CrtYd")
		)
		(fp_line
			(start 4.505 -1.51)
			(end 3.77 -1.51)
			(stroke
				(width 0.05)
				(type solid)
			)
			(layer "B.CrtYd")
		)
		(fp_line
			(start -3.77 -2.4)
			(end -3.77 -1.51)
			(stroke
				(width 0.05)
				(type solid)
			)
			(layer "B.CrtYd")
		)
		(fp_line
			(start 3.77 -2.4)
			(end -3.77 -2.4)
			(stroke
				(width 0.05)
				(type solid)
			)
			(layer "B.CrtYd")
		)
		(fp_rect
			(start -3.65 2.15)
			(end 3.65 -2.15)
			(stroke
				(width 0.15)
				(type solid)
			)
			(fill no)
			(layer "B.Fab")
		)
		(pad "1" smd roundrect
			(at -3.1 0 270)
			(size 2.31 2.52)
			(layers "B.Cu" "B.Mask" "B.Paste")
			(roundrect_rratio 0.1)
			(net 6 "DVDD")
			(pintype "passive")
		)
		(pad "2" smd roundrect
			(at 3.1 0 270)
			(size 2.31 2.52)
			(layers "B.Cu" "B.Mask" "B.Paste")
			(roundrect_rratio 0.1)
			(net 28 "GND")
			(pintype "passive")
		)
	)
	(footprint "antmicro-footprints:TP_SMD_0.75mm"
		(layer "B.Cu")
		(at 110.95 71.1 90)
		(property "Reference" "TP16"
			(at 0.3 0.54 180)
			(layer "B.SilkS")
			(effects
				(font
					(size 0.7 0.7)
					(thickness 0.15)
				)
				(justify right top mirror)
			)
		)
		(property "Value" "TP_0.75mm_SMD"
			(at 0 -1.2 90)
			(layer "B.Fab")
			(hide yes)
			(effects
				(font
					(size 0.7 0.7)
					(thickness 0.15)
				)
				(justify right top mirror)
			)
		)
		(property "Description" "SMT test point"
			(at 0 0 90)
			(layer "B.Fab")
			(hide yes)
			(effects
				(font
					(size 1.27 1.27)
					(thickness 0.15)
				)
				(justify mirror)
			)
		)
		(property "MPN" ""
			(at 0 0 90)
			(unlocked yes)
			(layer "B.Fab")
			(hide yes)
			(effects
				(font
					(size 1 1)
					(thickness 0.15)
				)
				(justify mirror)
			)
		)
		(property "Manufacturer" ""
			(at 0 0 90)
			(unlocked yes)
			(layer "B.Fab")
			(hide yes)
			(effects
				(font
					(size 1 1)
					(thickness 0.15)
				)
				(justify mirror)
			)
		)
		(property "Author" "Antmicro"
			(at 0 0 90)
			(unlocked yes)
			(layer "B.Fab")
			(hide yes)
			(effects
				(font
					(size 1 1)
					(thickness 0.15)
				)
				(justify mirror)
			)
		)
		(property "License" "Apache-2.0"
			(at 0 0 90)
			(unlocked yes)
			(layer "B.Fab")
			(hide yes)
			(effects
				(font
					(size 1 1)
					(thickness 0.15)
				)
				(justify mirror)
			)
		)
		(sheetname "/OCuLink/")
		(sheetfile "oculink.kicad_sch")
		(attr exclude_from_pos_files exclude_from_bom)
		(fp_circle
			(center 0 0)
			(end 0.475 0)
			(stroke
				(width 0.05)
				(type default)
			)
			(fill no)
			(layer "B.CrtYd")
		)
		(pad "1" smd circle
			(at 0 0 90)
			(size 0.75 0.75)
			(layers "B.Cu" "B.Mask")
			(net 320 "/OCuLink/~{CWAKE}_R")
			(pinfunction "1")
			(pintype "passive")
		)
	)
	(footprint "antmicro-footprints:C_0402_1005Metric"
		(layer "B.Cu")
		(at 91.225 94.6 90)
		(descr "Capacitor SMD 0402")
		(tags "capacitor SMD 0402")
		(property "Reference" "C117"
			(at 12.5 -0.462343 90)
			(layer "B.SilkS")
			(effects
				(font
					(size 0.7 0.7)
					(thickness 0.15)
				)
				(justify right top mirror)
			)
		)
		(property "Value" "C_1u_25V_0402"
			(at -1.022927 -2.155213 90)
			(layer "B.Fab")
			(hide yes)
			(effects
				(font
					(size 0.7 0.7)
					(thickness 0.15)
				)
				(justify right top mirror)
			)
		)
		(property "Datasheet" "https://www.murata.com/products/productdetail?partno=GRM155R61E105KE11%23"
			(at 0 0 90)
			(layer "B.Fab")
			(hide yes)
			(effects
				(font
					(size 1.27 1.27)
					(thickness 0.15)
				)
				(justify mirror)
			)
		)
		(property "Description" "SMD Multilayer Ceramic Capacitor, 1 µF, 25 V, 0402 [1005 Metric], ± 10%, X5R, GRM Series"
			(at 0 0 90)
			(layer "B.Fab")
			(hide yes)
			(effects
				(font
					(size 1.27 1.27)
					(thickness 0.15)
				)
				(justify mirror)
			)
		)
		(property "MPN" "GRM155R61E105KE11J"
			(at 0 0 90)
			(unlocked yes)
			(layer "B.Fab")
			(hide yes)
			(effects
				(font
					(size 1 1)
					(thickness 0.15)
				)
				(justify mirror)
			)
		)
		(property "Manufacturer" "Murata"
			(at 0 0 90)
			(unlocked yes)
			(layer "B.Fab")
			(hide yes)
			(effects
				(font
					(size 1 1)
					(thickness 0.15)
				)
				(justify mirror)
			)
		)
		(property "License" "Apache-2.0"
			(at 0 0 90)
			(unlocked yes)
			(layer "B.Fab")
			(hide yes)
			(effects
				(font
					(size 1 1)
					(thickness 0.15)
				)
				(justify mirror)
			)
		)
		(property "Author" "Antmicro"
			(at 0 0 90)
			(unlocked yes)
			(layer "B.Fab")
			(hide yes)
			(effects
				(font
					(size 1 1)
					(thickness 0.15)
				)
				(justify mirror)
			)
		)
		(property "Val" "1u"
			(at 0 0 90)
			(unlocked yes)
			(layer "B.Fab")
			(hide yes)
			(effects
				(font
					(size 1 1)
					(thickness 0.15)
				)
				(justify mirror)
			)
		)
		(property "Voltage" "25V"
			(at 0 0 90)
			(unlocked yes)
			(layer "B.Fab")
			(hide yes)
			(effects
				(font
					(size 1 1)
					(thickness 0.15)
				)
				(justify mirror)
			)
		)
		(property "Dielectric" "X5R"
			(at 0 0 90)
			(unlocked yes)
			(layer "B.Fab")
			(hide yes)
			(effects
				(font
					(size 1 1)
					(thickness 0.15)
				)
				(justify mirror)
			)
		)
		(sheetname "/X710-AT2 power/")
		(sheetfile "x710-at2-power.kicad_sch")
		(attr smd)
		(fp_rect
			(start -0.925 0.47)
			(end 0.925 -0.47)
			(stroke
				(width 0.05)
				(type default)
			)
			(fill no)
			(layer "B.CrtYd")
		)
		(fp_line
			(start 0.504 -0.248)
			(end -0.494 -0.248)
			(stroke
				(width 0.15)
				(type solid)
			)
			(layer "B.Fab")
		)
		(fp_line
			(start -0.494 -0.248)
			(end -0.494 0.25)
			(stroke
				(width 0.15)
				(type solid)
			)
			(layer "B.Fab")
		)
		(fp_line
			(start 0.504 0.25)
			(end 0.504 -0.248)
			(stroke
				(width 0.15)
				(type solid)
			)
			(layer "B.Fab")
		)
		(fp_line
			(start -0.494 0.25)
			(end 0.504 0.25)
			(stroke
				(width 0.15)
				(type solid)
			)
			(layer "B.Fab")
		)
		(pad "1" smd roundrect
			(at -0.48 0 90)
			(size 0.59 0.64)
			(layers "B.Cu" "B.Mask" "B.Paste")
			(roundrect_rratio 0.25)
			(net 28 "GND")
			(pintype "passive")
		)
		(pad "2" smd roundrect
			(at 0.48 0 90)
			(size 0.59 0.64)
			(layers "B.Cu" "B.Mask" "B.Paste")
			(roundrect_rratio 0.25)
			(net 9 "VCCD")
			(pintype "passive")
		)
	)
	(footprint "antmicro-footprints:C_0402_1005Metric"
		(layer "B.Cu")
		(at 77.48 106.05 -90)
		(descr "Capacitor SMD 0402")
		(tags "capacitor SMD 0402")
		(property "Reference" "C142"
			(at 8.99 -0.09 90)
			(layer "B.SilkS")
			(effects
				(font
					(size 0.7 0.7)
					(thickness 0.15)
				)
				(justify left bottom mirror)
			)
		)
		(property "Value" "C_1u_25V_0402"
			(at -1.022927 -2.155213 90)
			(layer "B.Fab")
			(hide yes)
			(effects
				(font
					(size 0.7 0.7)
					(thickness 0.15)
				)
				(justify left bottom mirror)
			)
		)
		(property "Datasheet" "https://www.murata.com/products/productdetail?partno=GRM155R61E105KE11%23"
			(at 0 0 90)
			(layer "B.Fab")
			(hide yes)
			(effects
				(font
					(size 1.27 1.27)
					(thickness 0.15)
				)
				(justify mirror)
			)
		)
		(property "Description" "SMD Multilayer Ceramic Capacitor, 1 µF, 25 V, 0402 [1005 Metric], ± 10%, X5R, GRM Series"
			(at 0 0 90)
			(layer "B.Fab")
			(hide yes)
			(effects
				(font
					(size 1.27 1.27)
					(thickness 0.15)
				)
				(justify mirror)
			)
		)
		(property "MPN" "GRM155R61E105KE11J"
			(at 0 0 270)
			(unlocked yes)
			(layer "B.Fab")
			(hide yes)
			(effects
				(font
					(size 1 1)
					(thickness 0.15)
				)
				(justify mirror)
			)
		)
		(property "Manufacturer" "Murata"
			(at 0 0 270)
			(unlocked yes)
			(layer "B.Fab")
			(hide yes)
			(effects
				(font
					(size 1 1)
					(thickness 0.15)
				)
				(justify mirror)
			)
		)
		(property "License" "Apache-2.0"
			(at 0 0 270)
			(unlocked yes)
			(layer "B.Fab")
			(hide yes)
			(effects
				(font
					(size 1 1)
					(thickness 0.15)
				)
				(justify mirror)
			)
		)
		(property "Author" "Antmicro"
			(at 0 0 270)
			(unlocked yes)
			(layer "B.Fab")
			(hide yes)
			(effects
				(font
					(size 1 1)
					(thickness 0.15)
				)
				(justify mirror)
			)
		)
		(property "Val" "1u"
			(at 0 0 270)
			(unlocked yes)
			(layer "B.Fab")
			(hide yes)
			(effects
				(font
					(size 1 1)
					(thickness 0.15)
				)
				(justify mirror)
			)
		)
		(property "Voltage" "25V"
			(at 0 0 270)
			(unlocked yes)
			(layer "B.Fab")
			(hide yes)
			(effects
				(font
					(size 1 1)
					(thickness 0.15)
				)
				(justify mirror)
			)
		)
		(property "Dielectric" "X5R"
			(at 0 0 270)
			(unlocked yes)
			(layer "B.Fab")
			(hide yes)
			(effects
				(font
					(size 1 1)
					(thickness 0.15)
				)
				(justify mirror)
			)
		)
		(sheetname "/X710-AT2 power/")
		(sheetfile "x710-at2-power.kicad_sch")
		(attr smd)
		(fp_rect
			(start -0.925 0.47)
			(end 0.925 -0.47)
			(stroke
				(width 0.05)
				(type default)
			)
			(fill no)
			(layer "B.CrtYd")
		)
		(fp_line
			(start -0.494 0.25)
			(end 0.504 0.25)
			(stroke
				(width 0.15)
				(type solid)
			)
			(layer "B.Fab")
		)
		(fp_line
			(start 0.504 0.25)
			(end 0.504 -0.248)
			(stroke
				(width 0.15)
				(type solid)
			)
			(layer "B.Fab")
		)
		(fp_line
			(start -0.494 -0.248)
			(end -0.494 0.25)
			(stroke
				(width 0.15)
				(type solid)
			)
			(layer "B.Fab")
		)
		(fp_line
			(start 0.504 -0.248)
			(end -0.494 -0.248)
			(stroke
				(width 0.15)
				(type solid)
			)
			(layer "B.Fab")
		)
		(pad "1" smd roundrect
			(at -0.48 0 270)
			(size 0.59 0.64)
			(layers "B.Cu" "B.Mask" "B.Paste")
			(roundrect_rratio 0.25)
			(net 28 "GND")
			(pintype "passive")
		)
		(pad "2" smd roundrect
			(at 0.48 0 270)
			(size 0.59 0.64)
			(layers "B.Cu" "B.Mask" "B.Paste")
			(roundrect_rratio 0.25)
			(net 10 "AVDDH")
			(pintype "passive")
		)
	)
	(footprint "antmicro-footprints:R_0402_1005Metric"
		(layer "B.Cu")
		(at 72.48 145.34 90)
		(descr "Resistor SMD 0402")
		(tags "resistor SMD 0402")
		(property "Reference" "R38"
			(at 0.76 -0.37 90)
			(layer "B.SilkS")
			(effects
				(font
					(size 0.7 0.7)
					(thickness 0.15)
				)
				(justify right top mirror)
			)
		)
		(property "Value" "R_220R_0402"
			(at -1.011843 -1.772046 90)
			(layer "B.Fab")
			(hide yes)
			(effects
				(font
					(size 0.7 0.7)
					(thickness 0.15)
				)
				(justify right top mirror)
			)
		)
		(property "Datasheet" "https://www.bourns.com/docs/product-datasheets/cr.pdf"
			(at 0 0 90)
			(layer "B.Fab")
			(hide yes)
			(effects
				(font
					(size 1.27 1.27)
					(thickness 0.15)
				)
				(justify mirror)
			)
		)
		(property "Description" "SMD Chip Resistor, 220 ohm, ± 1%, 62.5 mW, 0402 [1005 Metric], Thick Film, General Purpose"
			(at 0 0 90)
			(layer "B.Fab")
			(hide yes)
			(effects
				(font
					(size 1.27 1.27)
					(thickness 0.15)
				)
				(justify mirror)
			)
		)
		(property "MPN" "CR0402-FX-2200GLF"
			(at 0 0 90)
			(unlocked yes)
			(layer "B.Fab")
			(hide yes)
			(effects
				(font
					(size 1 1)
					(thickness 0.15)
				)
				(justify mirror)
			)
		)
		(property "Manufacturer" "Bourns"
			(at 0 0 90)
			(unlocked yes)
			(layer "B.Fab")
			(hide yes)
			(effects
				(font
					(size 1 1)
					(thickness 0.15)
				)
				(justify mirror)
			)
		)
		(property "License" "Apache-2.0"
			(at 0 0 90)
			(unlocked yes)
			(layer "B.Fab")
			(hide yes)
			(effects
				(font
					(size 1 1)
					(thickness 0.15)
				)
				(justify mirror)
			)
		)
		(property "Author" "Antmicro"
			(at 0 0 90)
			(unlocked yes)
			(layer "B.Fab")
			(hide yes)
			(effects
				(font
					(size 1 1)
					(thickness 0.15)
				)
				(justify mirror)
			)
		)
		(property "Val" "220R"
			(at 0 0 90)
			(unlocked yes)
			(layer "B.Fab")
			(hide yes)
			(effects
				(font
					(size 1 1)
					(thickness 0.15)
				)
				(justify mirror)
			)
		)
		(property "Tolerance" "1%"
			(at 0 0 90)
			(unlocked yes)
			(layer "B.Fab")
			(hide yes)
			(effects
				(font
					(size 1 1)
					(thickness 0.15)
				)
				(justify mirror)
			)
		)
		(sheetname "/2xRJ45/")
		(sheetfile "2xrj45.kicad_sch")
		(attr smd)
		(fp_rect
			(start -0.925 0.47)
			(end 0.925 -0.47)
			(stroke
				(width 0.05)
				(type default)
			)
			(fill no)
			(layer "B.CrtYd")
		)
		(fp_rect
			(start -0.5 0.25)
			(end 0.5 -0.25)
			(stroke
				(width 0.15)
				(type solid)
			)
			(fill no)
			(layer "B.Fab")
		)
		(pad "1" smd roundrect
			(at -0.48 0 90)
			(size 0.59 0.64)
			(layers "B.Cu" "B.Mask" "B.Paste")
			(roundrect_rratio 0.25)
			(net 54 "Net-(J3-LED_GRN-)")
			(pintype "passive")
		)
		(pad "2" smd roundrect
			(at 0.48 0 90)
			(size 0.59 0.64)
			(layers "B.Cu" "B.Mask" "B.Paste")
			(roundrect_rratio 0.25)
			(net 82 "/2xRJ45/~{P0_LED_ACT}")
			(pintype "passive")
		)
	)
	(footprint "antmicro-footprints:SOD-523"
		(layer "B.Cu")
		(at 74.9 86.75 -90)
		(property "Reference" "D12"
			(at 1.12 -2.57 90)
			(layer "B.SilkS")
			(effects
				(font
					(size 0.7 0.7)
					(thickness 0.15)
				)
				(justify right bottom mirror)
			)
		)
		(property "Value" "RB521S30T1G"
			(at 0 -1.499 90)
			(layer "B.Fab")
			(hide yes)
			(effects
				(font
					(size 0.7 0.7)
					(thickness 0.15)
				)
				(justify left bottom mirror)
			)
		)
		(property "Datasheet" "https://www.onsemi.com/pdf/datasheet/rb521s30t1-d.pdf"
			(at 0 0 90)
			(layer "B.Fab")
			(hide yes)
			(effects
				(font
					(size 1.27 1.27)
					(thickness 0.15)
				)
				(justify mirror)
			)
		)
		(property "Description" "Small Signal Schottky Diode, Single, 30 V, 200 mA, 500 mV, 1 A, 125 °C"
			(at 0 0 90)
			(layer "B.Fab")
			(hide yes)
			(effects
				(font
					(size 1.27 1.27)
					(thickness 0.15)
				)
				(justify mirror)
			)
		)
		(property "MPN" "RB521S30T1G"
			(at 0 0 270)
			(unlocked yes)
			(layer "B.Fab")
			(hide yes)
			(effects
				(font
					(size 1 1)
					(thickness 0.15)
				)
				(justify mirror)
			)
		)
		(property "Manufacturer" "ON Semiconductor"
			(at 0 0 270)
			(unlocked yes)
			(layer "B.Fab")
			(hide yes)
			(effects
				(font
					(size 1 1)
					(thickness 0.15)
				)
				(justify mirror)
			)
		)
		(property "Author" "Antmicro"
			(at 0 0 270)
			(unlocked yes)
			(layer "B.Fab")
			(hide yes)
			(effects
				(font
					(size 1 1)
					(thickness 0.15)
				)
				(justify mirror)
			)
		)
		(property "License" "Apache-2.0"
			(at 0 0 270)
			(unlocked yes)
			(layer "B.Fab")
			(hide yes)
			(effects
				(font
					(size 1 1)
					(thickness 0.15)
				)
				(justify mirror)
			)
		)
		(sheetname "/Flash memory/")
		(sheetfile "flash-memory.kicad_sch")
		(attr smd)
		(fp_line
			(start -0.35 0.5)
			(end -0.35 -0.5)
			(stroke
				(width 0.15)
				(type solid)
			)
			(layer "B.SilkS")
		)
		(fp_rect
			(start -1 0.6)
			(end 1 -0.6)
			(stroke
				(width 0.05)
				(type solid)
			)
			(fill no)
			(layer "B.CrtYd")
		)
		(fp_line
			(start -0.652 0.425)
			(end 0.65 0.425)
			(stroke
				(width 0.15)
				(type solid)
			)
			(layer "B.Fab")
		)
		(fp_line
			(start 0.65 0.425)
			(end 0.65 -0.423)
			(stroke
				(width 0.15)
				(type solid)
			)
			(layer "B.Fab")
		)
		(fp_line
			(start -0.35 0.4)
			(end -0.35 -0.4)
			(stroke
				(width 0.15)
				(type solid)
			)
			(layer "B.Fab")
		)
		(fp_line
			(start -0.652 -0.423)
			(end -0.652 0.425)
			(stroke
				(width 0.15)
				(type solid)
			)
			(layer "B.Fab")
		)
		(fp_line
			(start -0.652 -0.423)
			(end 0.65 -0.423)
			(stroke
				(width 0.15)
				(type solid)
			)
			(layer "B.Fab")
		)
		(pad "1" smd roundrect
			(at -0.701 0 270)
			(size 0.5 0.6)
			(layers "B.Cu" "B.Mask" "B.Paste")
			(roundrect_rratio 0.25)
			(net 110 "/Flash memory/+3V3_FLASH")
			(pinfunction "C")
			(pintype "passive")
		)
		(pad "2" smd roundrect
			(at 0.699 0 270)
			(size 0.5 0.6)
			(layers "B.Cu" "B.Mask" "B.Paste")
			(roundrect_rratio 0.25)
			(net 7 "+3V3")
			(pinfunction "A")
			(pintype "passive")
		)
	)
	(footprint "antmicro-footprints:R_0402_1005Metric"
		(layer "B.Cu")
		(at 109.49 86.76 90)
		(descr "Resistor SMD 0402")
		(tags "resistor SMD 0402")
		(property "Reference" "R128"
			(at 0.81 -0.31 90)
			(layer "B.SilkS")
			(effects
				(font
					(size 0.7 0.7)
					(thickness 0.15)
				)
				(justify right top mirror)
			)
		)
		(property "Value" "R_1k_0402"
			(at -1.011843 -1.772046 90)
			(layer "B.Fab")
			(hide yes)
			(effects
				(font
					(size 0.7 0.7)
					(thickness 0.15)
				)
				(justify right top mirror)
			)
		)
		(property "Datasheet" "https://www.bourns.com/docs/product-datasheets/cr.pdf"
			(at 0 0 90)
			(layer "B.Fab")
			(hide yes)
			(effects
				(font
					(size 1.27 1.27)
					(thickness 0.15)
				)
				(justify mirror)
			)
		)
		(property "Description" "SMD Chip Resistor, 1 kohm, ± 1%, 63 mW, 0402 [1005 Metric], Thick Film, General Purpose"
			(at 0 0 90)
			(layer "B.Fab")
			(hide yes)
			(effects
				(font
					(size 1.27 1.27)
					(thickness 0.15)
				)
				(justify mirror)
			)
		)
		(property "MPN" "CR0402-FX-1001GLF"
			(at 0 0 90)
			(unlocked yes)
			(layer "B.Fab")
			(hide yes)
			(effects
				(font
					(size 1 1)
					(thickness 0.15)
				)
				(justify mirror)
			)
		)
		(property "Manufacturer" "Bourns"
			(at 0 0 90)
			(unlocked yes)
			(layer "B.Fab")
			(hide yes)
			(effects
				(font
					(size 1 1)
					(thickness 0.15)
				)
				(justify mirror)
			)
		)
		(property "License" "Apache-2.0"
			(at 0 0 90)
			(unlocked yes)
			(layer "B.Fab")
			(hide yes)
			(effects
				(font
					(size 1 1)
					(thickness 0.15)
				)
				(justify mirror)
			)
		)
		(property "Author" "Antmicro"
			(at 0 0 90)
			(unlocked yes)
			(layer "B.Fab")
			(hide yes)
			(effects
				(font
					(size 1 1)
					(thickness 0.15)
				)
				(justify mirror)
			)
		)
		(property "Val" "1k"
			(at 0 0 90)
			(unlocked yes)
			(layer "B.Fab")
			(hide yes)
			(effects
				(font
					(size 1 1)
					(thickness 0.15)
				)
				(justify mirror)
			)
		)
		(property "Tolerance" "1%"
			(at 0 0 90)
			(unlocked yes)
			(layer "B.Fab")
			(hide yes)
			(effects
				(font
					(size 1 1)
					(thickness 0.15)
				)
				(justify mirror)
			)
		)
		(sheetname "/X710-AT2 RSVD/")
		(sheetfile "x710-at2-rsvd.kicad_sch")
		(attr smd)
		(fp_rect
			(start -0.925 0.47)
			(end 0.925 -0.47)
			(stroke
				(width 0.05)
				(type default)
			)
			(fill no)
			(layer "B.CrtYd")
		)
		(fp_rect
			(start -0.5 0.25)
			(end 0.5 -0.25)
			(stroke
				(width 0.15)
				(type solid)
			)
			(fill no)
			(layer "B.Fab")
		)
		(pad "1" smd roundrect
			(at -0.48 0 90)
			(size 0.59 0.64)
			(layers "B.Cu" "B.Mask" "B.Paste")
			(roundrect_rratio 0.25)
			(net 119 "/X710-AT2 RSVD/DEBUG_Y20")
			(pintype "passive")
		)
		(pad "2" smd roundrect
			(at 0.48 0 90)
			(size 0.59 0.64)
			(layers "B.Cu" "B.Mask" "B.Paste")
			(roundrect_rratio 0.25)
			(net 114 "/X710-AT2 RSVD/DEBUG_EN")
			(pintype "passive")
		)
	)
	(footprint "antmicro-footprints:C_0402_1005Metric"
		(layer "B.Cu")
		(at 103.95 132.39 180)
		(descr "Capacitor SMD 0402")
		(tags "capacitor SMD 0402")
		(property "Reference" "C65"
			(at -2.99 -0.45 0)
			(layer "B.SilkS")
			(effects
				(font
					(size 0.7 0.7)
					(thickness 0.15)
				)
				(justify left bottom mirror)
			)
		)
		(property "Value" "C_1u_25V_0402"
			(at -1.022927 -2.155213 0)
			(layer "B.Fab")
			(hide yes)
			(effects
				(font
					(size 0.7 0.7)
					(thickness 0.15)
				)
				(justify left bottom mirror)
			)
		)
		(property "Datasheet" "https://www.murata.com/products/productdetail?partno=GRM155R61E105KE11%23"
			(at 0 0 0)
			(layer "B.Fab")
			(hide yes)
			(effects
				(font
					(size 1.27 1.27)
					(thickness 0.15)
				)
				(justify mirror)
			)
		)
		(property "Description" "SMD Multilayer Ceramic Capacitor, 1 µF, 25 V, 0402 [1005 Metric], ± 10%, X5R, GRM Series"
			(at 0 0 0)
			(layer "B.Fab")
			(hide yes)
			(effects
				(font
					(size 1.27 1.27)
					(thickness 0.15)
				)
				(justify mirror)
			)
		)
		(property "MPN" "GRM155R61E105KE11J"
			(at 0 0 180)
			(unlocked yes)
			(layer "B.Fab")
			(hide yes)
			(effects
				(font
					(size 1 1)
					(thickness 0.15)
				)
				(justify mirror)
			)
		)
		(property "Manufacturer" "Murata"
			(at 0 0 180)
			(unlocked yes)
			(layer "B.Fab")
			(hide yes)
			(effects
				(font
					(size 1 1)
					(thickness 0.15)
				)
				(justify mirror)
			)
		)
		(property "License" "Apache-2.0"
			(at 0 0 180)
			(unlocked yes)
			(layer "B.Fab")
			(hide yes)
			(effects
				(font
					(size 1 1)
					(thickness 0.15)
				)
				(justify mirror)
			)
		)
		(property "Author" "Antmicro"
			(at 0 0 180)
			(unlocked yes)
			(layer "B.Fab")
			(hide yes)
			(effects
				(font
					(size 1 1)
					(thickness 0.15)
				)
				(justify mirror)
			)
		)
		(property "Val" "1u"
			(at 0 0 180)
			(unlocked yes)
			(layer "B.Fab")
			(hide yes)
			(effects
				(font
					(size 1 1)
					(thickness 0.15)
				)
				(justify mirror)
			)
		)
		(property "Voltage" "25V"
			(at 0 0 180)
			(unlocked yes)
			(layer "B.Fab")
			(hide yes)
			(effects
				(font
					(size 1 1)
					(thickness 0.15)
				)
				(justify mirror)
			)
		)
		(property "Dielectric" "X5R"
			(at 0 0 180)
			(unlocked yes)
			(layer "B.Fab")
			(hide yes)
			(effects
				(font
					(size 1 1)
					(thickness 0.15)
				)
				(justify mirror)
			)
		)
		(sheetname "/2xRJ45/")
		(sheetfile "2xrj45.kicad_sch")
		(attr smd)
		(fp_rect
			(start -0.925 0.47)
			(end 0.925 -0.47)
			(stroke
				(width 0.05)
				(type default)
			)
			(fill no)
			(layer "B.CrtYd")
		)
		(fp_line
			(start 0.504 0.25)
			(end 0.504 -0.248)
			(stroke
				(width 0.15)
				(type solid)
			)
			(layer "B.Fab")
		)
		(fp_line
			(start 0.504 -0.248)
			(end -0.494 -0.248)
			(stroke
				(width 0.15)
				(type solid)
			)
			(layer "B.Fab")
		)
		(fp_line
			(start -0.494 0.25)
			(end 0.504 0.25)
			(stroke
				(width 0.15)
				(type solid)
			)
			(layer "B.Fab")
		)
		(fp_line
			(start -0.494 -0.248)
			(end -0.494 0.25)
			(stroke
				(width 0.15)
				(type solid)
			)
			(layer "B.Fab")
		)
		(pad "1" smd roundrect
			(at -0.48 0 180)
			(size 0.59 0.64)
			(layers "B.Cu" "B.Mask" "B.Paste")
			(roundrect_rratio 0.25)
			(net 28 "GND")
			(pintype "passive")
		)
		(pad "2" smd roundrect
			(at 0.48 0 180)
			(size 0.59 0.64)
			(layers "B.Cu" "B.Mask" "B.Paste")
			(roundrect_rratio 0.25)
			(net 300 "/2xRJ45/P1_CT")
			(pintype "passive")
		)
	)
	(footprint "antmicro-footprints:R_0402_1005Metric"
		(layer "B.Cu")
		(at 100.62 90.644 90)
		(descr "Resistor SMD 0402")
		(tags "resistor SMD 0402")
		(property "Reference" "R126"
			(at -0.806 0.43 90)
			(layer "B.SilkS")
			(effects
				(font
					(size 0.7 0.7)
					(thickness 0.15)
				)
				(justify left bottom mirror)
			)
		)
		(property "Value" "R_49R9_0402"
			(at -1.011843 -1.772047 90)
			(layer "B.Fab")
			(hide yes)
			(effects
				(font
					(size 0.7 0.7)
					(thickness 0.15)
				)
				(justify right top mirror)
			)
		)
		(property "Datasheet" "https://www.bourns.com/docs/product-datasheets/cr.pdf"
			(at 0 0 90)
			(layer "B.Fab")
			(hide yes)
			(effects
				(font
					(size 1.27 1.27)
					(thickness 0.15)
				)
				(justify mirror)
			)
		)
		(property "Description" "SMD Chip Resistor, 49.9 ohm, ± 1%, 62.5 mW, 0402 [1005 Metric], Thick Film, General Purpose"
			(at 0 0 90)
			(layer "B.Fab")
			(hide yes)
			(effects
				(font
					(size 1.27 1.27)
					(thickness 0.15)
				)
				(justify mirror)
			)
		)
		(property "MPN" "CR0402-FX-49R9GLF"
			(at 0 0 270)
			(unlocked yes)
			(layer "B.Fab")
			(hide yes)
			(effects
				(font
					(size 1 1)
					(thickness 0.15)
				)
				(justify mirror)
			)
		)
		(property "Manufacturer" "Bourns"
			(at 0 0 270)
			(unlocked yes)
			(layer "B.Fab")
			(hide yes)
			(effects
				(font
					(size 1 1)
					(thickness 0.15)
				)
				(justify mirror)
			)
		)
		(property "License" "Apache-2.0"
			(at 0 0 270)
			(unlocked yes)
			(layer "B.Fab")
			(hide yes)
			(effects
				(font
					(size 1 1)
					(thickness 0.15)
				)
				(justify mirror)
			)
		)
		(property "Author" "Antmicro"
			(at 0 0 270)
			(unlocked yes)
			(layer "B.Fab")
			(hide yes)
			(effects
				(font
					(size 1 1)
					(thickness 0.15)
				)
				(justify mirror)
			)
		)
		(property "Val" "49R9"
			(at 0 0 270)
			(unlocked yes)
			(layer "B.Fab")
			(hide yes)
			(effects
				(font
					(size 1 1)
					(thickness 0.15)
				)
				(justify mirror)
			)
		)
		(property "Tolerance" "1%"
			(at 0 0 270)
			(unlocked yes)
			(layer "B.Fab")
			(hide yes)
			(effects
				(font
					(size 1 1)
					(thickness 0.15)
				)
				(justify mirror)
			)
		)
		(sheetname "/X710-AT2 PCIe/")
		(sheetfile "x710-at2-pcie.kicad_sch")
		(attr smd exclude_from_pos_files exclude_from_bom dnp)
		(fp_rect
			(start -0.925 0.47)
			(end 0.925 -0.47)
			(stroke
				(width 0.05)
				(type default)
			)
			(fill no)
			(layer "B.CrtYd")
		)
		(fp_rect
			(start -0.5 0.25)
			(end 0.5 -0.25)
			(stroke
				(width 0.15)
				(type solid)
			)
			(fill no)
			(layer "B.Fab")
		)
		(pad "1" smd roundrect
			(at -0.48 0 90)
			(size 0.59 0.64)
			(layers "B.Cu" "B.Mask" "B.Paste")
			(roundrect_rratio 0.25)
			(net 28 "GND")
			(pintype "passive")
		)
		(pad "2" smd roundrect
			(at 0.48 0 90)
			(size 0.59 0.64)
			(layers "B.Cu" "B.Mask" "B.Paste")
			(roundrect_rratio 0.25)
			(net 405 "/X710-AT2 PCIe/GEN_F_CLK+")
			(pintype "passive")
		)
	)
	(footprint "antmicro-footprints:C_0402_1005Metric"
		(layer "B.Cu")
		(at 89.225 98.294031 90)
		(descr "Capacitor SMD 0402")
		(tags "capacitor SMD 0402")
		(property "Reference" "C110"
			(at 10.69 -0.467857 90)
			(layer "B.SilkS")
			(effects
				(font
					(size 0.7 0.7)
					(thickness 0.15)
				)
				(justify right top mirror)
			)
		)
		(property "Value" "C_1u_25V_0402"
			(at -1.022927 -2.155213 90)
			(layer "B.Fab")
			(hide yes)
			(effects
				(font
					(size 0.7 0.7)
					(thickness 0.15)
				)
				(justify right top mirror)
			)
		)
		(property "Datasheet" "https://www.murata.com/products/productdetail?partno=GRM155R61E105KE11%23"
			(at 0 0 90)
			(layer "B.Fab")
			(hide yes)
			(effects
				(font
					(size 1.27 1.27)
					(thickness 0.15)
				)
				(justify mirror)
			)
		)
		(property "Description" "SMD Multilayer Ceramic Capacitor, 1 µF, 25 V, 0402 [1005 Metric], ± 10%, X5R, GRM Series"
			(at 0 0 90)
			(layer "B.Fab")
			(hide yes)
			(effects
				(font
					(size 1.27 1.27)
					(thickness 0.15)
				)
				(justify mirror)
			)
		)
		(property "MPN" "GRM155R61E105KE11J"
			(at 0 0 90)
			(unlocked yes)
			(layer "B.Fab")
			(hide yes)
			(effects
				(font
					(size 1 1)
					(thickness 0.15)
				)
				(justify mirror)
			)
		)
		(property "Manufacturer" "Murata"
			(at 0 0 90)
			(unlocked yes)
			(layer "B.Fab")
			(hide yes)
			(effects
				(font
					(size 1 1)
					(thickness 0.15)
				)
				(justify mirror)
			)
		)
		(property "License" "Apache-2.0"
			(at 0 0 90)
			(unlocked yes)
			(layer "B.Fab")
			(hide yes)
			(effects
				(font
					(size 1 1)
					(thickness 0.15)
				)
				(justify mirror)
			)
		)
		(property "Author" "Antmicro"
			(at 0 0 90)
			(unlocked yes)
			(layer "B.Fab")
			(hide yes)
			(effects
				(font
					(size 1 1)
					(thickness 0.15)
				)
				(justify mirror)
			)
		)
		(property "Val" "1u"
			(at 0 0 90)
			(unlocked yes)
			(layer "B.Fab")
			(hide yes)
			(effects
				(font
					(size 1 1)
					(thickness 0.15)
				)
				(justify mirror)
			)
		)
		(property "Voltage" "25V"
			(at 0 0 90)
			(unlocked yes)
			(layer "B.Fab")
			(hide yes)
			(effects
				(font
					(size 1 1)
					(thickness 0.15)
				)
				(justify mirror)
			)
		)
		(property "Dielectric" "X5R"
			(at 0 0 90)
			(unlocked yes)
			(layer "B.Fab")
			(hide yes)
			(effects
				(font
					(size 1 1)
					(thickness 0.15)
				)
				(justify mirror)
			)
		)
		(sheetname "/X710-AT2 power/")
		(sheetfile "x710-at2-power.kicad_sch")
		(attr smd)
		(fp_rect
			(start -0.925 0.47)
			(end 0.925 -0.47)
			(stroke
				(width 0.05)
				(type default)
			)
			(fill no)
			(layer "B.CrtYd")
		)
		(fp_line
			(start 0.504 -0.248)
			(end -0.494 -0.248)
			(stroke
				(width 0.15)
				(type solid)
			)
			(layer "B.Fab")
		)
		(fp_line
			(start -0.494 -0.248)
			(end -0.494 0.25)
			(stroke
				(width 0.15)
				(type solid)
			)
			(layer "B.Fab")
		)
		(fp_line
			(start 0.504 0.25)
			(end 0.504 -0.248)
			(stroke
				(width 0.15)
				(type solid)
			)
			(layer "B.Fab")
		)
		(fp_line
			(start -0.494 0.25)
			(end 0.504 0.25)
			(stroke
				(width 0.15)
				(type solid)
			)
			(layer "B.Fab")
		)
		(pad "1" smd roundrect
			(at -0.48 0 90)
			(size 0.59 0.64)
			(layers "B.Cu" "B.Mask" "B.Paste")
			(roundrect_rratio 0.25)
			(net 28 "GND")
			(pintype "passive")
		)
		(pad "2" smd roundrect
			(at 0.48 0 90)
			(size 0.59 0.64)
			(layers "B.Cu" "B.Mask" "B.Paste")
			(roundrect_rratio 0.25)
			(net 9 "VCCD")
			(pintype "passive")
		)
	)
	(footprint "antmicro-footprints:SOT-416"
		(layer "B.Cu")
		(at 56.25 120.4)
		(descr "SOT-416")
		(tags "SOT-416")
		(property "Reference" "Q8"
			(at 1.169999 0.8 90)
			(layer "B.SilkS")
			(effects
				(font
					(size 0.7 0.7)
					(thickness 0.15)
				)
				(justify right top mirror)
			)
		)
		(property "Value" "DTC014T_SOT-416"
			(at 0 -2.000001 0)
			(layer "B.Fab")
			(hide yes)
			(effects
				(font
					(size 0.7 0.7)
					(thickness 0.15)
				)
				(justify right top mirror)
			)
		)
		(property "Datasheet" "https://www.rohm.com/datasheet?p=DTC014TEB&dist=Mouser&media=referral&source=mouser.com&campaign=Mouser"
			(at 0 0 0)
			(layer "B.Fab")
			(hide yes)
			(effects
				(font
					(size 1.27 1.27)
					(thickness 0.15)
				)
				(justify mirror)
			)
		)
		(property "Description" "Bipolar (BJT) Single Transistor with built-in base resistor, NPN, 50V, 100mA, 150mW, SOT-416FL, Surface Mount"
			(at 0 0 0)
			(layer "B.Fab")
			(hide yes)
			(effects
				(font
					(size 1.27 1.27)
					(thickness 0.15)
				)
				(justify mirror)
			)
		)
		(property "Manufacturer" "ROHM Semiconductor"
			(at 0 0 180)
			(unlocked yes)
			(layer "B.Fab")
			(hide yes)
			(effects
				(font
					(size 1 1)
					(thickness 0.15)
				)
				(justify mirror)
			)
		)
		(property "MPN" "DTC014TEBTL"
			(at 0 0 180)
			(unlocked yes)
			(layer "B.Fab")
			(hide yes)
			(effects
				(font
					(size 1 1)
					(thickness 0.15)
				)
				(justify mirror)
			)
		)
		(property "Author" "Antmicro"
			(at 0 0 180)
			(unlocked yes)
			(layer "B.Fab")
			(hide yes)
			(effects
				(font
					(size 1 1)
					(thickness 0.15)
				)
				(justify mirror)
			)
		)
		(property "License" "Apache-2.0"
			(at 0 0 180)
			(unlocked yes)
			(layer "B.Fab")
			(hide yes)
			(effects
				(font
					(size 1 1)
					(thickness 0.15)
				)
				(justify mirror)
			)
		)
		(sheetname "/Power/")
		(sheetfile "power.kicad_sch")
		(attr smd)
		(fp_line
			(start -0.5 0.15)
			(end -0.5 -0.15)
			(stroke
				(width 0.15)
				(type solid)
			)
			(layer "B.SilkS")
		)
		(fp_line
			(start 0.5 -0.9)
			(end -0.5 -0.9)
			(stroke
				(width 0.15)
				(type solid)
			)
			(layer "B.SilkS")
		)
		(fp_line
			(start 0.5 -0.9)
			(end 0.5 -0.7)
			(stroke
				(width 0.15)
				(type solid)
			)
			(layer "B.SilkS")
		)
		(fp_line
			(start 0.508 0.9)
			(end -0.5 0.9)
			(stroke
				(width 0.15)
				(type solid)
			)
			(layer "B.SilkS")
		)
		(fp_line
			(start 0.508 0.9)
			(end 0.508 0.592)
			(stroke
				(width 0.15)
				(type solid)
			)
			(layer "B.SilkS")
		)
		(fp_rect
			(start -1 1.05)
			(end 1 -1.05)
			(stroke
				(width 0.05)
				(type solid)
			)
			(fill no)
			(layer "B.CrtYd")
		)
		(fp_line
			(start -0.05 0.9)
			(end -0.45 0.5)
			(stroke
				(width 0.15)
				(type solid)
			)
			(layer "B.Fab")
		)
		(fp_rect
			(start 0.45 -0.9)
			(end -0.45 0.9)
			(stroke
				(width 0.15)
				(type solid)
			)
			(fill no)
			(layer "B.Fab")
		)
		(fp_text user "License: Apache-2.0"
			(at -1 -5.802 180)
			(layer "B.Fab")
			(effects
				(font
					(size 0.7 0.7)
					(thickness 0.15)
				)
				(justify left bottom mirror)
			)
		)
		(fp_text user "Author: Antmicro"
			(at -1 -4.602 180)
			(layer "B.Fab")
			(effects
				(font
					(size 0.7 0.7)
					(thickness 0.15)
				)
				(justify left bottom mirror)
			)
		)
		(fp_text user "${REFERENCE}"
			(at -1 -3.4 180)
			(layer "B.Fab")
			(effects
				(font
					(size 0.7 0.7)
					(thickness 0.15)
				)
				(justify left bottom mirror)
			)
		)
		(pad "1" smd rect
			(at -0.652 0.5)
			(size 0.6 0.5)
			(layers "B.Cu" "B.Mask" "B.Paste")
			(net 312 "/Power/+1V0_OUT")
			(pinfunction "B")
			(pintype "input")
		)
		(pad "2" smd rect
			(at -0.652 -0.498)
			(size 0.6 0.5)
			(layers "B.Cu" "B.Mask" "B.Paste")
			(net 28 "GND")
			(pinfunction "E")
			(pintype "passive")
		)
		(pad "3" smd rect
			(at 0.65 0)
			(size 0.6 0.5)
			(layers "B.Cu" "B.Mask" "B.Paste")
			(net 418 "Net-(Q8-C)")
			(pinfunction "C")
			(pintype "passive")
		)
	)
	(footprint "antmicro-footprints:R_0402_1005Metric"
		(layer "B.Cu")
		(at 83.225 94.6 90)
		(descr "Resistor SMD 0402")
		(tags "resistor SMD 0402")
		(property "Reference" "R134"
			(at 12.5 -0.462343 90)
			(layer "B.SilkS")
			(effects
				(font
					(size 0.7 0.7)
					(thickness 0.15)
				)
				(justify right top mirror)
			)
		)
		(property "Value" "R_100R_0402"
			(at -1.011843 -1.772046 90)
			(layer "B.Fab")
			(hide yes)
			(effects
				(font
					(size 0.7 0.7)
					(thickness 0.15)
				)
				(justify right top mirror)
			)
		)
		(property "Datasheet" "https://www.bourns.com/docs/product-datasheets/cr.pdf"
			(at 0 0 90)
			(layer "B.Fab")
			(hide yes)
			(effects
				(font
					(size 1.27 1.27)
					(thickness 0.15)
				)
				(justify mirror)
			)
		)
		(property "Description" "SMD Chip Resistor, 100 ohm, ± 1%, 62.5 mW, 0402 [1005 Metric], Thick Film, General Purpose"
			(at 0 0 90)
			(layer "B.Fab")
			(hide yes)
			(effects
				(font
					(size 1.27 1.27)
					(thickness 0.15)
				)
				(justify mirror)
			)
		)
		(property "MPN" "CR0402-FX-1000GLF"
			(at 0 0 90)
			(unlocked yes)
			(layer "B.Fab")
			(hide yes)
			(effects
				(font
					(size 1 1)
					(thickness 0.15)
				)
				(justify mirror)
			)
		)
		(property "Manufacturer" "Bourns"
			(at 0 0 90)
			(unlocked yes)
			(layer "B.Fab")
			(hide yes)
			(effects
				(font
					(size 1 1)
					(thickness 0.15)
				)
				(justify mirror)
			)
		)
		(property "License" "Apache-2.0"
			(at 0 0 90)
			(unlocked yes)
			(layer "B.Fab")
			(hide yes)
			(effects
				(font
					(size 1 1)
					(thickness 0.15)
				)
				(justify mirror)
			)
		)
		(property "Author" "Antmicro"
			(at 0 0 90)
			(unlocked yes)
			(layer "B.Fab")
			(hide yes)
			(effects
				(font
					(size 1 1)
					(thickness 0.15)
				)
				(justify mirror)
			)
		)
		(property "Val" "100R"
			(at 0 0 90)
			(unlocked yes)
			(layer "B.Fab")
			(hide yes)
			(effects
				(font
					(size 1 1)
					(thickness 0.15)
				)
				(justify mirror)
			)
		)
		(property "Tolerance" "1%"
			(at 0 0 90)
			(unlocked yes)
			(layer "B.Fab")
			(hide yes)
			(effects
				(font
					(size 1 1)
					(thickness 0.15)
				)
				(justify mirror)
			)
		)
		(sheetname "/X710-AT2 RSVD/")
		(sheetfile "x710-at2-rsvd.kicad_sch")
		(attr smd)
		(fp_rect
			(start -0.925 0.47)
			(end 0.925 -0.47)
			(stroke
				(width 0.05)
				(type default)
			)
			(fill no)
			(layer "B.CrtYd")
		)
		(fp_rect
			(start -0.5 0.25)
			(end 0.5 -0.25)
			(stroke
				(width 0.15)
				(type solid)
			)
			(fill no)
			(layer "B.Fab")
		)
		(pad "1" smd roundrect
			(at -0.48 0 90)
			(size 0.59 0.64)
			(layers "B.Cu" "B.Mask" "B.Paste")
			(roundrect_rratio 0.25)
			(net 28 "GND")
			(pintype "passive")
		)
		(pad "2" smd roundrect
			(at 0.48 0 90)
			(size 0.59 0.64)
			(layers "B.Cu" "B.Mask" "B.Paste")
			(roundrect_rratio 0.25)
			(net 122 "/X710-AT2 RSVD/RSVDY24_VSS")
			(pintype "passive")
		)
	)
	(footprint "antmicro-footprints:R_0402_1005Metric"
		(layer "B.Cu")
		(at 89.5 111.15 -90)
		(descr "Resistor SMD 0402")
		(tags "resistor SMD 0402")
		(property "Reference" "R142"
			(at 0.76 -0.319195 90)
			(layer "B.SilkS")
			(effects
				(font
					(size 0.7 0.7)
					(thickness 0.15)
				)
				(justify left bottom mirror)
			)
		)
		(property "Value" "R_1k_0402"
			(at -1.011843 -1.772046 90)
			(layer "B.Fab")
			(hide yes)
			(effects
				(font
					(size 0.7 0.7)
					(thickness 0.15)
				)
				(justify left bottom mirror)
			)
		)
		(property "Datasheet" "https://www.bourns.com/docs/product-datasheets/cr.pdf"
			(at 0 0 90)
			(layer "B.Fab")
			(hide yes)
			(effects
				(font
					(size 1.27 1.27)
					(thickness 0.15)
				)
				(justify mirror)
			)
		)
		(property "Description" "SMD Chip Resistor, 1 kohm, ± 1%, 63 mW, 0402 [1005 Metric], Thick Film, General Purpose"
			(at 0 0 90)
			(layer "B.Fab")
			(hide yes)
			(effects
				(font
					(size 1.27 1.27)
					(thickness 0.15)
				)
				(justify mirror)
			)
		)
		(property "MPN" "CR0402-FX-1001GLF"
			(at 0 0 270)
			(unlocked yes)
			(layer "B.Fab")
			(hide yes)
			(effects
				(font
					(size 1 1)
					(thickness 0.15)
				)
				(justify mirror)
			)
		)
		(property "Manufacturer" "Bourns"
			(at 0 0 270)
			(unlocked yes)
			(layer "B.Fab")
			(hide yes)
			(effects
				(font
					(size 1 1)
					(thickness 0.15)
				)
				(justify mirror)
			)
		)
		(property "License" "Apache-2.0"
			(at 0 0 270)
			(unlocked yes)
			(layer "B.Fab")
			(hide yes)
			(effects
				(font
					(size 1 1)
					(thickness 0.15)
				)
				(justify mirror)
			)
		)
		(property "Author" "Antmicro"
			(at 0 0 270)
			(unlocked yes)
			(layer "B.Fab")
			(hide yes)
			(effects
				(font
					(size 1 1)
					(thickness 0.15)
				)
				(justify mirror)
			)
		)
		(property "Val" "1k"
			(at 0 0 270)
			(unlocked yes)
			(layer "B.Fab")
			(hide yes)
			(effects
				(font
					(size 1 1)
					(thickness 0.15)
				)
				(justify mirror)
			)
		)
		(property "Tolerance" "1%"
			(at 0 0 270)
			(unlocked yes)
			(layer "B.Fab")
			(hide yes)
			(effects
				(font
					(size 1 1)
					(thickness 0.15)
				)
				(justify mirror)
			)
		)
		(sheetname "/X710-AT2 RSVD/")
		(sheetfile "x710-at2-rsvd.kicad_sch")
		(attr smd)
		(fp_rect
			(start -0.925 0.47)
			(end 0.925 -0.47)
			(stroke
				(width 0.05)
				(type default)
			)
			(fill no)
			(layer "B.CrtYd")
		)
		(fp_rect
			(start -0.5 0.25)
			(end 0.5 -0.25)
			(stroke
				(width 0.15)
				(type solid)
			)
			(fill no)
			(layer "B.Fab")
		)
		(pad "1" smd roundrect
			(at -0.48 0 270)
			(size 0.59 0.64)
			(layers "B.Cu" "B.Mask" "B.Paste")
			(roundrect_rratio 0.25)
			(net 131 "/X710-AT2 RSVD/RSVDD8_1P88V")
			(pintype "passive")
		)
		(pad "2" smd roundrect
			(at 0.48 0 270)
			(size 0.59 0.64)
			(layers "B.Cu" "B.Mask" "B.Paste")
			(roundrect_rratio 0.25)
			(net 18 "+1V88")
			(pintype "passive")
		)
	)
	(footprint "antmicro-footprints:R_0402_1005Metric"
		(layer "B.Cu")
		(at 91.2 100.15 90)
		(descr "Resistor SMD 0402")
		(tags "resistor SMD 0402")
		(property "Reference" "R137"
			(at 9.87 -0.352343 90)
			(layer "B.SilkS")
			(effects
				(font
					(size 0.7 0.7)
					(thickness 0.15)
				)
				(justify right top mirror)
			)
		)
		(property "Value" "R_100R_0402"
			(at -1.011843 -1.772046 90)
			(layer "B.Fab")
			(hide yes)
			(effects
				(font
					(size 0.7 0.7)
					(thickness 0.15)
				)
				(justify right top mirror)
			)
		)
		(property "Datasheet" "https://www.bourns.com/docs/product-datasheets/cr.pdf"
			(at 0 0 90)
			(layer "B.Fab")
			(hide yes)
			(effects
				(font
					(size 1.27 1.27)
					(thickness 0.15)
				)
				(justify mirror)
			)
		)
		(property "Description" "SMD Chip Resistor, 100 ohm, ± 1%, 62.5 mW, 0402 [1005 Metric], Thick Film, General Purpose"
			(at 0 0 90)
			(layer "B.Fab")
			(hide yes)
			(effects
				(font
					(size 1.27 1.27)
					(thickness 0.15)
				)
				(justify mirror)
			)
		)
		(property "MPN" "CR0402-FX-1000GLF"
			(at 0 0 90)
			(unlocked yes)
			(layer "B.Fab")
			(hide yes)
			(effects
				(font
					(size 1 1)
					(thickness 0.15)
				)
				(justify mirror)
			)
		)
		(property "Manufacturer" "Bourns"
			(at 0 0 90)
			(unlocked yes)
			(layer "B.Fab")
			(hide yes)
			(effects
				(font
					(size 1 1)
					(thickness 0.15)
				)
				(justify mirror)
			)
		)
		(property "License" "Apache-2.0"
			(at 0 0 90)
			(unlocked yes)
			(layer "B.Fab")
			(hide yes)
			(effects
				(font
					(size 1 1)
					(thickness 0.15)
				)
				(justify mirror)
			)
		)
		(property "Author" "Antmicro"
			(at 0 0 90)
			(unlocked yes)
			(layer "B.Fab")
			(hide yes)
			(effects
				(font
					(size 1 1)
					(thickness 0.15)
				)
				(justify mirror)
			)
		)
		(property "Val" "100R"
			(at 0 0 90)
			(unlocked yes)
			(layer "B.Fab")
			(hide yes)
			(effects
				(font
					(size 1 1)
					(thickness 0.15)
				)
				(justify mirror)
			)
		)
		(property "Tolerance" "1%"
			(at 0 0 90)
			(unlocked yes)
			(layer "B.Fab")
			(hide yes)
			(effects
				(font
					(size 1 1)
					(thickness 0.15)
				)
				(justify mirror)
			)
		)
		(sheetname "/X710-AT2 RSVD/")
		(sheetfile "x710-at2-rsvd.kicad_sch")
		(attr smd)
		(fp_rect
			(start -0.925 0.47)
			(end 0.925 -0.47)
			(stroke
				(width 0.05)
				(type default)
			)
			(fill no)
			(layer "B.CrtYd")
		)
		(fp_rect
			(start -0.5 0.25)
			(end 0.5 -0.25)
			(stroke
				(width 0.15)
				(type solid)
			)
			(fill no)
			(layer "B.Fab")
		)
		(pad "1" smd roundrect
			(at -0.48 0 90)
			(size 0.59 0.64)
			(layers "B.Cu" "B.Mask" "B.Paste")
			(roundrect_rratio 0.25)
			(net 28 "GND")
			(pintype "passive")
		)
		(pad "2" smd roundrect
			(at 0.48 0 90)
			(size 0.59 0.64)
			(layers "B.Cu" "B.Mask" "B.Paste")
			(roundrect_rratio 0.25)
			(net 125 "/X710-AT2 RSVD/RSVDN9_VSS")
			(pintype "passive")
		)
	)
	(footprint "antmicro-footprints:C_0402_1005Metric"
		(layer "B.Cu")
		(at 88.225 96.45 90)
		(descr "Capacitor SMD 0402")
		(tags "capacitor SMD 0402")
		(property "Reference" "C113"
			(at 11.58 -0.432343 90)
			(layer "B.SilkS")
			(effects
				(font
					(size 0.7 0.7)
					(thickness 0.15)
				)
				(justify right top mirror)
			)
		)
		(property "Value" "C_1u_25V_0402"
			(at -1.022927 -2.155213 90)
			(layer "B.Fab")
			(hide yes)
			(effects
				(font
					(size 0.7 0.7)
					(thickness 0.15)
				)
				(justify right top mirror)
			)
		)
		(property "Datasheet" "https://www.murata.com/products/productdetail?partno=GRM155R61E105KE11%23"
			(at 0 0 90)
			(layer "B.Fab")
			(hide yes)
			(effects
				(font
					(size 1.27 1.27)
					(thickness 0.15)
				)
				(justify mirror)
			)
		)
		(property "Description" "SMD Multilayer Ceramic Capacitor, 1 µF, 25 V, 0402 [1005 Metric], ± 10%, X5R, GRM Series"
			(at 0 0 90)
			(layer "B.Fab")
			(hide yes)
			(effects
				(font
					(size 1.27 1.27)
					(thickness 0.15)
				)
				(justify mirror)
			)
		)
		(property "MPN" "GRM155R61E105KE11J"
			(at 0 0 90)
			(unlocked yes)
			(layer "B.Fab")
			(hide yes)
			(effects
				(font
					(size 1 1)
					(thickness 0.15)
				)
				(justify mirror)
			)
		)
		(property "Manufacturer" "Murata"
			(at 0 0 90)
			(unlocked yes)
			(layer "B.Fab")
			(hide yes)
			(effects
				(font
					(size 1 1)
					(thickness 0.15)
				)
				(justify mirror)
			)
		)
		(property "License" "Apache-2.0"
			(at 0 0 90)
			(unlocked yes)
			(layer "B.Fab")
			(hide yes)
			(effects
				(font
					(size 1 1)
					(thickness 0.15)
				)
				(justify mirror)
			)
		)
		(property "Author" "Antmicro"
			(at 0 0 90)
			(unlocked yes)
			(layer "B.Fab")
			(hide yes)
			(effects
				(font
					(size 1 1)
					(thickness 0.15)
				)
				(justify mirror)
			)
		)
		(property "Val" "1u"
			(at 0 0 90)
			(unlocked yes)
			(layer "B.Fab")
			(hide yes)
			(effects
				(font
					(size 1 1)
					(thickness 0.15)
				)
				(justify mirror)
			)
		)
		(property "Voltage" "25V"
			(at 0 0 90)
			(unlocked yes)
			(layer "B.Fab")
			(hide yes)
			(effects
				(font
					(size 1 1)
					(thickness 0.15)
				)
				(justify mirror)
			)
		)
		(property "Dielectric" "X5R"
			(at 0 0 90)
			(unlocked yes)
			(layer "B.Fab")
			(hide yes)
			(effects
				(font
					(size 1 1)
					(thickness 0.15)
				)
				(justify mirror)
			)
		)
		(sheetname "/X710-AT2 power/")
		(sheetfile "x710-at2-power.kicad_sch")
		(attr smd)
		(fp_rect
			(start -0.925 0.47)
			(end 0.925 -0.47)
			(stroke
				(width 0.05)
				(type default)
			)
			(fill no)
			(layer "B.CrtYd")
		)
		(fp_line
			(start 0.504 -0.248)
			(end -0.494 -0.248)
			(stroke
				(width 0.15)
				(type solid)
			)
			(layer "B.Fab")
		)
		(fp_line
			(start -0.494 -0.248)
			(end -0.494 0.25)
			(stroke
				(width 0.15)
				(type solid)
			)
			(layer "B.Fab")
		)
		(fp_line
			(start 0.504 0.25)
			(end 0.504 -0.248)
			(stroke
				(width 0.15)
				(type solid)
			)
			(layer "B.Fab")
		)
		(fp_line
			(start -0.494 0.25)
			(end 0.504 0.25)
			(stroke
				(width 0.15)
				(type solid)
			)
			(layer "B.Fab")
		)
		(pad "1" smd roundrect
			(at -0.48 0 90)
			(size 0.59 0.64)
			(layers "B.Cu" "B.Mask" "B.Paste")
			(roundrect_rratio 0.25)
			(net 28 "GND")
			(pintype "passive")
		)
		(pad "2" smd roundrect
			(at 0.48 0 90)
			(size 0.59 0.64)
			(layers "B.Cu" "B.Mask" "B.Paste")
			(roundrect_rratio 0.25)
			(net 9 "VCCD")
			(pintype "passive")
		)
	)
	(footprint "antmicro-footprints:Oscillator_SMD_Abracon_AX3_3.2x2.5x1mm"
		(layer "B.Cu")
		(at 104.675 89.054 180)
		(property "Reference" "Y3"
			(at 0.725 -2.036 0)
			(layer "B.SilkS")
			(effects
				(font
					(size 0.7 0.7)
					(thickness 0.15)
				)
				(justify right top mirror)
			)
		)
		(property "Value" "Oscillator_100MHz_NX324"
			(at 0 -2.8 0)
			(layer "B.Fab")
			(hide yes)
			(effects
				(font
					(size 0.7 0.7)
					(thickness 0.15)
				)
				(justify left bottom mirror)
			)
		)
		(property "Datasheet" "https://www.diodes.com/assets/Datasheets/NX324.pdf"
			(at 0 0 0)
			(layer "B.Fab")
			(hide yes)
			(effects
				(font
					(size 1.27 1.27)
					(thickness 0.15)
				)
				(justify mirror)
			)
		)
		(property "Description" "100 MHz XO (Standard) HCSL Oscillator 3.3V Enable/Disable 6-SMD, No Lead"
			(at 0 0 0)
			(layer "B.Fab")
			(hide yes)
			(effects
				(font
					(size 1.27 1.27)
					(thickness 0.15)
				)
				(justify mirror)
			)
		)
		(property "Manufacturer" "Diodes Incorporated"
			(at 0 0 0)
			(unlocked yes)
			(layer "B.Fab")
			(hide yes)
			(effects
				(font
					(size 1 1)
					(thickness 0.15)
				)
				(justify mirror)
			)
		)
		(property "MPN" "NX3241E0100.000000"
			(at 0 0 0)
			(unlocked yes)
			(layer "B.Fab")
			(hide yes)
			(effects
				(font
					(size 1 1)
					(thickness 0.15)
				)
				(justify mirror)
			)
		)
		(property "Val" "100 MHz"
			(at 0 0 0)
			(unlocked yes)
			(layer "B.Fab")
			(hide yes)
			(effects
				(font
					(size 1 1)
					(thickness 0.15)
				)
				(justify mirror)
			)
		)
		(property "Author" "Antmicro"
			(at 0 0 0)
			(unlocked yes)
			(layer "B.Fab")
			(hide yes)
			(effects
				(font
					(size 1 1)
					(thickness 0.15)
				)
				(justify mirror)
			)
		)
		(property "License" "Apache-2.0"
			(at 0 0 0)
			(unlocked yes)
			(layer "B.Fab")
			(hide yes)
			(effects
				(font
					(size 1 1)
					(thickness 0.15)
				)
				(justify mirror)
			)
		)
		(sheetname "/X710-AT2 PCIe/")
		(sheetfile "x710-at2-pcie.kicad_sch")
		(attr smd exclude_from_pos_files exclude_from_bom dnp)
		(fp_line
			(start 1.5 1.8)
			(end -1.5 1.8)
			(stroke
				(width 0.12)
				(type solid)
			)
			(layer "B.SilkS")
		)
		(fp_line
			(start 1.5 1.5)
			(end 1.5 1.8)
			(stroke
				(width 0.12)
				(type solid)
			)
			(layer "B.SilkS")
		)
		(fp_line
			(start 1.5 -1.8)
			(end 1.5 -1.5)
			(stroke
				(width 0.12)
				(type solid)
			)
			(layer "B.SilkS")
		)
		(fp_line
			(start -1.5 1.8)
			(end -1.5 1.5)
			(stroke
				(width 0.12)
				(type solid)
			)
			(layer "B.SilkS")
		)
		(fp_line
			(start -1.5 -1.5)
			(end -1.5 -1.8)
			(stroke
				(width 0.12)
				(type solid)
			)
			(layer "B.SilkS")
		)
		(fp_line
			(start -1.5 -1.8)
			(end 1.5 -1.8)
			(stroke
				(width 0.12)
				(type solid)
			)
			(layer "B.SilkS")
		)
		(fp_circle
			(center -1.7 1.9)
			(end -1.7 1.85)
			(stroke
				(width 0.15)
				(type solid)
			)
			(fill yes)
			(layer "B.SilkS")
		)
		(fp_rect
			(start 1.6 1.9)
			(end -1.6 -1.9)
			(stroke
				(width 0.05)
				(type solid)
			)
			(fill no)
			(layer "B.CrtYd")
		)
		(fp_line
			(start -0.6 1.6)
			(end -1.3 0.9)
			(stroke
				(width 0.15)
				(type solid)
			)
			(layer "B.Fab")
		)
		(fp_rect
			(start 1.3 1.601)
			(end -1.3 -1.599)
			(stroke
				(width 0.15)
				(type solid)
			)
			(fill no)
			(layer "B.Fab")
		)
		(pad "1" smd rect
			(at -0.8 1.199 270)
			(size 0.9 1.1)
			(layers "B.Cu" "B.Mask" "B.Paste")
			(net 404 "Net-(Y3-EN)")
			(pinfunction "EN")
			(pintype "input")
		)
		(pad "2" smd rect
			(at -0.8 0 270)
			(size 0.9 1.1)
			(layers "B.Cu" "B.Mask" "B.Paste")
			(net 409 "unconnected-(Y3-NC-Pad2)")
			(pinfunction "NC")
			(pintype "no_connect")
		)
		(pad "3" smd rect
			(at -0.8 -1.199 270)
			(size 0.9 1.1)
			(layers "B.Cu" "B.Mask" "B.Paste")
			(net 28 "GND")
			(pinfunction "GND")
			(pintype "power_in")
		)
		(pad "4" smd rect
			(at 0.801 -1.199 270)
			(size 0.9 1.1)
			(layers "B.Cu" "B.Mask" "B.Paste")
			(net 407 "/X710-AT2 PCIe/GEN_CLK+")
			(pinfunction "OUT+")
			(pintype "output")
		)
		(pad "5" smd rect
			(at 0.801 0 270)
			(size 0.9 1.1)
			(layers "B.Cu" "B.Mask" "B.Paste")
			(net 408 "/X710-AT2 PCIe/GEN_CLK-")
			(pinfunction "OUT-")
			(pintype "output")
		)
		(pad "6" smd rect
			(at 0.801 1.199 270)
			(size 0.9 1.1)
			(layers "B.Cu" "B.Mask" "B.Paste")
			(net 7 "+3V3")
			(pinfunction "VCC")
			(pintype "power_in")
		)
	)
	(footprint "antmicro-footprints:C_0402_1005Metric"
		(layer "B.Cu")
		(at 89.225 94.6 90)
		(descr "Capacitor SMD 0402")
		(tags "capacitor SMD 0402")
		(property "Reference" "C94"
			(at 12.5 -0.462343 90)
			(layer "B.SilkS")
			(effects
				(font
					(size 0.7 0.7)
					(thickness 0.15)
				)
				(justify right top mirror)
			)
		)
		(property "Value" "C_1u_25V_0402"
			(at -1.022927 -2.155213 90)
			(layer "B.Fab")
			(hide yes)
			(effects
				(font
					(size 0.7 0.7)
					(thickness 0.15)
				)
				(justify right top mirror)
			)
		)
		(property "Datasheet" "https://www.murata.com/products/productdetail?partno=GRM155R61E105KE11%23"
			(at 0 0 90)
			(layer "B.Fab")
			(hide yes)
			(effects
				(font
					(size 1.27 1.27)
					(thickness 0.15)
				)
				(justify mirror)
			)
		)
		(property "Description" "SMD Multilayer Ceramic Capacitor, 1 µF, 25 V, 0402 [1005 Metric], ± 10%, X5R, GRM Series"
			(at 0 0 90)
			(layer "B.Fab")
			(hide yes)
			(effects
				(font
					(size 1.27 1.27)
					(thickness 0.15)
				)
				(justify mirror)
			)
		)
		(property "MPN" "GRM155R61E105KE11J"
			(at 0 0 90)
			(unlocked yes)
			(layer "B.Fab")
			(hide yes)
			(effects
				(font
					(size 1 1)
					(thickness 0.15)
				)
				(justify mirror)
			)
		)
		(property "Manufacturer" "Murata"
			(at 0 0 90)
			(unlocked yes)
			(layer "B.Fab")
			(hide yes)
			(effects
				(font
					(size 1 1)
					(thickness 0.15)
				)
				(justify mirror)
			)
		)
		(property "License" "Apache-2.0"
			(at 0 0 90)
			(unlocked yes)
			(layer "B.Fab")
			(hide yes)
			(effects
				(font
					(size 1 1)
					(thickness 0.15)
				)
				(justify mirror)
			)
		)
		(property "Author" "Antmicro"
			(at 0 0 90)
			(unlocked yes)
			(layer "B.Fab")
			(hide yes)
			(effects
				(font
					(size 1 1)
					(thickness 0.15)
				)
				(justify mirror)
			)
		)
		(property "Val" "1u"
			(at 0 0 90)
			(unlocked yes)
			(layer "B.Fab")
			(hide yes)
			(effects
				(font
					(size 1 1)
					(thickness 0.15)
				)
				(justify mirror)
			)
		)
		(property "Voltage" "25V"
			(at 0 0 90)
			(unlocked yes)
			(layer "B.Fab")
			(hide yes)
			(effects
				(font
					(size 1 1)
					(thickness 0.15)
				)
				(justify mirror)
			)
		)
		(property "Dielectric" "X5R"
			(at 0 0 90)
			(unlocked yes)
			(layer "B.Fab")
			(hide yes)
			(effects
				(font
					(size 1 1)
					(thickness 0.15)
				)
				(justify mirror)
			)
		)
		(sheetname "/X710-AT2 power/")
		(sheetfile "x710-at2-power.kicad_sch")
		(attr smd)
		(fp_rect
			(start -0.925 0.47)
			(end 0.925 -0.47)
			(stroke
				(width 0.05)
				(type default)
			)
			(fill no)
			(layer "B.CrtYd")
		)
		(fp_line
			(start 0.504 -0.248)
			(end -0.494 -0.248)
			(stroke
				(width 0.15)
				(type solid)
			)
			(layer "B.Fab")
		)
		(fp_line
			(start -0.494 -0.248)
			(end -0.494 0.25)
			(stroke
				(width 0.15)
				(type solid)
			)
			(layer "B.Fab")
		)
		(fp_line
			(start 0.504 0.25)
			(end 0.504 -0.248)
			(stroke
				(width 0.15)
				(type solid)
			)
			(layer "B.Fab")
		)
		(fp_line
			(start -0.494 0.25)
			(end 0.504 0.25)
			(stroke
				(width 0.15)
				(type solid)
			)
			(layer "B.Fab")
		)
		(pad "1" smd roundrect
			(at -0.48 0 90)
			(size 0.59 0.64)
			(layers "B.Cu" "B.Mask" "B.Paste")
			(roundrect_rratio 0.25)
			(net 28 "GND")
			(pintype "passive")
		)
		(pad "2" smd roundrect
			(at 0.48 0 90)
			(size 0.59 0.64)
			(layers "B.Cu" "B.Mask" "B.Paste")
			(roundrect_rratio 0.25)
			(net 1 "VCCA")
			(pintype "passive")
		)
	)
	(footprint "antmicro-footprints:R_0402_1005Metric"
		(layer "B.Cu")
		(at 90.725 107.8 90)
		(descr "Resistor SMD 0402")
		(tags "resistor SMD 0402")
		(property "Reference" "R113"
			(at -1.37 0.665 90)
			(layer "B.SilkS")
			(effects
				(font
					(size 0.7 0.7)
					(thickness 0.15)
				)
				(justify right top mirror)
			)
		)
		(property "Value" "R_1k_0402"
			(at -1.011843 -1.772046 90)
			(layer "B.Fab")
			(hide yes)
			(effects
				(font
					(size 0.7 0.7)
					(thickness 0.15)
				)
				(justify right top mirror)
			)
		)
		(property "Datasheet" "https://www.bourns.com/docs/product-datasheets/cr.pdf"
			(at 0 0 90)
			(layer "B.Fab")
			(hide yes)
			(effects
				(font
					(size 1.27 1.27)
					(thickness 0.15)
				)
				(justify mirror)
			)
		)
		(property "Description" "SMD Chip Resistor, 1 kohm, ± 1%, 63 mW, 0402 [1005 Metric], Thick Film, General Purpose"
			(at 0 0 90)
			(layer "B.Fab")
			(hide yes)
			(effects
				(font
					(size 1.27 1.27)
					(thickness 0.15)
				)
				(justify mirror)
			)
		)
		(property "MPN" "CR0402-FX-1001GLF"
			(at 0 0 90)
			(unlocked yes)
			(layer "B.Fab")
			(hide yes)
			(effects
				(font
					(size 1 1)
					(thickness 0.15)
				)
				(justify mirror)
			)
		)
		(property "Manufacturer" "Bourns"
			(at 0 0 90)
			(unlocked yes)
			(layer "B.Fab")
			(hide yes)
			(effects
				(font
					(size 1 1)
					(thickness 0.15)
				)
				(justify mirror)
			)
		)
		(property "License" "Apache-2.0"
			(at 0 0 90)
			(unlocked yes)
			(layer "B.Fab")
			(hide yes)
			(effects
				(font
					(size 1 1)
					(thickness 0.15)
				)
				(justify mirror)
			)
		)
		(property "Author" "Antmicro"
			(at 0 0 90)
			(unlocked yes)
			(layer "B.Fab")
			(hide yes)
			(effects
				(font
					(size 1 1)
					(thickness 0.15)
				)
				(justify mirror)
			)
		)
		(property "Val" "1k"
			(at 0 0 90)
			(unlocked yes)
			(layer "B.Fab")
			(hide yes)
			(effects
				(font
					(size 1 1)
					(thickness 0.15)
				)
				(justify mirror)
			)
		)
		(property "Tolerance" "1%"
			(at 0 0 90)
			(unlocked yes)
			(layer "B.Fab")
			(hide yes)
			(effects
				(font
					(size 1 1)
					(thickness 0.15)
				)
				(justify mirror)
			)
		)
		(sheetname "/X710-AT2 Misc/")
		(sheetfile "x710-at2-mics.kicad_sch")
		(attr smd)
		(fp_rect
			(start -0.925 0.47)
			(end 0.925 -0.47)
			(stroke
				(width 0.05)
				(type default)
			)
			(fill no)
			(layer "B.CrtYd")
		)
		(fp_rect
			(start -0.5 0.25)
			(end 0.5 -0.25)
			(stroke
				(width 0.15)
				(type solid)
			)
			(fill no)
			(layer "B.Fab")
		)
		(pad "1" smd roundrect
			(at -0.48 0 90)
			(size 0.59 0.64)
			(layers "B.Cu" "B.Mask" "B.Paste")
			(roundrect_rratio 0.25)
			(net 28 "GND")
			(pintype "passive")
		)
		(pad "2" smd roundrect
			(at 0.48 0 90)
			(size 0.59 0.64)
			(layers "B.Cu" "B.Mask" "B.Paste")
			(roundrect_rratio 0.25)
			(net 295 "/X710-AT2 Misc/XTAL_BYPASS")
			(pintype "passive")
		)
	)
	(footprint "antmicro-footprints:L_0402_1005Metric"
		(layer "B.Cu")
		(at 88 130.4)
		(descr "Inductor SMD 0402")
		(tags "Inductor SMD 0402")
		(property "Reference" "L7"
			(at -0.979 2.590999 0)
			(layer "B.SilkS")
			(effects
				(font
					(size 0.7 0.7)
					(thickness 0.15)
				)
				(justify right top mirror)
			)
		)
		(property "Value" "L_2n4_0.85A_0402"
			(at 0 -1.399999 0)
			(layer "B.Fab")
			(hide yes)
			(effects
				(font
					(size 0.7 0.7)
					(thickness 0.15)
				)
				(justify right top mirror)
			)
		)
		(property "Datasheet" "https://www.murata.com/products/productdetail?partno=LQW15AN2N4B00%23"
			(at 0 0 0)
			(layer "B.Fab")
			(hide yes)
			(effects
				(font
					(size 1.27 1.27)
					(thickness 0.15)
				)
				(justify mirror)
			)
		)
		(property "Description" "Wirewound Inductor, 2.4 nH, 0.05 ohm, 15 GHz, 850 mA, 0402 [1005 Metric], LQW15AN"
			(at 0 0 0)
			(layer "B.Fab")
			(hide yes)
			(effects
				(font
					(size 1.27 1.27)
					(thickness 0.15)
				)
				(justify mirror)
			)
		)
		(property "Val" "2n4/0.85A"
			(at 0 0 0)
			(unlocked yes)
			(layer "B.Fab")
			(hide yes)
			(effects
				(font
					(size 1 1)
					(thickness 0.15)
				)
				(justify mirror)
			)
		)
		(property "Manufacturer" "Murata"
			(at 0 0 0)
			(unlocked yes)
			(layer "B.Fab")
			(hide yes)
			(effects
				(font
					(size 1 1)
					(thickness 0.15)
				)
				(justify mirror)
			)
		)
		(property "MPN" "LQW15AN2N4B00D"
			(at 0 0 0)
			(unlocked yes)
			(layer "B.Fab")
			(hide yes)
			(effects
				(font
					(size 1 1)
					(thickness 0.15)
				)
				(justify mirror)
			)
		)
		(property "ISat" "0.85 A"
			(at 0 0 0)
			(unlocked yes)
			(layer "B.Fab")
			(hide yes)
			(effects
				(font
					(size 1 1)
					(thickness 0.15)
				)
				(justify mirror)
			)
		)
		(property "IMax" "0.85 A"
			(at 0 0 0)
			(unlocked yes)
			(layer "B.Fab")
			(hide yes)
			(effects
				(font
					(size 1 1)
					(thickness 0.15)
				)
				(justify mirror)
			)
		)
		(property "Size" "1.0x0.5"
			(at 0 0 0)
			(unlocked yes)
			(layer "B.Fab")
			(hide yes)
			(effects
				(font
					(size 1 1)
					(thickness 0.15)
				)
				(justify mirror)
			)
		)
		(property "Author" "Antmicro"
			(at 0 0 0)
			(unlocked yes)
			(layer "B.Fab")
			(hide yes)
			(effects
				(font
					(size 1 1)
					(thickness 0.15)
				)
				(justify mirror)
			)
		)
		(property "License" "Apache-2.0"
			(at 0 0 0)
			(unlocked yes)
			(layer "B.Fab")
			(hide yes)
			(effects
				(font
					(size 1 1)
					(thickness 0.15)
				)
				(justify mirror)
			)
		)
		(sheetname "/2xRJ45/")
		(sheetfile "2xrj45.kicad_sch")
		(attr smd)
		(fp_rect
			(start -0.925 0.47)
			(end 0.925 -0.47)
			(stroke
				(width 0.05)
				(type default)
			)
			(fill no)
			(layer "B.CrtYd")
		)
		(fp_rect
			(start -0.499 0.249)
			(end 0.499 -0.249)
			(stroke
				(width 0.15)
				(type solid)
			)
			(fill no)
			(layer "B.Fab")
		)
		(pad "1" smd roundrect
			(at -0.48 0)
			(size 0.59 0.64)
			(layers "B.Cu" "B.Mask" "B.Paste")
			(roundrect_rratio 0.25)
			(net 301 "+1V88_CT")
			(pintype "passive")
		)
		(pad "2" smd roundrect
			(at 0.48 0)
			(size 0.59 0.64)
			(layers "B.Cu" "B.Mask" "B.Paste")
			(roundrect_rratio 0.25)
			(net 300 "/2xRJ45/P1_CT")
			(pintype "passive")
		)
	)
	(footprint "antmicro-footprints:C_0402_1005Metric"
		(layer "B.Cu")
		(at 104.34 86.654 180)
		(descr "Capacitor SMD 0402")
		(tags "capacitor SMD 0402")
		(property "Reference" "C199"
			(at -0.99 0.654 0)
			(layer "B.SilkS")
			(effects
				(font
					(size 0.7 0.7)
					(thickness 0.15)
				)
				(justify left bottom mirror)
			)
		)
		(property "Value" "C_100n_0402"
			(at -1.022927 -2.155213 0)
			(layer "B.Fab")
			(hide yes)
			(effects
				(font
					(size 0.7 0.7)
					(thickness 0.15)
				)
				(justify left bottom mirror)
			)
		)
		(property "Datasheet" "https://www.murata.com/products/productdetail?partno=GRM155R61H104KE14%23"
			(at 0 0 0)
			(layer "B.Fab")
			(hide yes)
			(effects
				(font
					(size 1.27 1.27)
					(thickness 0.15)
				)
				(justify mirror)
			)
		)
		(property "Description" "SMD Multilayer Ceramic Capacitor, 0.1 µF, 50 V, 0402 [1005 Metric], ± 10%, X5R, GRM Series"
			(at 0 0 0)
			(layer "B.Fab")
			(hide yes)
			(effects
				(font
					(size 1.27 1.27)
					(thickness 0.15)
				)
				(justify mirror)
			)
		)
		(property "MPN" "GRM155R61H104KE14D"
			(at 0 0 0)
			(unlocked yes)
			(layer "B.Fab")
			(hide yes)
			(effects
				(font
					(size 1 1)
					(thickness 0.15)
				)
				(justify mirror)
			)
		)
		(property "Manufacturer" "Murata"
			(at 0 0 0)
			(unlocked yes)
			(layer "B.Fab")
			(hide yes)
			(effects
				(font
					(size 1 1)
					(thickness 0.15)
				)
				(justify mirror)
			)
		)
		(property "License" "Apache-2.0"
			(at 0 0 0)
			(unlocked yes)
			(layer "B.Fab")
			(hide yes)
			(effects
				(font
					(size 1 1)
					(thickness 0.15)
				)
				(justify mirror)
			)
		)
		(property "Author" "Antmicro"
			(at 0 0 0)
			(unlocked yes)
			(layer "B.Fab")
			(hide yes)
			(effects
				(font
					(size 1 1)
					(thickness 0.15)
				)
				(justify mirror)
			)
		)
		(property "Val" "100n"
			(at 0 0 0)
			(unlocked yes)
			(layer "B.Fab")
			(hide yes)
			(effects
				(font
					(size 1 1)
					(thickness 0.15)
				)
				(justify mirror)
			)
		)
		(property "Voltage" "50V"
			(at 0 0 0)
			(unlocked yes)
			(layer "B.Fab")
			(hide yes)
			(effects
				(font
					(size 1 1)
					(thickness 0.15)
				)
				(justify mirror)
			)
		)
		(property "Dielectric" "X5R"
			(at 0 0 0)
			(unlocked yes)
			(layer "B.Fab")
			(hide yes)
			(effects
				(font
					(size 1 1)
					(thickness 0.15)
				)
				(justify mirror)
			)
		)
		(sheetname "/X710-AT2 PCIe/")
		(sheetfile "x710-at2-pcie.kicad_sch")
		(attr smd exclude_from_pos_files exclude_from_bom dnp)
		(fp_rect
			(start -0.925 0.47)
			(end 0.925 -0.47)
			(stroke
				(width 0.05)
				(type default)
			)
			(fill no)
			(layer "B.CrtYd")
		)
		(fp_line
			(start 0.504 0.25)
			(end 0.504 -0.248)
			(stroke
				(width 0.15)
				(type solid)
			)
			(layer "B.Fab")
		)
		(fp_line
			(start 0.504 -0.248)
			(end -0.494 -0.248)
			(stroke
				(width 0.15)
				(type solid)
			)
			(layer "B.Fab")
		)
		(fp_line
			(start -0.494 0.25)
			(end 0.504 0.25)
			(stroke
				(width 0.15)
				(type solid)
			)
			(layer "B.Fab")
		)
		(fp_line
			(start -0.494 -0.248)
			(end -0.494 0.25)
			(stroke
				(width 0.15)
				(type solid)
			)
			(layer "B.Fab")
		)
		(pad "1" smd roundrect
			(at -0.48 0 180)
			(size 0.59 0.64)
			(layers "B.Cu" "B.Mask" "B.Paste")
			(roundrect_rratio 0.25)
			(net 28 "GND")
			(pintype "passive")
		)
		(pad "2" smd roundrect
			(at 0.48 0 180)
			(size 0.59 0.64)
			(layers "B.Cu" "B.Mask" "B.Paste")
			(roundrect_rratio 0.25)
			(net 7 "+3V3")
			(pintype "passive")
		)
	)
	(footprint "antmicro-footprints:C_0402_1005Metric"
		(layer "B.Cu")
		(at 80.22 103.23 90)
		(descr "Capacitor SMD 0402")
		(tags "capacitor SMD 0402")
		(property "Reference" "C183"
			(at -11.62 -0.04 90)
			(layer "B.SilkS")
			(effects
				(font
					(size 0.7 0.7)
					(thickness 0.15)
				)
				(justify right top mirror)
			)
		)
		(property "Value" "C_1u_25V_0402"
			(at -1.022927 -2.155213 90)
			(layer "B.Fab")
			(hide yes)
			(effects
				(font
					(size 0.7 0.7)
					(thickness 0.15)
				)
				(justify right top mirror)
			)
		)
		(property "Datasheet" "https://www.murata.com/products/productdetail?partno=GRM155R61E105KE11%23"
			(at 0 0 90)
			(layer "B.Fab")
			(hide yes)
			(effects
				(font
					(size 1.27 1.27)
					(thickness 0.15)
				)
				(justify mirror)
			)
		)
		(property "Description" "SMD Multilayer Ceramic Capacitor, 1 µF, 25 V, 0402 [1005 Metric], ± 10%, X5R, GRM Series"
			(at 0 0 90)
			(layer "B.Fab")
			(hide yes)
			(effects
				(font
					(size 1.27 1.27)
					(thickness 0.15)
				)
				(justify mirror)
			)
		)
		(property "MPN" "GRM155R61E105KE11J"
			(at 0 0 90)
			(unlocked yes)
			(layer "B.Fab")
			(hide yes)
			(effects
				(font
					(size 1 1)
					(thickness 0.15)
				)
				(justify mirror)
			)
		)
		(property "Manufacturer" "Murata"
			(at 0 0 90)
			(unlocked yes)
			(layer "B.Fab")
			(hide yes)
			(effects
				(font
					(size 1 1)
					(thickness 0.15)
				)
				(justify mirror)
			)
		)
		(property "License" "Apache-2.0"
			(at 0 0 90)
			(unlocked yes)
			(layer "B.Fab")
			(hide yes)
			(effects
				(font
					(size 1 1)
					(thickness 0.15)
				)
				(justify mirror)
			)
		)
		(property "Author" "Antmicro"
			(at 0 0 90)
			(unlocked yes)
			(layer "B.Fab")
			(hide yes)
			(effects
				(font
					(size 1 1)
					(thickness 0.15)
				)
				(justify mirror)
			)
		)
		(property "Val" "1u"
			(at 0 0 90)
			(unlocked yes)
			(layer "B.Fab")
			(hide yes)
			(effects
				(font
					(size 1 1)
					(thickness 0.15)
				)
				(justify mirror)
			)
		)
		(property "Voltage" "25V"
			(at 0 0 90)
			(unlocked yes)
			(layer "B.Fab")
			(hide yes)
			(effects
				(font
					(size 1 1)
					(thickness 0.15)
				)
				(justify mirror)
			)
		)
		(property "Dielectric" "X5R"
			(at 0 0 90)
			(unlocked yes)
			(layer "B.Fab")
			(hide yes)
			(effects
				(font
					(size 1 1)
					(thickness 0.15)
				)
				(justify mirror)
			)
		)
		(sheetname "/X710-AT2 power/")
		(sheetfile "x710-at2-power.kicad_sch")
		(attr smd)
		(fp_rect
			(start -0.925 0.47)
			(end 0.925 -0.47)
			(stroke
				(width 0.05)
				(type default)
			)
			(fill no)
			(layer "B.CrtYd")
		)
		(fp_line
			(start 0.504 -0.248)
			(end -0.494 -0.248)
			(stroke
				(width 0.15)
				(type solid)
			)
			(layer "B.Fab")
		)
		(fp_line
			(start -0.494 -0.248)
			(end -0.494 0.25)
			(stroke
				(width 0.15)
				(type solid)
			)
			(layer "B.Fab")
		)
		(fp_line
			(start 0.504 0.25)
			(end 0.504 -0.248)
			(stroke
				(width 0.15)
				(type solid)
			)
			(layer "B.Fab")
		)
		(fp_line
			(start -0.494 0.25)
			(end 0.504 0.25)
			(stroke
				(width 0.15)
				(type solid)
			)
			(layer "B.Fab")
		)
		(pad "1" smd roundrect
			(at -0.48 0 90)
			(size 0.59 0.64)
			(layers "B.Cu" "B.Mask" "B.Paste")
			(roundrect_rratio 0.25)
			(net 28 "GND")
			(pintype "passive")
		)
		(pad "2" smd roundrect
			(at 0.48 0 90)
			(size 0.59 0.64)
			(layers "B.Cu" "B.Mask" "B.Paste")
			(roundrect_rratio 0.25)
			(net 12 "XFI_VDD")
			(pintype "passive")
		)
	)
	(gr_line
		(start 120 50)
		(end 50 50)
		(stroke
			(width 0.12)
			(type solid)
		)
		(layer "Edge.Cuts")
	)
	(gr_line
		(start 120 150)
		(end 120 50)
		(stroke
			(width 0.12)
			(type solid)
		)
		(layer "Edge.Cuts")
	)
	(gr_line
		(start 50 150)
		(end 120 150)
		(stroke
			(width 0.12)
			(type solid)
		)
		(layer "Edge.Cuts")
	)
	(gr_line
		(start 50 50)
		(end 50 150)
		(stroke
			(width 0.12)
			(type solid)
		)
		(layer "Edge.Cuts")
	)
	(gr_text "OCuLink to 10GbE adapter\nRev. ${REVISION} 2/2026"
		(at 118.85 73.3 90)
		(layer "F.Cu")
		(effects
			(font
				(size 0.7 0.7)
				(thickness 0.125)
				(bold yes)
			)
			(justify left bottom)
		)
	)
	(via
		(at 101.525 97.95)
		(size 0.45)
		(drill 0.2)
		(layers "F.Cu" "B.Cu")
		(remove_unused_layers yes)
		(keep_end_layers yes)
		(zone_layer_connections "In2.Cu")
		(net 1)
	)
	(via
		(at 89.225 94.38)
		(size 0.45)
		(drill 0.2)
		(layers "F.Cu" "B.Cu")
		(remove_unused_layers yes)
		(keep_end_layers yes)
		(zone_layer_connections "In2.Cu")
		(net 1)
	)
	(via
		(at 101.525 100.65)
		(size 0.45)
		(drill 0.2)
		(layers "F.Cu" "B.Cu")
		(remove_unused_layers yes)
		(keep_end_layers yes)
		(zone_layer_connections "In2.Cu")
		(net 1)
	)
	(via
		(at 100.85 98.625)
		(size 0.45)
		(drill 0.2)
		(layers "F.Cu" "B.Cu")
		(remove_unused_layers yes)
		(keep_end_layers yes)
		(zone_layer_connections "In2.Cu")
		(net 1)
	)
	(via
		(at 102.2 98.625)
		(size 0.45)
		(drill 0.2)
		(layers "F.Cu" "B.Cu")
		(remove_unused_layers yes)
		(keep_end_layers yes)
		(zone_layer_connections "In2.Cu")
		(net 1)
	)
	(via
		(at 87.225 94.38)
		(size 0.45)
		(drill 0.2)
		(layers "F.Cu" "B.Cu")
		(remove_unused_layers yes)
		(keep_end_layers yes)
		(zone_layer_connections "In2.Cu")
		(net 1)
	)
	(via
		(at 89.225 99.57)
		(size 0.45)
		(drill 0.2)
		(layers "F.Cu" "B.Cu")
		(remove_unused_layers yes)
		(keep_end_layers yes)
		(zone_layer_connections "In2.Cu")
		(net 1)
	)
	(via
		(at 102.2 99.975)
		(size 0.45)
		(drill 0.2)
		(layers "F.Cu" "B.Cu")
		(remove_unused_layers yes)
		(keep_end_layers yes)
		(zone_layer_connections "In2.Cu")
		(net 1)
	)
	(via
		(at 90.225 101.3)
		(size 0.45)
		(drill 0.2)
		(layers "F.Cu" "B.Cu")
		(remove_unused_layers yes)
		(keep_end_layers yes)
		(zone_layer_connections "In2.Cu")
		(net 1)
	)
	(via
		(at 90.225 99.57)
		(size 0.45)
		(drill 0.2)
		(layers "F.Cu" "B.Cu")
		(remove_unused_layers yes)
		(keep_end_layers yes)
		(zone_layer_connections "In2.Cu")
		(net 1)
	)
	(via
		(at 85.225 94.38)
		(size 0.45)
		(drill 0.2)
		(layers "F.Cu" "B.Cu")
		(remove_unused_layers yes)
		(keep_end_layers yes)
		(zone_layer_connections "In2.Cu")
		(net 1)
	)
	(via
		(at 87.225 101.3)
		(size 0.45)
		(drill 0.2)
		(layers "F.Cu" "B.Cu")
		(remove_unused_layers yes)
		(keep_end_layers yes)
		(zone_layer_connections "In2.Cu")
		(net 1)
	)
	(via
		(at 100.85 99.975)
		(size 0.45)
		(drill 0.2)
		(layers "F.Cu" "B.Cu")
		(remove_unused_layers yes)
		(keep_end_layers yes)
		(zone_layer_connections "In2.Cu")
		(net 1)
	)
	(via
		(at 102.2 101.325)
		(size 0.45)
		(drill 0.2)
		(layers "F.Cu" "B.Cu")
		(remove_unused_layers yes)
		(keep_end_layers yes)
		(zone_layer_connections "In2.Cu")
		(net 1)
	)
	(via
		(at 88.225 99.57)
		(size 0.45)
		(drill 0.2)
		(layers "F.Cu" "B.Cu")
		(remove_unused_layers yes)
		(keep_end_layers yes)
		(zone_layer_connections "In2.Cu")
		(net 1)
	)
	(via
		(at 83.82 88.82)
		(size 0.45)
		(drill 0.2)
		(layers "F.Cu" "B.Cu")
		(remove_unused_layers yes)
		(keep_end_layers yes)
		(zone_layer_connections)
		(net 1)
	)
	(via
		(at 86.225 94.38)
		(size 0.45)
		(drill 0.2)
		(layers "F.Cu" "B.Cu")
		(remove_unused_layers yes)
		(keep_end_layers yes)
		(zone_layer_connections "In2.Cu")
		(net 1)
	)
	(via
		(at 101.525 101.975)
		(size 0.45)
		(drill 0.2)
		(layers "F.Cu" "B.Cu")
		(remove_unused_layers yes)
		(keep_end_layers yes)
		(zone_layer_connections "In2.Cu")
		(net 1)
	)
	(via
		(at 100.85 101.325)
		(size 0.45)
		(drill 0.2)
		(layers "F.Cu" "B.Cu")
		(remove_unused_layers yes)
		(keep_end_layers yes)
		(zone_layer_connections "In2.Cu")
		(net 1)
	)
	(via
		(at 101.525 99.3)
		(size 0.45)
		(drill 0.2)
		(layers "F.Cu" "B.Cu")
		(remove_unused_layers yes)
		(keep_end_layers yes)
		(zone_layer_connections "In2.Cu")
		(net 1)
	)
	(via
		(at 88.225 94.38)
		(size 0.45)
		(drill 0.2)
		(layers "F.Cu" "B.Cu")
		(remove_unused_layers yes)
		(keep_end_layers yes)
		(zone_layer_connections "In2.Cu")
		(net 1)
	)
	(via
		(at 88.225 101.3)
		(size 0.45)
		(drill 0.2)
		(layers "F.Cu" "B.Cu")
		(remove_unused_layers yes)
		(keep_end_layers yes)
		(zone_layer_connections "In2.Cu")
		(net 1)
	)
	(via
		(at 89.225 101.3)
		(size 0.45)
		(drill 0.2)
		(layers "F.Cu" "B.Cu")
		(remove_unused_layers yes)
		(keep_end_layers yes)
		(zone_layer_connections "In2.Cu")
		(net 1)
	)
	(segment
		(start 83.82 88.82)
		(end 83.13 88.13)
		(width 0.15)
		(layer "B.Cu")
		(net 1)
	)
	(segment
		(start 83.13 88.13)
		(end 83.13 77.58)
		(width 0.15)
		(layer "B.Cu")
		(net 1)
	)
	(segment
		(start 84.74 75.97)
		(end 84.74 74.55)
		(width 0.15)
		(layer "B.Cu")
		(net 1)
	)
	(segment
		(start 83.13 77.58)
		(end 83.51 77.2)
		(width 0.15)
		(layer "B.Cu")
		(net 1)
	)
	(segment
		(start 83.51 77.2)
		(end 84.74 75.97)
		(width 0.15)
		(layer "B.Cu")
		(net 1)
	)
	(segment
		(start 84.72 92.86)
		(end 85.225 93.365)
		(width 0.15)
		(layer "In5.Cu")
		(net 1)
	)
	(segment
		(start 83.82 88.82)
		(end 84.25 89.25)
		(width 0.15)
		(layer "In5.Cu")
		(net 1)
	)
	(segment
		(start 84.25 89.25)
		(end 84.25 91.97)
		(width 0.15)
		(layer "In5.Cu")
		(net 1)
	)
	(segment
		(start 84.72 92.44)
		(end 84.72 92.86)
		(width 0.15)
		(layer "In5.Cu")
		(net 1)
	)
	(segment
		(start 85.225 93.365)
		(end 85.225 94.38)
		(width 0.15)
		(layer "In5.Cu")
		(net 1)
	)
	(segment
		(start 84.25 91.97)
		(end 84.72 92.44)
		(width 0.15)
		(layer "In5.Cu")
		(net 1)
	)
	(via
		(at 89.725 93.515)
		(size 0.45)
		(drill 0.2)
		(layers "F.Cu" "B.Cu")
		(remove_unused_layers yes)
		(keep_end_layers yes)
		(zone_layer_connections)
		(net 2)
	)
	(segment
		(start 89.725 93.17)
		(end 89.745 93.15)
		(width 0.15)
		(layer "B.Cu")
		(net 2)
	)
	(segment
		(start 89.725 93.515)
		(end 89.725 93.17)
		(width 0.15)
		(layer "B.Cu")
		(net 2)
	)
	(via
		(at 90.725 93.515)
		(size 0.45)
		(drill 0.2)
		(layers "F.Cu" "B.Cu")
		(remove_unused_layers yes)
		(keep_end_layers yes)
		(zone_layer_connections)
		(net 3)
	)
	(segment
		(start 90.725 93.515)
		(end 90.725 93.17)
		(width 0.15)
		(layer "B.Cu")
		(net 3)
	)
	(segment
		(start 90.725 93.17)
		(end 90.705 93.15)
		(width 0.15)
		(layer "B.Cu")
		(net 3)
	)
	(via
		(at 56.97 82.284)
		(size 0.45)
		(drill 0.2)
		(layers "F.Cu" "B.Cu")
		(remove_unused_layers yes)
		(keep_end_layers yes)
		(zone_layer_connections)
		(net 4)
	)
	(via
		(at 76.725 95.245)
		(size 0.45)
		(drill 0.2)
		(layers "F.Cu" "B.Cu")
		(remove_unused_layers yes)
		(keep_end_layers yes)
		(zone_layer_connections)
		(net 4)
	)
	(segment
		(start 66.935355 91.05)
		(end 65.535355 89.65)
		(width 0.15)
		(layer "In5.Cu")
		(net 4)
	)
	(segment
		(start 67.85 91.05)
		(end 66.935355 91.05)
		(width 0.15)
		(layer "In5.Cu")
		(net 4)
	)
	(segment
		(start 76.725 93.275)
		(end 75.7 92.25)
		(width 0.15)
		(layer "In5.Cu")
		(net 4)
	)
	(segment
		(start 60.804483 83.824483)
		(end 59.965517 82.985517)
		(width 0.15)
		(layer "In5.Cu")
		(net 4)
	)
	(segment
		(start 57.622966 82.284)
		(end 56.97 82.284)
		(width 0.15)
		(layer "In5.Cu")
		(net 4)
	)
	(segment
		(start 58.324483 82.985517)
		(end 57.622966 82.284)
		(width 0.15)
		(layer "In5.Cu")
		(net 4)
	)
	(segment
		(start 75.7 92.25)
		(end 74.95 92.25)
		(width 0.15)
		(layer "In5.Cu")
		(net 4)
	)
	(segment
		(start 68.05 91.25)
		(end 67.85 91.05)
		(width 0.15)
		(layer "In5.Cu")
		(net 4)
	)
	(segment
		(start 74.95 92.25)
		(end 73.95 91.25)
		(width 0.15)
		(layer "In5.Cu")
		(net 4)
	)
	(segment
		(start 73.95 91.25)
		(end 68.05 91.25)
		(width 0.15)
		(layer "In5.Cu")
		(net 4)
	)
	(segment
		(start 59.965517 82.985517)
		(end 58.324483 82.985517)
		(width 0.15)
		(layer "In5.Cu")
		(net 4)
	)
	(segment
		(start 64.75 89.65)
		(end 60.804483 85.704483)
		(width 0.15)
		(layer "In5.Cu")
		(net 4)
	)
	(segment
		(start 76.725 95.245)
		(end 76.725 93.275)
		(width 0.15)
		(layer "In5.Cu")
		(net 4)
	)
	(segment
		(start 65.535355 89.65)
		(end 64.75 89.65)
		(width 0.15)
		(layer "In5.Cu")
		(net 4)
	)
	(segment
		(start 60.804483 85.704483)
		(end 60.804483 83.824483)
		(width 0.15)
		(layer "In5.Cu")
		(net 4)
	)
	(via
		(at 76.225 108.22)
		(size 0.45)
		(drill 0.2)
		(layers "F.Cu" "B.Cu")
		(remove_unused_layers yes)
		(keep_end_layers yes)
		(zone_layer_connections "In3.Cu")
		(net 5)
	)
	(via
		(at 79.225 108.22)
		(size 0.45)
		(drill 0.2)
		(layers "F.Cu" "B.Cu")
		(remove_unused_layers yes)
		(keep_end_layers yes)
		(zone_layer_connections "In3.Cu")
		(net 5)
	)
	(via
		(at 78.225 108.22)
		(size 0.45)
		(drill 0.2)
		(layers "F.Cu" "B.Cu")
		(remove_unused_layers yes)
		(keep_end_layers yes)
		(zone_layer_connections "In3.Cu")
		(net 5)
	)
	(via
		(at 73.15 109.9)
		(size 0.45)
		(drill 0.2)
		(layers "F.Cu" "B.Cu")
		(remove_unused_layers yes)
		(keep_end_layers yes)
		(zone_layer_connections "In3.Cu")
		(net 5)
	)
	(via
		(at 77.225 108.22)
		(size 0.45)
		(drill 0.2)
		(layers "F.Cu" "B.Cu")
		(remove_unused_layers yes)
		(keep_end_layers yes)
		(zone_layer_connections "In3.Cu")
		(net 5)
	)
	(via
		(at 72.15 108.9)
		(size 0.45)
		(drill 0.2)
		(layers "F.Cu" "B.Cu")
		(remove_unused_layers yes)
		(keep_end_layers yes)
		(zone_layer_connections "In3.Cu")
		(net 5)
	)
	(via
		(at 72.15 109.9)
		(size 0.45)
		(drill 0.2)
		(layers "F.Cu" "B.Cu")
		(remove_unused_layers yes)
		(keep_end_layers yes)
		(zone_layer_connections "In3.Cu")
		(net 5)
	)
	(via
		(at 73.15 108.9)
		(size 0.45)
		(drill 0.2)
		(layers "F.Cu" "B.Cu")
		(remove_unused_layers yes)
		(keep_end_layers yes)
		(zone_layer_connections "In3.Cu")
		(net 5)
	)
	(segment
		(start 68.64 74.22)
		(end 68.1 74.76)
		(width 0.15)
		(layer "F.Cu")
		(net 6)
	)
	(segment
		(start 74.39 74.22)
		(end 68.64 74.22)
		(width 0.15)
		(layer "F.Cu")
		(net 6)
	)
	(via
		(at 74.39 74.22)
		(size 0.45)
		(drill 0.2)
		(layers "F.Cu" "B.Cu")
		(remove_unused_layers yes)
		(keep_end_layers yes)
		(zone_layer_connections)
		(net 6)
	)
	(via
		(at 65.9 91.55)
		(size 0.45)
		(drill 0.2)
		(layers "F.Cu" "B.Cu")
		(remove_unused_layers yes)
		(keep_end_layers yes)
		(zone_layer_connections "In3.Cu")
		(net 6)
	)
	(via
		(at 65.9 90.550001)
		(size 0.45)
		(drill 0.2)
		(layers "F.Cu" "B.Cu")
		(remove_unused_layers yes)
		(keep_end_layers yes)
		(zone_layer_connections "In3.Cu")
		(net 6)
	)
	(via
		(at 64.9 91.55)
		(size 0.45)
		(drill 0.2)
		(layers "F.Cu" "B.Cu")
		(remove_unused_layers yes)
		(keep_end_layers yes)
		(zone_layer_connections "In3.Cu")
		(net 6)
	)
	(via
		(at 65.9 93.550002)
		(size 0.45)
		(drill 0.2)
		(layers "F.Cu" "B.Cu")
		(remove_unused_layers yes)
		(keep_end_layers yes)
		(zone_layer_connections "In3.Cu")
		(net 6)
	)
	(via
		(at 65.9 92.550002)
		(size 0.45)
		(drill 0.2)
		(layers "F.Cu" "B.Cu")
		(remove_unused_layers yes)
		(keep_end_layers yes)
		(zone_layer_connections "In3.Cu")
		(net 6)
	)
	(via
		(at 64.9 92.549999)
		(size 0.45)
		(drill 0.2)
		(layers "F.Cu" "B.Cu")
		(remove_unused_layers yes)
		(keep_end_layers yes)
		(zone_layer_connections "In3.Cu")
		(net 6)
	)
	(via
		(at 68.1 74.76)
		(size 0.45)
		(drill 0.2)
		(layers "F.Cu" "B.Cu")
		(remove_unused_layers yes)
		(keep_end_layers yes)
		(zone_layer_connections)
		(net 6)
	)
	(via
		(at 80.225 104.76)
		(size 0.45)
		(drill 0.2)
		(layers "F.Cu" "B.Cu")
		(remove_unused_layers yes)
		(keep_end_layers yes)
		(zone_layer_connections "In3.Cu")
		(net 6)
	)
	(via
		(at 82.225 104.76)
		(size 0.45)
		(drill 0.2)
		(layers "F.Cu" "B.Cu")
		(remove_unused_layers yes)
		(keep_end_layers yes)
		(zone_layer_connections "In3.Cu")
		(net 6)
	)
	(via
		(at 64.9 93.549999)
		(size 0.45)
		(drill 0.2)
		(layers "F.Cu" "B.Cu")
		(remove_unused_layers yes)
		(keep_end_layers yes)
		(zone_layer_connections "In3.Cu")
		(net 6)
	)
	(via
		(at 78.225 104.76)
		(size 0.45)
		(drill 0.2)
		(layers "F.Cu" "B.Cu")
		(remove_unused_layers yes)
		(keep_end_layers yes)
		(zone_layer_connections "In3.Cu")
		(net 6)
	)
	(via
		(at 81.225 104.76)
		(size 0.45)
		(drill 0.2)
		(layers "F.Cu" "B.Cu")
		(remove_unused_layers yes)
		(keep_end_layers yes)
		(zone_layer_connections "In3.Cu")
		(net 6)
	)
	(via
		(at 64.9 90.55)
		(size 0.45)
		(drill 0.2)
		(layers "F.Cu" "B.Cu")
		(remove_unused_layers yes)
		(keep_end_layers yes)
		(zone_layer_connections "In3.Cu")
		(net 6)
	)
	(via
		(at 79.225 104.76)
		(size 0.45)
		(drill 0.2)
		(layers "F.Cu" "B.Cu")
		(remove_unused_layers yes)
		(keep_end_layers yes)
		(zone_layer_connections "In3.Cu")
		(net 6)
	)
	(segment
		(start 75.74 74.55)
		(end 74.72 74.55)
		(width 0.15)
		(layer "B.Cu")
		(net 6)
	)
	(segment
		(start 66.95 89.75)
		(end 68.8 89.75)
		(width 0.15)
		(layer "B.Cu")
		(net 6)
	)
	(segment
		(start 68.1 79.3)
		(end 68.1 74.76)
		(width 0.15)
		(layer "B.Cu")
		(net 6)
	)
	(segment
		(start 66.149999 90.550001)
		(end 66.95 89.75)
		(width 0.15)
		(layer "B.Cu")
		(net 6)
	)
	(segment
		(start 70.15 81.35)
		(end 68.1 79.3)
		(width 0.15)
		(layer "B.Cu")
		(net 6)
	)
	(segment
		(start 65.9 90.550001)
		(end 66.149999 90.550001)
		(width 0.15)
		(layer "B.Cu")
		(net 6)
	)
	(segment
		(start 74.72 74.55)
		(end 74.39 74.22)
		(width 0.15)
		(layer "B.Cu")
		(net 6)
	)
	(segment
		(start 70.15 88.4)
		(end 70.15 81.35)
		(width 0.15)
		(layer "B.Cu")
		(net 6)
	)
	(segment
		(start 68.8 89.75)
		(end 70.15 88.4)
		(width 0.15)
		(layer "B.Cu")
		(net 6)
	)
	(segment
		(start 97.88 104.25)
		(end 97.88 105.2)
		(width 0.15)
		(layer "F.Cu")
		(net 7)
	)
	(segment
		(start 91.285001 113.613001)
		(end 91.082 113.41)
		(width 0.15)
		(layer "F.Cu")
		(net 7)
	)
	(segment
		(start 91.082 112.948)
		(end 91.1 112.93)
		(width 0.15)
		(layer "F.Cu")
		(net 7)
	)
	(segment
		(start 53.5 78.48)
		(end 53.5 79.2)
		(width 0.15)
		(layer "F.Cu")
		(net 7)
	)
	(segment
		(start 53.5 79.2)
		(end 53.161 79.539)
		(width 0.15)
		(layer "F.Cu")
		(net 7)
	)
	(segment
		(start 91.8 113.613001)
		(end 91.285001 113.613001)
		(width 0.15)
		(layer "F.Cu")
		(net 7)
	)
	(segment
		(start 71.8 90.825)
		(end 72.8 90.825)
		(width 0.15)
		(layer "F.Cu")
		(net 7)
	)
	(segment
		(start 107.288 97.4)
		(end 107.288 96.551)
		(width 0.3)
		(layer "F.Cu")
		(net 7)
	)
	(segment
		(start 91.082 113.41)
		(end 91.082 112.948)
		(width 0.15)
		(layer "F.Cu")
		(net 7)
	)
	(segment
		(start 106.18 113.569999)
		(end 105.849999 113.9)
		(width 0.5)
		(layer "F.Cu")
		(net 7)
	)
	(segment
		(start 105.849999 113.9)
		(end 105.799999 113.9)
		(width 0.5)
		(layer "F.Cu")
		(net 7)
	)
	(segment
		(start 106.18 112.5)
		(end 106.18 113.569999)
		(width 0.5)
		(layer "F.Cu")
		(net 7)
	)
	(segment
		(start 53.161 79.539)
		(end 53.161 80.22)
		(width 0.15)
		(layer "F.Cu")
		(net 7)
	)
	(segment
		(start 111.35 96.45)
		(end 111.35 95.83)
		(width 0.15)
		(layer "F.Cu")
		(net 7)
	)
	(segment
		(start 97.88 105.2)
		(end 97.88 106.15)
		(width 0.15)
		(layer "F.Cu")
		(net 7)
	)
	(segment
		(start 91.8 113.613001)
		(end 92.649 113.613001)
		(width 0.3)
		(layer "F.Cu")
		(net 7)
	)
	(segment
		(start 55.7 80.22)
		(end 53.161 80.22)
		(width 0.15)
		(layer "F.Cu")
		(net 7)
	)
	(segment
		(start 111.35 92.35)
		(end 111.35 92.97)
		(width 0.15)
		(layer "F.Cu")
		(net 7)
	)
	(segment
		(start 72.8 90.825)
		(end 72.8 90.15)
		(width 0.15)
		(layer "F.Cu")
		(net 7)
	)
	(via
		(at 98.87 104.25)
		(size 0.45)
		(drill 0.2)
		(layers "F.Cu" "B.Cu")
		(remove_unused_layers yes)
		(keep_end_layers yes)
		(zone_layer_connections "In2.Cu")
		(net 7)
	)
	(via
		(at 109.02 68.6)
		(size 0.45)
		(drill 0.2)
		(layers "F.Cu" "B.Cu")
		(remove_unused_layers yes)
		(keep_end_layers yes)
		(zone_layer_connections "In2.Cu")
		(net 7)
	)
	(via
		(at 72.8 90.15)
		(size 0.45)
		(drill 0.2)
		(layers "F.Cu" "B.Cu")
		(remove_unused_layers yes)
		(keep_end_layers yes)
		(zone_layer_connections "In2.Cu")
		(net 7)
	)
	(via
		(at 55.7 80.22)
		(size 0.45)
		(drill 0.2)
		(layers "F.Cu" "B.Cu")
		(remove_unused_layers yes)
		(keep_end_layers yes)
		(zone_layer_connections "In2.Cu")
		(net 7)
	)
	(via
		(at 98.87 106.15)
		(size 0.45)
		(drill 0.2)
		(layers "F.Cu" "B.Cu")
		(remove_unused_layers yes)
		(keep_end_layers yes)
		(zone_layer_connections "In2.Cu")
		(net 7)
	)
	(via
		(at 76.5 84.325)
		(size 0.45)
		(drill 0.2)
		(layers "F.Cu" "B.Cu")
		(remove_unused_layers yes)
		(keep_end_layers yes)
		(zone_layer_connections "In2.Cu")
		(net 7)
	)
	(via
		(at 91.225 101.3)
		(size 0.45)
		(drill 0.2)
		(layers "F.Cu" "B.Cu")
		(remove_unused_layers yes)
		(keep_end_layers yes)
		(zone_layer_connections "In2.Cu")
		(net 7)
	)
	(via
		(at 103.85 85.9)
		(size 0.45)
		(drill 0.2)
		(layers "F.Cu" "B.Cu")
		(remove_unused_layers yes)
		(keep_end_layers yes)
		(zone_layer_connections "In2.Cu")
		(net 7)
	)
	(via
		(at 94.725 96.975)
		(size 0.45)
		(drill 0.2)
		(layers "F.Cu" "B.Cu")
		(remove_unused_layers yes)
		(keep_end_layers yes)
		(zone_layer_connections)
		(net 7)
	)
	(via
		(at 90.225 97.84)
		(size 0.45)
		(drill 0.2)
		(layers "F.Cu" "B.Cu")
		(remove_unused_layers yes)
		(keep_end_layers yes)
		(zone_layer_connections "In2.Cu")
		(net 7)
	)
	(via
		(at 106.2 70.73)
		(size 0.45)
		(drill 0.2)
		(layers "F.Cu" "B.Cu")
		(remove_unused_layers yes)
		(keep_end_layers yes)
		(zone_layer_connections "In2.Cu")
		(net 7)
	)
	(via
		(at 107.2 70.73)
		(size 0.45)
		(drill 0.2)
		(layers "F.Cu" "B.Cu")
		(remove_unused_layers yes)
		(keep_end_layers yes)
		(zone_layer_connections "In2.Cu")
		(net 7)
	)
	(via
		(at 100.82 107.1)
		(size 0.45)
		(drill 0.2)
		(layers "F.Cu" "B.Cu")
		(remove_unused_layers yes)
		(keep_end_layers yes)
		(zone_layer_connections "In2.Cu")
		(net 7)
	)
	(via
		(at 85.225 96.11)
		(size 0.45)
		(drill 0.2)
		(layers "F.Cu" "B.Cu")
		(remove_unused_layers yes)
		(keep_end_layers yes)
		(zone_layer_connections "In2.Cu")
		(net 7)
	)
	(via
		(at 109.02 66.6)
		(size 0.45)
		(drill 0.2)
		(layers "F.Cu" "B.Cu")
		(remove_unused_layers yes)
		(keep_end_layers yes)
		(zone_layer_connections "In2.Cu")
		(net 7)
	)
	(via
		(at 106.68 87.36)
		(size 0.45)
		(drill 0.2)
		(layers "F.Cu" "B.Cu")
		(remove_unused_layers yes)
		(keep_end_layers yes)
		(zone_layer_connections "In2.Cu")
		(net 7)
	)
	(via
		(at 81.77 83.15)
		(size 0.45)
		(drill 0.2)
		(layers "F.Cu" "B.Cu")
		(remove_unused_layers yes)
		(keep_end_layers yes)
		(zone_layer_connections "In2.Cu")
		(net 7)
	)
	(via
		(at 117.062 98.828)
		(size 0.45)
		(drill 0.2)
		(layers "F.Cu" "B.Cu")
		(remove_unused_layers yes)
		(keep_end_layers yes)
		(zone_layer_connections "In2.Cu")
		(net 7)
	)
	(via
		(at 91.8 113.613001)
		(size 0.45)
		(drill 0.2)
		(layers "F.Cu" "B.Cu")
		(remove_unused_layers yes)
		(keep_end_layers yes)
		(zone_layer_connections "In2.Cu")
		(net 7)
	)
	(via
		(at 97.88 105.2)
		(size 0.45)
		(drill 0.2)
		(layers "F.Cu" "B.Cu")
		(remove_unused_layers yes)
		(keep_end_layers yes)
		(zone_layer_connections "In2.Cu")
		(net 7)
	)
	(via
		(at 73.4 93.7)
		(size 0.45)
		(drill 0.2)
		(layers "F.Cu" "B.Cu")
		(remove_unused_layers yes)
		(keep_end_layers yes)
		(zone_layer_connections)
		(net 7)
	)
	(via
		(at 76.5 87.025)
		(size 0.45)
		(drill 0.2)
		(layers "F.Cu" "B.Cu")
		(remove_unused_layers yes)
		(keep_end_layers yes)
		(zone_layer_connections "In2.Cu")
		(net 7)
	)
	(via
		(at 97.36 110.95)
		(size 0.45)
		(drill 0.2)
		(layers "F.Cu" "B.Cu")
		(remove_unused_layers yes)
		(keep_end_layers yes)
		(zone_layer_connections "In2.Cu")
		(net 7)
	)
	(via
		(at 97.55 100.65)
		(size 0.45)
		(drill 0.2)
		(layers "F.Cu" "B.Cu")
		(remove_unused_layers yes)
		(keep_end_layers yes)
		(zone_layer_connections)
		(net 7)
	)
	(via
		(at 98.87 103.3)
		(size 0.45)
		(drill 0.2)
		(layers "F.Cu" "B.Cu")
		(remove_unused_layers yes)
		(keep_end_layers yes)
		(zone_layer_connections "In2.Cu")
		(net 7)
	)
	(via
		(at 78.725 96.975)
		(size 0.45)
		(drill 0.2)
		(layers "F.Cu" "B.Cu")
		(remove_unused_layers yes)
		(keep_end_layers yes)
		(zone_layer_connections "In2.Cu")
		(net 7)
	)
	(via
		(at 90.225 94.38)
		(size 0.45)
		(drill 0.2)
		(layers "F.Cu" "B.Cu")
		(remove_unused_layers yes)
		(keep_end_layers yes)
		(zone_layer_connections "In2.Cu")
		(net 7)
	)
	(via
		(at 100.82 106.15)
		(size 0.45)
		(drill 0.2)
		(layers "F.Cu" "B.Cu")
		(remove_unused_layers yes)
		(keep_end_layers yes)
		(zone_layer_connections "In2.Cu")
		(net 7)
	)
	(via
		(at 74.899998 87.159997)
		(size 0.45)
		(drill 0.2)
		(layers "F.Cu" "B.Cu")
		(remove_unused_layers yes)
		(keep_end_layers yes)
		(zone_layer_connections "In2.Cu")
		(net 7)
	)
	(via
		(at 76.5 82.975)
		(size 0.45)
		(drill 0.2)
		(layers "F.Cu" "B.Cu")
		(remove_unused_layers yes)
		(keep_end_layers yes)
		(zone_layer_connections "In2.Cu")
		(net 7)
	)
	(via
		(at 76.5 81.625)
		(size 0.45)
		(drill 0.2)
		(layers "F.Cu" "B.Cu")
		(remove_unused_layers yes)
		(keep_end_layers yes)
		(zone_layer_connections "In2.Cu")
		(net 7)
	)
	(via
		(at 106.18 112.5)
		(size 0.45)
		(drill 0.2)
		(layers "F.Cu" "B.Cu")
		(remove_unused_layers yes)
		(keep_end_layers yes)
		(zone_layer_connections "In2.Cu")
		(net 7)
	)
	(via
		(at 111.35 96.45)
		(size 0.45)
		(drill 0.2)
		(layers "F.Cu" "B.Cu")
		(remove_unused_layers yes)
		(keep_end_layers yes)
		(zone_layer_connections "In2.Cu")
		(net 7)
	)
	(via
		(at 97.55 97.95)
		(size 0.45)
		(drill 0.2)
		(layers "F.Cu" "B.Cu")
		(remove_unused_layers yes)
		(keep_end_layers yes)
		(zone_layer_connections)
		(net 7)
	)
	(via
		(at 107.288 97.4)
		(size 0.45)
		(drill 0.2)
		(layers "F.Cu" "B.Cu")
		(remove_unused_layers yes)
		(keep_end_layers yes)
		(zone_layer_connections "In2.Cu")
		(net 7)
	)
	(via
		(at 109.02 70.6)
		(size 0.45)
		(drill 0.2)
		(layers "F.Cu" "B.Cu")
		(remove_unused_layers yes)
		(keep_end_layers yes)
		(zone_layer_connections "In2.Cu")
		(net 7)
	)
	(via
		(at 111.35 92.35)
		(size 0.45)
		(drill 0.2)
		(layers "F.Cu" "B.Cu")
		(remove_unused_layers yes)
		(keep_end_layers yes)
		(zone_layer_connections "In2.Cu")
		(net 7)
	)
	(via
		(at 97.55 99.3)
		(size 0.45)
		(drill 0.2)
		(layers "F.Cu" "B.Cu")
		(remove_unused_layers yes)
		(keep_end_layers yes)
		(zone_layer_connections)
		(net 7)
	)
	(via
		(at 97.55 102)
		(size 0.45)
		(drill 0.2)
		(layers "F.Cu" "B.Cu")
		(remove_unused_layers yes)
		(keep_end_layers yes)
		(zone_layer_connections "In2.Cu")
		(net 7)
	)
	(via
		(at 56.97 83.244)
		(size 0.45)
		(drill 0.2)
		(layers "F.Cu" "B.Cu")
		(remove_unused_layers yes)
		(keep_end_layers yes)
		(zone_layer_connections "In2.Cu")
		(net 7)
	)
	(via
		(at 76.5 85.675)
		(size 0.45)
		(drill 0.2)
		(layers "F.Cu" "B.Cu")
		(remove_unused_layers yes)
		(keep_end_layers yes)
		(zone_layer_connections "In2.Cu")
		(net 7)
	)
	(segment
		(start 107.288 96.883001)
		(end 107.285 96.88)
		(width 0.3)
		(layer "B.Cu")
		(net 7)
	)
	(segment
		(start 79.55 96.92)
		(end 78.78 96.92)
		(width 0.3)
		(layer "B.Cu")
		(net 7)
	)
	(segment
		(start 78.78 96.92)
		(end 78.725 96.975)
		(width 0.3)
		(layer "B.Cu")
		(net 7)
	)
	(segment
		(start 103.86 85.91)
		(end 103.85 85.9)
		(width 0.2)
		(layer "B.Cu")
		(net 7)
	)
	(segment
		(start 92.317 113.613001)
		(end 92.32 113.610001)
		(width 0.3)
		(layer "B.Cu")
		(net 7)
	)
	(segment
		(start 91.8 113.613001)
		(end 92.317 113.613001)
		(width 0.3)
		(layer "B.Cu")
		(net 7)
	)
	(segment
		(start 106.67 86.644)
		(end 106.67 87.35)
		(width 0.2)
		(layer "B.Cu")
		(net 7)
	)
	(segment
		(start 76.5 76.04)
		(end 76.5 81.625)
		(width 0.15)
		(layer "B.Cu")
		(net 7)
	)
	(segment
		(start 73.52 96.65)
		(end 73.52 95.65)
		(width 0.15)
		(layer "B.Cu")
		(net 7)
	)
	(segment
		(start 93.268301 102.348888)
		(end 92.774 102.843189)
		(width 0.15)
		(layer "B.Cu")
		(net 7)
	)
	(segment
		(start 107.288 97.4)
		(end 107.288 96.883001)
		(width 0.5)
		(layer "B.Cu")
		(net 7)
	)
	(segment
		(start 93.268301 101.815926)
		(end 93.268301 102.1)
		(width 0.125)
		(layer "B.Cu")
		(net 7)
	)
	(segment
		(start 92.774 103.856)
		(end 92.18 104.45)
		(width 0.15)
		(layer "B.Cu")
		(net 7)
	)
	(segment
		(start 74.899998 87.159997)
		(end 74.899998 87.448999)
		(width 0.15)
		(layer "B.Cu")
		(net 7)
	)
	(segment
		(start 74.101 94.401)
		(end 73.4 93.7)
		(width 0.15)
		(layer "B.Cu")
		(net 7)
	)
	(segment
		(start 91 112.813001)
		(end 91.8 113.613001)
		(width 0.125)
		(layer "B.Cu")
		(net 7)
	)
	(segment
		(start 91 111.63)
		(end 91 112.813001)
		(width 0.125)
		(layer "B.Cu")
		(net 7)
	)
	(segment
		(start 92.774 102.843189)
		(end 92.774 103.856)
		(width 0.15)
		(layer "B.Cu")
		(net 7)
	)
	(segment
		(start 74.101 95.069)
		(end 74.101 94.401)
		(width 0.15)
		(layer "B.Cu")
		(net 7)
	)
	(segment
		(start 93.268301 102.1)
		(end 93.268301 102.348888)
		(width 0.15)
		(layer "B.Cu")
		(net 7)
	)
	(segment
		(start 73.52 95.65)
		(end 74.101 95.069)
		(width 0.15)
		(layer "B.Cu")
		(net 7)
	)
	(segment
		(start 103.86 86.654)
		(end 103.86 87.841)
		(width 0.2)
		(layer "B.Cu")
		(net 7)
	)
	(segment
		(start 93.268301 101.768301)
		(end 93.268301 101.815926)
		(width 0.15)
		(layer "B.Cu")
		(net 7)
	)
	(segment
		(start 77.99 74.55)
		(end 76.5 76.04)
		(width 0.15)
		(layer "B.Cu")
		(net 7)
	)
	(segment
		(start 92.25 101.52)
		(end 93.02 101.52)
		(width 0.15)
		(layer "B.Cu")
		(net 7)
	)
	(segment
		(start 106.67 87.35)
		(end 106.68 87.36)
		(width 0.2)
		(layer "B.Cu")
		(net 7)
	)
	(segment
		(start 103.86 86.654)
		(end 103.86 85.91)
		(width 0.2)
		(layer "B.Cu")
		(net 7)
	)
	(segment
		(start 93.02 101.52)
		(end 93.268301 101.768301)
		(width 0.15)
		(layer "B.Cu")
		(net 7)
	)
	(segment
		(start 103.86 87.841)
		(end 103.874 87.855)
		(width 0.2)
		(layer "B.Cu")
		(net 7)
	)
	(segment
		(start 74.899998 87.448999)
		(end 74.9 87.449001)
		(width 0.15)
		(layer "B.Cu")
		(net 7)
	)
	(segment
		(start 95.95 96.98)
		(end 94.95 96.98)
		(width 0.15)
		(layer "B.Cu")
		(net 7)
	)
	(segment
		(start 73.4 93.7)
		(end 73.4 93.35)
		(width 0.5)
		(layer "In2.Cu")
		(net 7)
	)
	(segment
		(start 97.55 97.95)
		(end 97.55 102)
		(width 0.5)
		(layer "In2.Cu")
		(net 7)
	)
	(segment
		(start 53.161 81.015)
		(end 53.161 81.18)
		(width 0.15)
		(layer "F.Cu")
		(net 8)
	)
	(via
		(at 53.161 81.015)
		(size 0.45)
		(drill 0.2)
		(layers "F.Cu" "B.Cu")
		(remove_unused_layers yes)
		(keep_end_layers yes)
		(zone_layer_connections)
		(net 8)
	)
	(via
		(at 76.725 96.975)
		(size 0.45)
		(drill 0.2)
		(layers "F.Cu" "B.Cu")
		(remove_unused_layers yes)
		(keep_end_layers yes)
		(zone_layer_connections)
		(net 8)
	)
	(segment
		(start 59.661032 80.4)
		(end 64.360516 85.099484)
		(width 0.15)
		(layer "In5.Cu")
		(net 8)
	)
	(segment
		(start 66.11 87.56)
		(end 67.08 88.53)
		(width 0.15)
		(layer "In5.Cu")
		(net 8)
	)
	(segment
		(start 55.4 81.7)
		(end 56.15 81.7)
		(width 0.15)
		(layer "In5.Cu")
		(net 8)
	)
	(segment
		(start 65.346882 87.286882)
		(end 65.62 87.56)
		(width 0.15)
		(layer "In5.Cu")
		(net 8)
	)
	(segment
		(start 76.65 89.35)
		(end 78.19 90.89)
		(width 0.15)
		(layer "In5.Cu")
		(net 8)
	)
	(segment
		(start 65.62 87.56)
		(end 66.11 87.56)
		(width 0.15)
		(layer "In5.Cu")
		(net 8)
	)
	(segment
		(start 56.15 81.7)
		(end 56.46 81.39)
		(width 0.15)
		(layer "In5.Cu")
		(net 8)
	)
	(segment
		(start 78.728283 92.58187)
		(end 78.728283 95.244528)
		(width 0.15)
		(layer "In5.Cu")
		(net 8)
	)
	(segment
		(start 65.346882 85.806882)
		(end 65.346882 87.286882)
		(width 0.15)
		(layer "In5.Cu")
		(net 8)
	)
	(segment
		(start 53.161 81.015)
		(end 54.715 81.015)
		(width 0.15)
		(layer "In5.Cu")
		(net 8)
	)
	(segment
		(start 67.08 88.53)
		(end 67.48 88.53)
		(width 0.15)
		(layer "In5.Cu")
		(net 8)
	)
	(segment
		(start 78.19 90.89)
		(end 78.19 92.043587)
		(width 0.15)
		(layer "In5.Cu")
		(net 8)
	)
	(segment
		(start 56.46 80.94)
		(end 57 80.4)
		(width 0.15)
		(layer "In5.Cu")
		(net 8)
	)
	(segment
		(start 67.48 88.53)
		(end 68.3 89.35)
		(width 0.15)
		(layer "In5.Cu")
		(net 8)
	)
	(segment
		(start 57 80.4)
		(end 59.661032 80.4)
		(width 0.15)
		(layer "In5.Cu")
		(net 8)
	)
	(segment
		(start 78.728283 95.244528)
		(end 76.997811 96.975)
		(width 0.15)
		(layer "In5.Cu")
		(net 8)
	)
	(segment
		(start 68.3 89.35)
		(end 76.65 89.35)
		(width 0.15)
		(layer "In5.Cu")
		(net 8)
	)
	(segment
		(start 64.360516 85.420516)
		(end 64.49 85.55)
		(width 0.15)
		(layer "In5.Cu")
		(net 8)
	)
	(segment
		(start 64.360516 85.099484)
		(end 64.360516 85.420516)
		(width 0.15)
		(layer "In5.Cu")
		(net 8)
	)
	(segment
		(start 65.09 85.55)
		(end 65.346882 85.806882)
		(width 0.15)
		(layer "In5.Cu")
		(net 8)
	)
	(segment
		(start 76.997811 96.975)
		(end 76.725 96.975)
		(width 0.15)
		(layer "In5.Cu")
		(net 8)
	)
	(segment
		(start 54.715 81.015)
		(end 55.4 81.7)
		(width 0.15)
		(layer "In5.Cu")
		(net 8)
	)
	(segment
		(start 64.49 85.55)
		(end 65.09 85.55)
		(width 0.15)
		(layer "In5.Cu")
		(net 8)
	)
	(segment
		(start 56.46 81.39)
		(end 56.46 80.94)
		(width 0.15)
		(layer "In5.Cu")
		(net 8)
	)
	(segment
		(start 78.19 92.043587)
		(end 78.728283 92.58187)
		(width 0.15)
		(layer "In5.Cu")
		(net 8)
	)
	(segment
		(start 69.42 72.29)
		(end 67.25 74.46)
		(width 0.15)
		(layer "F.Cu")
		(net 9)
	)
	(segment
		(start 67.25 74.46)
		(end 67.25 80.850001)
		(width 0.15)
		(layer "F.Cu")
		(net 9)
	)
	(segment
		(start 67.25 80.850001)
		(end 66 82.100001)
		(width 0.15)
		(layer "F.Cu")
		(net 9)
	)
	(segment
		(start 74.56 72.29)
		(end 69.42 72.29)
		(width 0.15)
		(layer "F.Cu")
		(net 9)
	)
	(via
		(at 65.85 89.050003)
		(size 0.45)
		(drill 0.2)
		(layers "F.Cu" "B.Cu")
		(remove_unused_layers yes)
		(keep_end_layers yes)
		(zone_layer_connections "In3.Cu")
		(net 9)
	)
	(via
		(at 64.85 85.050003)
		(size 0.45)
		(drill 0.2)
		(layers "F.Cu" "B.Cu")
		(remove_unused_layers yes)
		(keep_end_layers yes)
		(zone_layer_connections "In3.Cu")
		(net 9)
	)
	(via
		(at 74.56 72.29)
		(size 0.45)
		(drill 0.2)
		(layers "F.Cu" "B.Cu")
		(remove_unused_layers yes)
		(keep_end_layers yes)
		(zone_layer_connections)
		(net 9)
	)
	(via
		(at 64.85 87.050002)
		(size 0.45)
		(drill 0.2)
		(layers "F.Cu" "B.Cu")
		(remove_unused_layers yes)
		(keep_end_layers yes)
		(zone_layer_connections "In3.Cu")
		(net 9)
	)
	(via
		(at 85.225 99.57)
		(size 0.45)
		(drill 0.2)
		(layers "F.Cu" "B.Cu")
		(remove_unused_layers yes)
		(keep_end_layers yes)
		(zone_layer_connections "In3.Cu")
		(net 9)
	)
	(via
		(at 89.225 97.84)
		(size 0.45)
		(drill 0.2)
		(layers "F.Cu" "B.Cu")
		(remove_unused_layers yes)
		(keep_end_layers yes)
		(zone_layer_connections "In3.Cu")
		(net 9)
	)
	(via
		(at 64.85 82.050006)
		(size 0.45)
		(drill 0.2)
		(layers "F.Cu" "B.Cu")
		(remove_unused_layers yes)
		(keep_end_layers yes)
		(zone_layer_connections "In3.Cu")
		(net 9)
	)
	(via
		(at 88.225 96.11)
		(size 0.45)
		(drill 0.2)
		(layers "F.Cu" "B.Cu")
		(remove_unused_layers yes)
		(keep_end_layers yes)
		(zone_layer_connections "In3.Cu")
		(net 9)
	)
	(via
		(at 65.85 82.050006)
		(size 0.45)
		(drill 0.2)
		(layers "F.Cu" "B.Cu")
		(remove_unused_layers yes)
		(keep_end_layers yes)
		(zone_layer_connections "In3.Cu")
		(net 9)
	)
	(via
		(at 65.85 85.050004)
		(size 0.45)
		(drill 0.2)
		(layers "F.Cu" "B.Cu")
		(remove_unused_layers yes)
		(keep_end_layers yes)
		(zone_layer_connections "In3.Cu")
		(net 9)
	)
	(via
		(at 65.85 86.050003)
		(size 0.45)
		(drill 0.2)
		(layers "F.Cu" "B.Cu")
		(remove_unused_layers yes)
		(keep_end_layers yes)
		(zone_layer_connections "In3.Cu")
		(net 9)
	)
	(via
		(at 87.225 96.11)
		(size 0.45)
		(drill 0.2)
		(layers "F.Cu" "B.Cu")
		(remove_unused_layers yes)
		(keep_end_layers yes)
		(zone_layer_connections "In3.Cu")
		(net 9)
	)
	(via
		(at 86.225 96.11)
		(size 0.45)
		(drill 0.2)
		(layers "F.Cu" "B.Cu")
		(remove_unused_layers yes)
		(keep_end_layers yes)
		(zone_layer_connections "In3.Cu")
		(net 9)
	)
	(via
		(at 64.85 89.05)
		(size 0.45)
		(drill 0.2)
		(layers "F.Cu" "B.Cu")
		(remove_unused_layers yes)
		(keep_end_layers yes)
		(zone_layer_connections "In3.Cu")
		(net 9)
	)
	(via
		(at 86.225 101.3)
		(size 0.45)
		(drill 0.2)
		(layers "F.Cu" "B.Cu")
		(remove_unused_layers yes)
		(keep_end_layers yes)
		(zone_layer_connections "In3.Cu")
		(net 9)
	)
	(via
		(at 87.225 97.84)
		(size 0.45)
		(drill 0.2)
		(layers "F.Cu" "B.Cu")
		(remove_unused_layers yes)
		(keep_end_layers yes)
		(zone_layer_connections "In3.Cu")
		(net 9)
	)
	(via
		(at 88.225 97.84)
		(size 0.45)
		(drill 0.2)
		(layers "F.Cu" "B.Cu")
		(remove_unused_layers yes)
		(keep_end_layers yes)
		(zone_layer_connections "In3.Cu")
		(net 9)
	)
	(via
		(at 91.225 94.38)
		(size 0.45)
		(drill 0.2)
		(layers "F.Cu" "B.Cu")
		(remove_unused_layers yes)
		(keep_end_layers yes)
		(zone_layer_connections "In3.Cu")
		(net 9)
	)
	(via
		(at 87.225 99.57)
		(size 0.45)
		(drill 0.2)
		(layers "F.Cu" "B.Cu")
		(remove_unused_layers yes)
		(keep_end_layers yes)
		(zone_layer_connections "In3.Cu")
		(net 9)
	)
	(via
		(at 65.85 84.050004)
		(size 0.45)
		(drill 0.2)
		(layers "F.Cu" "B.Cu")
		(remove_unused_layers yes)
		(keep_end_layers yes)
		(zone_layer_connections "In3.Cu")
		(net 9)
	)
	(via
		(at 64.85 84.050004)
		(size 0.45)
		(drill 0.2)
		(layers "F.Cu" "B.Cu")
		(remove_unused_layers yes)
		(keep_end_layers yes)
		(zone_layer_connections "In3.Cu")
		(net 9)
	)
	(via
		(at 65.85 88.050004)
		(size 0.45)
		(drill 0.2)
		(layers "F.Cu" "B.Cu")
		(remove_unused_layers yes)
		(keep_end_layers yes)
		(zone_layer_connections "In3.Cu")
		(net 9)
	)
	(via
		(at 65.85 87.050002)
		(size 0.45)
		(drill 0.2)
		(layers "F.Cu" "B.Cu")
		(remove_unused_layers yes)
		(keep_end_layers yes)
		(zone_layer_connections "In3.Cu")
		(net 9)
	)
	(via
		(at 89.225 96.11)
		(size 0.45)
		(drill 0.2)
		(layers "F.Cu" "B.Cu")
		(remove_unused_layers yes)
		(keep_end_layers yes)
		(zone_layer_connections "In3.Cu")
		(net 9)
	)
	(via
		(at 91.725 96.975)
		(size 0.45)
		(drill 0.2)
		(layers "F.Cu" "B.Cu")
		(remove_unused_layers yes)
		(keep_end_layers yes)
		(zone_layer_connections "In3.Cu")
		(net 9)
	)
	(via
		(at 85.225 97.84)
		(size 0.45)
		(drill 0.2)
		(layers "F.Cu" "B.Cu")
		(remove_unused_layers yes)
		(keep_end_layers yes)
		(zone_layer_connections "In3.Cu")
		(net 9)
	)
	(via
		(at 64.85 88.050001)
		(size 0.45)
		(drill 0.2)
		(layers "F.Cu" "B.Cu")
		(remove_unused_layers yes)
		(keep_end_layers yes)
		(zone_layer_connections "In3.Cu")
		(net 9)
	)
	(via
		(at 64.85 86.050002)
		(size 0.45)
		(drill 0.2)
		(layers "F.Cu" "B.Cu")
		(remove_unused_layers yes)
		(keep_end_layers yes)
		(zone_layer_connections "In3.Cu")
		(net 9)
	)
	(via
		(at 64.85 83.050005)
		(size 0.45)
		(drill 0.2)
		(layers "F.Cu" "B.Cu")
		(remove_unused_layers yes)
		(keep_end_layers yes)
		(zone_layer_connections "In3.Cu")
		(net 9)
	)
	(via
		(at 86.225 99.57)
		(size 0.45)
		(drill 0.2)
		(layers "F.Cu" "B.Cu")
		(remove_unused_layers yes)
		(keep_end_layers yes)
		(zone_layer_connections "In3.Cu")
		(net 9)
	)
	(via
		(at 65.85 83.050006)
		(size 0.45)
		(drill 0.2)
		(layers "F.Cu" "B.Cu")
		(remove_unused_layers yes)
		(keep_end_layers yes)
		(zone_layer_connections "In3.Cu")
		(net 9)
	)
	(via
		(at 90.225 96.11)
		(size 0.45)
		(drill 0.2)
		(layers "F.Cu" "B.Cu")
		(remove_unused_layers yes)
		(keep_end_layers yes)
		(zone_layer_connections "In3.Cu")
		(net 9)
	)
	(via
		(at 86.225 97.84)
		(size 0.45)
		(drill 0.2)
		(layers "F.Cu" "B.Cu")
		(remove_unused_layers yes)
		(keep_end_layers yes)
		(zone_layer_connections "In3.Cu")
		(net 9)
	)
	(via
		(at 85.225 101.3)
		(size 0.45)
		(drill 0.2)
		(layers "F.Cu" "B.Cu")
		(remove_unused_layers yes)
		(keep_end_layers yes)
		(zone_layer_connections "In3.Cu")
		(net 9)
	)
	(segment
		(start 75.73 72.29)
		(end 75.74 72.3)
		(width 0.15)
		(layer "B.Cu")
		(net 9)
	)
	(segment
		(start 91.245 96.975)
		(end 91.725 96.975)
		(width 0.5)
		(layer "B.Cu")
		(net 9)
	)
	(segment
		(start 74.56 72.29)
		(end 75.73 72.29)
		(width 0.15)
		(layer "B.Cu")
		(net 9)
	)
	(segment
		(start 91.2 96.93)
		(end 91.245 96.975)
		(width 0.5)
		(layer "B.Cu")
		(net 9)
	)
	(via
		(at 70.95 97.4)
		(size 0.45)
		(drill 0.2)
		(layers "F.Cu" "B.Cu")
		(remove_unused_layers yes)
		(keep_end_layers yes)
		(zone_layer_connections "In2.Cu")
		(net 10)
	)
	(via
		(at 78.225 106.49)
		(size 0.45)
		(drill 0.2)
		(layers "F.Cu" "B.Cu")
		(remove_unused_layers yes)
		(keep_end_layers yes)
		(zone_layer_connections "In2.Cu")
		(net 10)
	)
	(via
		(at 71.95 97.4)
		(size 0.45)
		(drill 0.2)
		(layers "F.Cu" "B.Cu")
		(remove_unused_layers yes)
		(keep_end_layers yes)
		(zone_layer_connections "In2.Cu")
		(net 10)
	)
	(via
		(at 82.225 106.49)
		(size 0.45)
		(drill 0.2)
		(layers "F.Cu" "B.Cu")
		(remove_unused_layers yes)
		(keep_end_layers yes)
		(zone_layer_connections "In2.Cu")
		(net 10)
	)
	(via
		(at 77.225 106.49)
		(size 0.45)
		(drill 0.2)
		(layers "F.Cu" "B.Cu")
		(remove_unused_layers yes)
		(keep_end_layers yes)
		(zone_layer_connections "In2.Cu")
		(net 10)
	)
	(via
		(at 80.725 107.355)
		(size 0.45)
		(drill 0.2)
		(layers "F.Cu" "B.Cu")
		(remove_unused_layers yes)
		(keep_end_layers yes)
		(zone_layer_connections "In2.Cu")
		(net 10)
	)
	(via
		(at 72.45 98)
		(size 0.45)
		(drill 0.2)
		(layers "F.Cu" "B.Cu")
		(remove_unused_layers yes)
		(keep_end_layers yes)
		(zone_layer_connections "In2.Cu")
		(net 10)
	)
	(via
		(at 70.45 98)
		(size 0.45)
		(drill 0.2)
		(layers "F.Cu" "B.Cu")
		(remove_unused_layers yes)
		(keep_end_layers yes)
		(zone_layer_connections "In2.Cu")
		(net 10)
	)
	(via
		(at 81.225 106.49)
		(size 0.45)
		(drill 0.2)
		(layers "F.Cu" "B.Cu")
		(remove_unused_layers yes)
		(keep_end_layers yes)
		(zone_layer_connections "In2.Cu")
		(net 10)
	)
	(via
		(at 71.45 98)
		(size 0.45)
		(drill 0.2)
		(layers "F.Cu" "B.Cu")
		(remove_unused_layers yes)
		(keep_end_layers yes)
		(zone_layer_connections "In2.Cu")
		(net 10)
	)
	(segment
		(start 55.7 81.18)
		(end 55.7 81.015)
		(width 0.15)
		(layer "F.Cu")
		(net 11)
	)
	(via
		(at 55.7 81.015)
		(size 0.45)
		(drill 0.2)
		(layers "F.Cu" "B.Cu")
		(remove_unused_layers yes)
		(keep_end_layers yes)
		(zone_layer_connections)
		(net 11)
	)
	(via
		(at 77.725 96.975)
		(size 0.45)
		(drill 0.2)
		(layers "F.Cu" "B.Cu")
		(remove_unused_layers yes)
		(keep_end_layers yes)
		(zone_layer_connections)
		(net 11)
	)
	(segment
		(start 66.08 84.57)
		(end 64.67 84.57)
		(width 0.15)
		(layer "In5.Cu")
		(net 11)
	)
	(segment
		(start 78.5 88.8)
		(end 68.7 88.8)
		(width 0.15)
		(layer "In5.Cu")
		(net 11)
	)
	(segment
		(start 79.75 94.15)
		(end 80.25 93.65)
		(width 0.15)
		(layer "In5.Cu")
		(net 11)
	)
	(segment
		(start 80.25 90.55)
		(end 78.5 88.8)
		(width 0.15)
		(layer "In5.Cu")
		(net 11)
	)
	(segment
		(start 67.8 86.77)
		(end 67.58 86.55)
		(width 0.15)
		(layer "In5.Cu")
		(net 11)
	)
	(segment
		(start 66.63 85.12)
		(end 66.08 84.57)
		(width 0.15)
		(layer "In5.Cu")
		(net 11)
	)
	(segment
		(start 56.815 79.9)
		(end 55.7 81.015)
		(width 0.15)
		(layer "In5.Cu")
		(net 11)
	)
	(segment
		(start 77.725 96.975)
		(end 79.75 94.95)
		(width 0.15)
		(layer "In5.Cu")
		(net 11)
	)
	(segment
		(start 61.32 81.52)
		(end 59.7 79.9)
		(width 0.15)
		(layer "In5.Cu")
		(net 11)
	)
	(segment
		(start 79.75 94.95)
		(end 79.75 94.15)
		(width 0.15)
		(layer "In5.Cu")
		(net 11)
	)
	(segment
		(start 67.58 86.55)
		(end 67.01 86.55)
		(width 0.15)
		(layer "In5.Cu")
		(net 11)
	)
	(segment
		(start 61.62 81.52)
		(end 61.32 81.52)
		(width 0.15)
		(layer "In5.Cu")
		(net 11)
	)
	(segment
		(start 66.63 86.17)
		(end 66.63 85.12)
		(width 0.15)
		(layer "In5.Cu")
		(net 11)
	)
	(segment
		(start 80.25 93.65)
		(end 80.25 90.55)
		(width 0.15)
		(layer "In5.Cu")
		(net 11)
	)
	(segment
		(start 67.01 86.55)
		(end 66.63 86.17)
		(width 0.15)
		(layer "In5.Cu")
		(net 11)
	)
	(segment
		(start 67.8 87.9)
		(end 67.8 86.77)
		(width 0.15)
		(layer "In5.Cu")
		(net 11)
	)
	(segment
		(start 64.67 84.57)
		(end 61.62 81.52)
		(width 0.15)
		(layer "In5.Cu")
		(net 11)
	)
	(segment
		(start 59.7 79.9)
		(end 56.815 79.9)
		(width 0.15)
		(layer "In5.Cu")
		(net 11)
	)
	(segment
		(start 68.7 88.8)
		(end 67.8 87.9)
		(width 0.15)
		(layer "In5.Cu")
		(net 11)
	)
	(via
		(at 72.2 101.25)
		(size 0.45)
		(drill 0.2)
		(layers "F.Cu" "B.Cu")
		(remove_unused_layers yes)
		(keep_end_layers yes)
		(zone_layer_connections "In3.Cu")
		(net 12)
	)
	(via
		(at 73.2 101.25)
		(size 0.45)
		(drill 0.2)
		(layers "F.Cu" "B.Cu")
		(remove_unused_layers yes)
		(keep_end_layers yes)
		(zone_layer_connections "In3.Cu")
		(net 12)
	)
	(via
		(at 81.225 103.03)
		(size 0.45)
		(drill 0.2)
		(layers "F.Cu" "B.Cu")
		(remove_unused_layers yes)
		(keep_end_layers yes)
		(zone_layer_connections "In3.Cu")
		(net 12)
	)
	(via
		(at 82.225 103.03)
		(size 0.45)
		(drill 0.2)
		(layers "F.Cu" "B.Cu")
		(remove_unused_layers yes)
		(keep_end_layers yes)
		(zone_layer_connections "In3.Cu")
		(net 12)
	)
	(via
		(at 72.7 101.85)
		(size 0.45)
		(drill 0.2)
		(layers "F.Cu" "B.Cu")
		(remove_unused_layers yes)
		(keep_end_layers yes)
		(zone_layer_connections "In3.Cu")
		(net 12)
	)
	(via
		(at 78.225 103.03)
		(size 0.45)
		(drill 0.2)
		(layers "F.Cu" "B.Cu")
		(remove_unused_layers yes)
		(keep_end_layers yes)
		(zone_layer_connections "In3.Cu")
		(net 12)
	)
	(via
		(at 80.225 103.03)
		(size 0.45)
		(drill 0.2)
		(layers "F.Cu" "B.Cu")
		(remove_unused_layers yes)
		(keep_end_layers yes)
		(zone_layer_connections "In3.Cu")
		(net 12)
	)
	(via
		(at 73.7 101.85)
		(size 0.45)
		(drill 0.2)
		(layers "F.Cu" "B.Cu")
		(remove_unused_layers yes)
		(keep_end_layers yes)
		(zone_layer_connections "In3.Cu")
		(net 12)
	)
	(segment
		(start 104.498001 62.273655)
		(end 104.498001 62.298655)
		(width 0.202)
		(layer "F.Cu")
		(net 13)
	)
	(segment
		(start 104.1945 59.544499)
		(end 104.25 59.599999)
		(width 0.202)
		(layer "F.Cu")
		(net 13)
	)
	(segment
		(start 104.25 59.599999)
		(end 104.25 60.372)
		(width 0.202)
		(layer "F.Cu")
		(net 13)
	)
	(segment
		(start 104.1945 58.045501)
		(end 104.1945 59.544499)
		(width 0.202)
		(layer "F.Cu")
		(net 13)
	)
	(segment
		(start 104.192499 60.4275)
		(end 104.192499 61.968153)
		(width 0.202)
		(layer "F.Cu")
		(net 13)
	)
	(segment
		(start 104.25 57.990001)
		(end 104.1945 58.045501)
		(width 0.202)
		(layer "F.Cu")
		(net 13)
	)
	(segment
		(start 104.248 60.371999)
		(end 104.192499 60.4275)
		(width 0.202)
		(layer "F.Cu")
		(net 13)
	)
	(segment
		(start 104.192499 61.968153)
		(end 104.498001 62.273655)
		(width 0.202)
		(layer "F.Cu")
		(net 13)
	)
	(segment
		(start 104.25 57.690001)
		(end 104.25 57.990001)
		(width 0.202)
		(layer "F.Cu")
		(net 13)
	)
	(via
		(at 73.15 112.85)
		(size 0.45)
		(drill 0.2)
		(layers "F.Cu" "B.Cu")
		(remove_unused_layers yes)
		(keep_end_layers yes)
		(zone_layer_connections "In3.Cu")
		(net 14)
	)
	(via
		(at 72.15 112.85)
		(size 0.45)
		(drill 0.2)
		(layers "F.Cu" "B.Cu")
		(remove_unused_layers yes)
		(keep_end_layers yes)
		(zone_layer_connections "In3.Cu")
		(net 14)
	)
	(via
		(at 72.15 113.85)
		(size 0.45)
		(drill 0.2)
		(layers "F.Cu" "B.Cu")
		(remove_unused_layers yes)
		(keep_end_layers yes)
		(zone_layer_connections "In3.Cu")
		(net 14)
	)
	(via
		(at 84.225 108.22)
		(size 0.45)
		(drill 0.2)
		(layers "F.Cu" "B.Cu")
		(remove_unused_layers yes)
		(keep_end_layers yes)
		(zone_layer_connections "In3.Cu")
		(net 14)
	)
	(via
		(at 83.225 108.22)
		(size 0.45)
		(drill 0.2)
		(layers "F.Cu" "B.Cu")
		(remove_unused_layers yes)
		(keep_end_layers yes)
		(zone_layer_connections "In3.Cu")
		(net 14)
	)
	(via
		(at 73.15 113.85)
		(size 0.45)
		(drill 0.2)
		(layers "F.Cu" "B.Cu")
		(remove_unused_layers yes)
		(keep_end_layers yes)
		(zone_layer_connections "In3.Cu")
		(net 14)
	)
	(via
		(at 81.225 108.22)
		(size 0.45)
		(drill 0.2)
		(layers "F.Cu" "B.Cu")
		(remove_unused_layers yes)
		(keep_end_layers yes)
		(zone_layer_connections "In3.Cu")
		(net 14)
	)
	(via
		(at 82.225 108.22)
		(size 0.45)
		(drill 0.2)
		(layers "F.Cu" "B.Cu")
		(remove_unused_layers yes)
		(keep_end_layers yes)
		(zone_layer_connections "In3.Cu")
		(net 14)
	)
	(segment
		(start 58.24 81.015)
		(end 58.24 81.18)
		(width 0.15)
		(layer "F.Cu")
		(net 15)
	)
	(via
		(at 77.725 95.245)
		(size 0.45)
		(drill 0.2)
		(layers "F.Cu" "B.Cu")
		(remove_unused_layers yes)
		(keep_end_layers yes)
		(zone_layer_connections)
		(net 15)
	)
	(via
		(at 58.24 81.015)
		(size 0.45)
		(drill 0.2)
		(layers "F.Cu" "B.Cu")
		(remove_unused_layers yes)
		(keep_end_layers yes)
		(zone_layer_connections)
		(net 15)
	)
	(segment
		(start 60.189483 82.609483)
		(end 61.455517 83.875517)
		(width 0.15)
		(layer "In5.Cu")
		(net 15)
	)
	(segment
		(start 78.17 93.755378)
		(end 77.725 94.200378)
		(width 0.15)
		(layer "In5.Cu")
		(net 15)
	)
	(segment
		(start 75.002924 91.352924)
		(end 77.022924 91.352924)
		(width 0.15)
		(layer "In5.Cu")
		(net 15)
	)
	(segment
		(start 58.920517 82.609483)
		(end 60.189483 82.609483)
		(width 0.15)
		(layer "In5.Cu")
		(net 15)
	)
	(segment
		(start 68.025 89.975)
		(end 68.7 90.65)
		(width 0.15)
		(layer "In5.Cu")
		(net 15)
	)
	(segment
		(start 67.425 89.975)
		(end 68.025 89.975)
		(width 0.15)
		(layer "In5.Cu")
		(net 15)
	)
	(segment
		(start 66 88.55)
		(end 67.425 89.975)
		(width 0.15)
		(layer "In5.Cu")
		(net 15)
	)
	(segment
		(start 61.455517 85.255517)
		(end 64.75 88.55)
		(width 0.15)
		(layer "In5.Cu")
		(net 15)
	)
	(segment
		(start 77.26 91.59)
		(end 77.26 91.99)
		(width 0.15)
		(layer "In5.Cu")
		(net 15)
	)
	(segment
		(start 58.24 81.928967)
		(end 58.920517 82.609483)
		(width 0.15)
		(layer "In5.Cu")
		(net 15)
	)
	(segment
		(start 78.17 92.9)
		(end 78.17 93.755378)
		(width 0.15)
		(layer "In5.Cu")
		(net 15)
	)
	(segment
		(start 74.3 90.65)
		(end 75.002924 91.352924)
		(width 0.15)
		(layer "In5.Cu")
		(net 15)
	)
	(segment
		(start 77.26 91.99)
		(end 78.17 92.9)
		(width 0.15)
		(layer "In5.Cu")
		(net 15)
	)
	(segment
		(start 68.7 90.65)
		(end 74.3 90.65)
		(width 0.15)
		(layer "In5.Cu")
		(net 15)
	)
	(segment
		(start 61.455517 83.875517)
		(end 61.455517 85.255517)
		(width 0.15)
		(layer "In5.Cu")
		(net 15)
	)
	(segment
		(start 64.75 88.55)
		(end 66 88.55)
		(width 0.15)
		(layer "In5.Cu")
		(net 15)
	)
	(segment
		(start 77.725 94.200378)
		(end 77.725 95.245)
		(width 0.15)
		(layer "In5.Cu")
		(net 15)
	)
	(segment
		(start 77.022924 91.352924)
		(end 77.26 91.59)
		(width 0.15)
		(layer "In5.Cu")
		(net 15)
	)
	(segment
		(start 58.24 81.015)
		(end 58.24 81.928967)
		(width 0.15)
		(layer "In5.Cu")
		(net 15)
	)
	(via
		(at 54.431 82.284)
		(size 0.45)
		(drill 0.2)
		(layers "F.Cu" "B.Cu")
		(remove_unused_layers yes)
		(keep_end_layers yes)
		(zone_layer_connections)
		(net 16)
	)
	(via
		(at 77.225 96.11)
		(size 0.45)
		(drill 0.2)
		(layers "F.Cu" "B.Cu")
		(remove_unused_layers yes)
		(keep_end_layers yes)
		(zone_layer_connections)
		(net 16)
	)
	(segment
		(start 75.3 94.05)
		(end 75.3 93.35)
		(width 0.15)
		(layer "In5.Cu")
		(net 16)
	)
	(segment
		(start 73.9 91.95)
		(end 70.65 91.95)
		(width 0.15)
		(layer "In5.Cu")
		(net 16)
	)
	(segment
		(start 76.25 95)
		(end 75.3 94.05)
		(width 0.15)
		(layer "In5.Cu")
		(net 16)
	)
	(segment
		(start 76.25 95.407811)
		(end 76.25 95)
		(width 0.15)
		(layer "In5.Cu")
		(net 16)
	)
	(segment
		(start 69.544484 92.45)
		(end 69.144484 92.05)
		(width 0.15)
		(layer "In5.Cu")
		(net 16)
	)
	(segment
		(start 75.3 93.35)
		(end 73.9 91.95)
		(width 0.15)
		(layer "In5.Cu")
		(net 16)
	)
	(segment
		(start 64.2 92.05)
		(end 63.55 91.4)
		(width 0.15)
		(layer "In5.Cu")
		(net 16)
	)
	(segment
		(start 76.952189 96.11)
		(end 76.25 95.407811)
		(width 0.15)
		(layer "In5.Cu")
		(net 16)
	)
	(segment
		(start 56.6 84.453)
		(end 54.431 82.284)
		(width 0.15)
		(layer "In5.Cu")
		(net 16)
	)
	(segment
		(start 77.225 96.11)
		(end 76.952189 96.11)
		(width 0.15)
		(layer "In5.Cu")
		(net 16)
	)
	(segment
		(start 70.15 92.45)
		(end 69.544484 92.45)
		(width 0.15)
		(layer "In5.Cu")
		(net 16)
	)
	(segment
		(start 63.55 89.2)
		(end 61.015 86.665)
		(width 0.15)
		(layer "In5.Cu")
		(net 16)
	)
	(segment
		(start 56.6 85)
		(end 56.6 84.453)
		(width 0.15)
		(layer "In5.Cu")
		(net 16)
	)
	(segment
		(start 69.144484 92.05)
		(end 64.2 92.05)
		(width 0.15)
		(layer "In5.Cu")
		(net 16)
	)
	(segment
		(start 58.265 86.665)
		(end 56.6 85)
		(width 0.15)
		(layer "In5.Cu")
		(net 16)
	)
	(segment
		(start 70.65 91.95)
		(end 70.15 92.45)
		(width 0.15)
		(layer "In5.Cu")
		(net 16)
	)
	(segment
		(start 63.55 91.4)
		(end 63.55 89.2)
		(width 0.15)
		(layer "In5.Cu")
		(net 16)
	)
	(segment
		(start 61.015 86.665)
		(end 58.265 86.665)
		(width 0.15)
		(layer "In5.Cu")
		(net 16)
	)
	(segment
		(start 103.75 59.6)
		(end 103.75 60.372)
		(width 0.202)
		(layer "F.Cu")
		(net 17)
	)
	(segment
		(start 103.75 57.990001)
		(end 103.75 57.690001)
		(width 0.202)
		(layer "F.Cu")
		(net 17)
	)
	(segment
		(start 103.75 59.6)
		(end 103.8055 59.5445)
		(width 0.202)
		(layer "F.Cu")
		(net 17)
	)
	(segment
		(start 103.498001 62.273655)
		(end 103.498001 62.298655)
		(width 0.202)
		(layer "F.Cu")
		(net 17)
	)
	(segment
		(start 103.8055 58.045501)
		(end 103.75 57.990001)
		(width 0.202)
		(layer "F.Cu")
		(net 17)
	)
	(segment
		(start 103.748 60.372)
		(end 103.803499 60.427499)
		(width 0.202)
		(layer "F.Cu")
		(net 17)
	)
	(segment
		(start 103.803501 61.968155)
		(end 103.498001 62.273655)
		(width 0.202)
		(layer "F.Cu")
		(net 17)
	)
	(segment
		(start 103.8055 59.5445)
		(end 103.8055 58.045501)
		(width 0.202)
		(layer "F.Cu")
		(net 17)
	)
	(segment
		(start 103.803499 61.968153)
		(end 103.803501 61.968155)
		(width 0.202)
		(layer "F.Cu")
		(net 17)
	)
	(segment
		(start 103.803499 60.427499)
		(end 103.803499 61.968153)
		(width 0.202)
		(layer "F.Cu")
		(net 17)
	)
	(segment
		(start 104.625 94.87)
		(end 104.625 94.49)
		(width 0.15)
		(layer "F.Cu")
		(net 18)
	)
	(segment
		(start 92.649 112.962001)
		(end 96.947999 112.962001)
		(width 0.15)
		(layer "F.Cu")
		(net 18)
	)
	(segment
		(start 104.76 94.4)
		(end 104.715 94.4)
		(width 0.15)
		(layer "F.Cu")
		(net 18)
	)
	(segment
		(start 104.625 94.49)
		(end 104.625 94.4)
		(width 0.15)
		(layer "F.Cu")
		(net 18)
	)
	(segment
		(start 86.1 113.4)
		(end 86.4 113.7)
		(width 0.15)
		(layer "F.Cu")
		(net 18)
	)
	(segment
		(start 106.49 94.4)
		(end 106.637 94.4)
		(width 0.15)
		(layer "F.Cu")
		(net 18)
	)
	(segment
		(start 104.715 94.4)
		(end 104.625 94.49)
		(width 0.15)
		(layer "F.Cu")
		(net 18)
	)
	(segment
		(start 88.825 113.7)
		(end 89.1 113.425)
		(width 0.15)
		(layer "F.Cu")
		(net 18)
	)
	(segment
		(start 106.507 94.4)
		(end 106.637 94.53)
		(width 0.15)
		(layer "F.Cu")
		(net 18)
	)
	(segment
		(start 104.76 94.4)
		(end 106.49 94.4)
		(width 0.15)
		(layer "F.Cu")
		(net 18)
	)
	(segment
		(start 106.49 94.4)
		(end 106.507 94.4)
		(width 0.15)
		(layer "F.Cu")
		(net 18)
	)
	(segment
		(start 106.637 94.27)
		(end 106.637 92.252001)
		(width 0.15)
		(layer "F.Cu")
		(net 18)
	)
	(segment
		(start 104.625 94.4)
		(end 104.625 94.31)
		(width 0.15)
		(layer "F.Cu")
		(net 18)
	)
	(segment
		(start 106.637 94.53)
		(end 106.637 94.55)
		(width 0.15)
		(layer "F.Cu")
		(net 18)
	)
	(segment
		(start 106.636999 96.551)
		(end 106.637 94.55)
		(width 0.15)
		(layer "F.Cu")
		(net 18)
	)
	(segment
		(start 89.1 113.425)
		(end 89.1 112.93)
		(width 0.15)
		(layer "F.Cu")
		(net 18)
	)
	(segment
		(start 106.637 91.399999)
		(end 106.637 92.252001)
		(width 0.3)
		(layer "F.Cu")
		(net 18)
	)
	(segment
		(start 97.8 112.962001)
		(end 96.947999 112.962001)
		(width 0.3)
		(layer "F.Cu")
		(net 18)
	)
	(segment
		(start 106.637 94.55)
		(end 106.637 94.27)
		(width 0.15)
		(layer "F.Cu")
		(net 18)
	)
	(segment
		(start 104.625 94.31)
		(end 104.625 93.93)
		(width 0.15)
		(layer "F.Cu")
		(net 18)
	)
	(segment
		(start 86.4 113.7)
		(end 88.825 113.7)
		(width 0.15)
		(layer "F.Cu")
		(net 18)
	)
	(segment
		(start 104.715 94.4)
		(end 104.625 94.31)
		(width 0.15)
		(layer "F.Cu")
		(net 18)
	)
	(segment
		(start 106.507 94.4)
		(end 106.637 94.27)
		(width 0.15)
		(layer "F.Cu")
		(net 18)
	)
	(segment
		(start 86.1 112.93)
		(end 86.1 113.4)
		(width 0.15)
		(layer "F.Cu")
		(net 18)
	)
	(segment
		(start 104.625 94.4)
		(end 104.76 94.4)
		(width 0.15)
		(layer "F.Cu")
		(net 18)
	)
	(via
		(at 83.225 104.76)
		(size 0.45)
		(drill 0.2)
		(layers "F.Cu" "B.Cu")
		(remove_unused_layers yes)
		(keep_end_layers yes)
		(zone_layer_connections "In2.Cu")
		(net 18)
	)
	(via
		(at 67.7 95)
		(size 0.45)
		(drill 0.2)
		(layers "F.Cu" "B.Cu")
		(remove_unused_layers yes)
		(keep_end_layers yes)
		(zone_layer_connections "In2.Cu" "In3.Cu")
		(net 18)
	)
	(via
		(at 83.78 127.1)
		(size 0.45)
		(drill 0.2)
		(layers "F.Cu" "B.Cu")
		(remove_unused_layers yes)
		(keep_end_layers yes)
		(zone_layer_connections "In3.Cu")
		(net 18)
	)
	(via
		(at 67.7 98)
		(size 0.45)
		(drill 0.2)
		(layers "F.Cu" "B.Cu")
		(remove_unused_layers yes)
		(keep_end_layers yes)
		(zone_layer_connections "In2.Cu" "In3.Cu")
		(net 18)
	)
	(via
		(at 67.7 95.999999)
		(size 0.45)
		(drill 0.2)
		(layers "F.Cu" "B.Cu")
		(remove_unused_layers yes)
		(keep_end_layers yes)
		(zone_layer_connections "In2.Cu" "In3.Cu")
		(net 18)
	)
	(via
		(at 106.637 91.399999)
		(size 0.45)
		(drill 0.2)
		(layers "F.Cu" "B.Cu")
		(remove_unused_layers yes)
		(keep_end_layers yes)
		(zone_layer_connections "In3.Cu")
		(net 18)
	)
	(via
		(at 93.81 112.962001)
		(size 0.45)
		(drill 0.2)
		(layers "F.Cu" "B.Cu")
		(remove_unused_layers yes)
		(keep_end_layers yes)
		(zone_layer_connections "In3.Cu")
		(net 18)
	)
	(via
		(at 84.78 126.1)
		(size 0.45)
		(drill 0.2)
		(layers "F.Cu" "B.Cu")
		(remove_unused_layers yes)
		(keep_end_layers yes)
		(zone_layer_connections "In3.Cu")
		(net 18)
	)
	(via
		(at 68.7 95)
		(size 0.45)
		(drill 0.2)
		(layers "F.Cu" "B.Cu")
		(remove_unused_layers yes)
		(keep_end_layers yes)
		(zone_layer_connections "In2.Cu" "In3.Cu")
		(net 18)
	)
	(via
		(at 77.225 104.76)
		(size 0.45)
		(drill 0.2)
		(layers "F.Cu" "B.Cu")
		(remove_unused_layers yes)
		(keep_end_layers yes)
		(zone_layer_connections "In2.Cu")
		(net 18)
	)
	(via
		(at 68.7 97)
		(size 0.45)
		(drill 0.2)
		(layers "F.Cu" "B.Cu")
		(remove_unused_layers yes)
		(keep_end_layers yes)
		(zone_layer_connections "In2.Cu" "In3.Cu")
		(net 18)
	)
	(via
		(at 67.7 97.000001)
		(size 0.45)
		(drill 0.2)
		(layers "F.Cu" "B.Cu")
		(remove_unused_layers yes)
		(keep_end_layers yes)
		(zone_layer_connections "In2.Cu" "In3.Cu")
		(net 18)
	)
	(via
		(at 84.78 127.1)
		(size 0.45)
		(drill 0.2)
		(layers "F.Cu" "B.Cu")
		(remove_unused_layers yes)
		(keep_end_layers yes)
		(zone_layer_connections "In3.Cu")
		(net 18)
	)
	(via
		(at 97.8 112.962001)
		(size 0.45)
		(drill 0.2)
		(layers "F.Cu" "B.Cu")
		(remove_unused_layers yes)
		(keep_end_layers yes)
		(zone_layer_connections "In3.Cu")
		(net 18)
	)
	(via
		(at 76.725 100.435)
		(size 0.45)
		(drill 0.2)
		(layers "F.Cu" "B.Cu")
		(remove_unused_layers yes)
		(keep_end_layers yes)
		(zone_layer_connections "In2.Cu")
		(net 18)
	)
	(via
		(at 68.7 96)
		(size 0.45)
		(drill 0.2)
		(layers "F.Cu" "B.Cu")
		(remove_unused_layers yes)
		(keep_end_layers yes)
		(zone_layer_connections "In2.Cu" "In3.Cu")
		(net 18)
	)
	(via
		(at 76.225 101.3)
		(size 0.45)
		(drill 0.2)
		(layers "F.Cu" "B.Cu")
		(remove_unused_layers yes)
		(keep_end_layers yes)
		(zone_layer_connections "In2.Cu")
		(net 18)
	)
	(via
		(at 89.1 112.93)
		(size 0.45)
		(drill 0.2)
		(layers "F.Cu" "B.Cu")
		(remove_unused_layers yes)
		(keep_end_layers yes)
		(zone_layer_connections "In3.Cu")
		(net 18)
	)
	(via
		(at 83.78 126.1)
		(size 0.45)
		(drill 0.2)
		(layers "F.Cu" "B.Cu")
		(remove_unused_layers yes)
		(keep_end_layers yes)
		(zone_layer_connections "In3.Cu")
		(net 18)
	)
	(via
		(at 68.7 98)
		(size 0.45)
		(drill 0.2)
		(layers "F.Cu" "B.Cu")
		(remove_unused_layers yes)
		(keep_end_layers yes)
		(zone_layer_connections "In2.Cu" "In3.Cu")
		(net 18)
	)
	(segment
		(start 78.676 95.296811)
		(end 78.676 92.471811)
		(width 0.15)
		(layer "B.Cu")
		(net 18)
	)
	(segment
		(start 74.274 101.978189)
		(end 74.274 102.424)
		(width 0.15)
		(layer "B.Cu")
		(net 18)
	)
	(segment
		(start 75.45 101.8)
		(end 74.997811 101.8)
		(width 0.15)
		(layer "B.Cu")
		(net 18)
	)
	(segment
		(start 76.555 100.435)
		(end 76.47 100.35)
		(width 0.15)
		(layer "B.Cu")
		(net 18)
	)
	(segment
		(start 76.47 99.87)
		(end 75.8 99.2)
		(width 0.15)
		(layer "B.Cu")
		(net 18)
	)
	(segment
		(start 76.47 101.35)
		(end 76.55 101.35)
		(width 0.15)
		(layer "B.Cu")
		(net 18)
	)
	(segment
		(start 78.37 101.65)
		(end 78.37 101.330001)
		(width 0.15)
		(layer "B.Cu")
		(net 18)
	)
	(segment
		(start 106.637 91.4)
		(end 106.637 91.838001)
		(width 0.5)
		(layer "B.Cu")
		(net 18)
	)
	(segment
		(start 89.5 112.53)
		(end 89.1 112.93)
		(width 0.125)
		(layer "B.Cu")
		(net 18)
	)
	(segment
		(start 77.274 97.456)
		(end 77.274 96.698811)
		(width 0.15)
		(layer "B.Cu")
		(net 18)
	)
	(segment
		(start 77.97 102.05)
		(end 78.37 101.65)
		(width 0.15)
		(layer "B.Cu")
		(net 18)
	)
	(segment
		(start 77.25 102.05)
		(end 77.97 102.05)
		(width 0.15)
		(layer "B.Cu")
		(net 18)
	)
	(segment
		(start 78.73 81.25)
		(end 82.49 77.49)
		(width 0.15)
		(layer "B.Cu")
		(net 18)
	)
	(segment
		(start 78.186406 87.683594)
		(end 78.73 87.14)
		(width 0.15)
		(layer "B.Cu")
		(net 18)
	)
	(segment
		(start 89.5 111.63)
		(end 89.5 112.53)
		(width 0.125)
		(layer "B.Cu")
		(net 18)
	)
	(segment
		(start 76.47 100.35)
		(end 76.47 99.87)
		(width 0.15)
		(layer "B.Cu")
		(net 18)
	)
	(segment
		(start 75.8 98.93)
		(end 77.274 97.456)
		(width 0.15)
		(layer "B.Cu")
		(net 18)
	)
	(segment
		(start 78.37 101.330001)
		(end 78.851001 100.849)
		(width 0.15)
		(layer "B.Cu")
		(net 18)
	)
	(segment
		(start 77.274 96.698811)
		(end 78.676 95.296811)
		(width 0.15)
		(layer "B.Cu")
		(net 18)
	)
	(segment
		(start 76.225 101.3)
		(end 75.95 101.3)
		(width 0.15)
		(layer "B.Cu")
		(net 18)
	)
	(segment
		(start 75.8 99.2)
		(end 75.8 98.93)
		(width 0.15)
		(layer "B.Cu")
		(net 18)
	)
	(segment
		(start 82.49 77.49)
		(end 82.49 74.55)
		(width 0.15)
		(layer "B.Cu")
		(net 18)
	)
	(segment
		(start 74.538189 101.714)
		(end 74.274 101.978189)
		(width 0.15)
		(layer "B.Cu")
		(net 18)
	)
	(segment
		(start 74.274 102.424)
		(end 74.47 102.62)
		(width 0.15)
		(layer "B.Cu")
		(net 18)
	)
	(segment
		(start 76.55 101.35)
		(end 77.25 102.05)
		(width 0.15)
		(layer "B.Cu")
		(net 18)
	)
	(segment
		(start 93.632001 112.962001)
		(end 93.28 112.61)
		(width 0.15)
		(layer "B.Cu")
		(net 18)
	)
	(segment
		(start 83.579 100.849)
		(end 84.25 101.52)
		(width 0.15)
		(layer "B.Cu")
		(net 18)
	)
	(segment
		(start 106.637 91.838001)
		(end 106.635 91.84)
		(width 0.3)
		(layer "B.Cu")
		(net 18)
	)
	(segment
		(start 74.911811 101.714)
		(end 74.538189 101.714)
		(width 0.15)
		(layer "B.Cu")
		(net 18)
	)
	(segment
		(start 78.73 87.14)
		(end 78.73 81.25)
		(width 0.15)
		(layer "B.Cu")
		(net 18)
	)
	(segment
		(start 97.362 112.962001)
		(end 97.36 112.960001)
		(width 0.3)
		(layer "B.Cu")
		(net 18)
	)
	(segment
		(start 74.47 102.62)
		(end 74.47 103.2)
		(width 0.15)
		(layer "B.Cu")
		(net 18)
	)
	(segment
		(start 93.81 112.962001)
		(end 93.632001 112.962001)
		(width 0.15)
		(layer "B.Cu")
		(net 18)
	)
	(segment
		(start 76.42 101.3)
		(end 76.47 101.35)
		(width 0.15)
		(layer "B.Cu")
		(net 18)
	)
	(segment
		(start 97.8 112.962001)
		(end 97.362 112.962001)
		(width 0.3)
		(layer "B.Cu")
		(net 18)
	)
	(segment
		(start 75.95 101.3)
		(end 75.45 101.8)
		(width 0.15)
		(layer "B.Cu")
		(net 18)
	)
	(segment
		(start 76.225 101.3)
		(end 76.42 101.3)
		(width 0.15)
		(layer "B.Cu")
		(net 18)
	)
	(segment
		(start 78.186406 91.982217)
		(end 78.186406 87.683594)
		(width 0.15)
		(layer "B.Cu")
		(net 18)
	)
	(segment
		(start 78.851001 100.849)
		(end 83.579 100.849)
		(width 0.15)
		(layer "B.Cu")
		(net 18)
	)
	(segment
		(start 78.676 92.471811)
		(end 78.186406 91.982217)
		(width 0.15)
		(layer "B.Cu")
		(net 18)
	)
	(segment
		(start 74.997811 101.8)
		(end 74.911811 101.714)
		(width 0.15)
		(layer "B.Cu")
		(net 18)
	)
	(segment
		(start 76.725 100.435)
		(end 76.555 100.435)
		(width 0.15)
		(layer "B.Cu")
		(net 18)
	)
	(segment
		(start 102.6945 58.045501)
		(end 102.6945 59.544499)
		(width 0.202)
		(layer "F.Cu")
		(net 19)
	)
	(segment
		(start 102.694499 64.499499)
		(end 102.999995 64.804995)
		(width 0.202)
		(layer "F.Cu")
		(net 19)
	)
	(segment
		(start 102.6945 59.544499)
		(end 102.75 59.599999)
		(width 0.202)
		(layer "F.Cu")
		(net 19)
	)
	(segment
		(start 102.75 57.990001)
		(end 102.6945 58.045501)
		(width 0.202)
		(layer "F.Cu")
		(net 19)
	)
	(segment
		(start 102.694499 60.4275)
		(end 102.694499 64.499499)
		(width 0.202)
		(layer "F.Cu")
		(net 19)
	)
	(segment
		(start 102.999995 64.804995)
		(end 103.000005 64.804995)
		(width 0.202)
		(layer "F.Cu")
		(net 19)
	)
	(segment
		(start 102.75 57.690001)
		(end 102.75 57.990001)
		(width 0.202)
		(layer "F.Cu")
		(net 19)
	)
	(segment
		(start 103.000005 64.804995)
		(end 103 64.805)
		(width 0.202)
		(layer "F.Cu")
		(net 19)
	)
	(segment
		(start 102.75 59.599999)
		(end 102.75 60.372)
		(width 0.202)
		(layer "F.Cu")
		(net 19)
	)
	(segment
		(start 102.75 60.371999)
		(end 102.694499 60.4275)
		(width 0.202)
		(layer "F.Cu")
		(net 19)
	)
	(segment
		(start 102.25 59.6)
		(end 102.25 60.372)
		(width 0.202)
		(layer "F.Cu")
		(net 20)
	)
	(segment
		(start 102.305499 64.499501)
		(end 102 64.805)
		(width 0.202)
		(layer "F.Cu")
		(net 20)
	)
	(segment
		(start 102.25 60.372)
		(end 102.305499 60.427499)
		(width 0.202)
		(layer "F.Cu")
		(net 20)
	)
	(segment
		(start 102.3055 59.5445)
		(end 102.25 59.6)
		(width 0.202)
		(layer "F.Cu")
		(net 20)
	)
	(segment
		(start 102.305499 60.427499)
		(end 102.305499 64.499501)
		(width 0.202)
		(layer "F.Cu")
		(net 20)
	)
	(segment
		(start 102.3055 58.045501)
		(end 102.3055 59.5445)
		(width 0.202)
		(layer "F.Cu")
		(net 20)
	)
	(segment
		(start 102.25 57.990001)
		(end 102.3055 58.045501)
		(width 0.202)
		(layer "F.Cu")
		(net 20)
	)
	(segment
		(start 102.25 57.690001)
		(end 102.25 57.990001)
		(width 0.202)
		(layer "F.Cu")
		(net 20)
	)
	(segment
		(start 98.1945 59.544499)
		(end 98.25 59.599999)
		(width 0.202)
		(layer "F.Cu")
		(net 21)
	)
	(segment
		(start 98.25 57.990001)
		(end 98.1945 58.045501)
		(width 0.202)
		(layer "F.Cu")
		(net 21)
	)
	(segment
		(start 98.192499 61.968153)
		(end 98.498001 62.273655)
		(width 0.202)
		(layer "F.Cu")
		(net 21)
	)
	(segment
		(start 98.248 60.371999)
		(end 98.192499 60.4275)
		(width 0.202)
		(layer "F.Cu")
		(net 21)
	)
	(segment
		(start 98.25 59.599999)
		(end 98.25 60.372)
		(width 0.202)
		(layer "F.Cu")
		(net 21)
	)
	(segment
		(start 98.1945 58.045501)
		(end 98.1945 59.544499)
		(width 0.202)
		(layer "F.Cu")
		(net 21)
	)
	(segment
		(start 98.25 57.690001)
		(end 98.25 57.990001)
		(width 0.202)
		(layer "F.Cu")
		(net 21)
	)
	(segment
		(start 98.192499 60.4275)
		(end 98.192499 61.968153)
		(width 0.202)
		(layer "F.Cu")
		(net 21)
	)
	(segment
		(start 98.498001 62.273655)
		(end 98.498001 62.298655)
		(width 0.202)
		(layer "F.Cu")
		(net 21)
	)
	(segment
		(start 97.803501 61.968155)
		(end 97.498001 62.273655)
		(width 0.202)
		(layer "F.Cu")
		(net 22)
	)
	(segment
		(start 97.803499 61.968153)
		(end 97.803501 61.968155)
		(width 0.202)
		(layer "F.Cu")
		(net 22)
	)
	(segment
		(start 97.75 59.6)
		(end 97.75 60.372)
		(width 0.202)
		(layer "F.Cu")
		(net 22)
	)
	(segment
		(start 97.748 60.372)
		(end 97.803499 60.427499)
		(width 0.202)
		(layer "F.Cu")
		(net 22)
	)
	(segment
		(start 97.8055 58.045501)
		(end 97.75 57.990001)
		(width 0.202)
		(layer "F.Cu")
		(net 22)
	)
	(segment
		(start 97.75 57.990001)
		(end 97.75 57.690001)
		(width 0.202)
		(layer "F.Cu")
		(net 22)
	)
	(segment
		(start 97.8055 59.5445)
		(end 97.8055 58.045501)
		(width 0.202)
		(layer "F.Cu")
		(net 22)
	)
	(segment
		(start 97.498001 62.273655)
		(end 97.498001 62.298655)
		(width 0.202)
		(layer "F.Cu")
		(net 22)
	)
	(segment
		(start 97.75 59.6)
		(end 97.8055 59.5445)
		(width 0.202)
		(layer "F.Cu")
		(net 22)
	)
	(segment
		(start 97.803499 60.427499)
		(end 97.803499 61.968153)
		(width 0.202)
		(layer "F.Cu")
		(net 22)
	)
	(via
		(at 69.8 95.35)
		(size 0.45)
		(drill 0.2)
		(layers "F.Cu" "B.Cu")
		(remove_unused_layers yes)
		(keep_end_layers yes)
		(zone_layer_connections "In3.Cu")
		(net 23)
	)
	(via
		(at 78.725 107.355)
		(size 0.45)
		(drill 0.2)
		(layers "F.Cu" "B.Cu")
		(remove_unused_layers yes)
		(keep_end_layers yes)
		(zone_layer_connections "In3.Cu")
		(net 23)
	)
	(via
		(at 79.225 103.03)
		(size 0.45)
		(drill 0.2)
		(layers "F.Cu" "B.Cu")
		(remove_unused_layers yes)
		(keep_end_layers yes)
		(zone_layer_connections)
		(net 24)
	)
	(segment
		(start 96.6945 58.045501)
		(end 96.6945 59.544499)
		(width 0.202)
		(layer "F.Cu")
		(net 25)
	)
	(segment
		(start 96.75 60.371999)
		(end 96.694499 60.4275)
		(width 0.202)
		(layer "F.Cu")
		(net 25)
	)
	(segment
		(start 97.000005 64.804995)
		(end 97 64.805)
		(width 0.202)
		(layer "F.Cu")
		(net 25)
	)
	(segment
		(start 96.6945 59.544499)
		(end 96.75 59.599999)
		(width 0.202)
		(layer "F.Cu")
		(net 25)
	)
	(segment
		(start 96.75 59.599999)
		(end 96.75 60.372)
		(width 0.202)
		(layer "F.Cu")
		(net 25)
	)
	(segment
		(start 96.75 57.990001)
		(end 96.6945 58.045501)
		(width 0.202)
		(layer "F.Cu")
		(net 25)
	)
	(segment
		(start 96.999995 64.804995)
		(end 97.000005 64.804995)
		(width 0.202)
		(layer "F.Cu")
		(net 25)
	)
	(segment
		(start 96.694499 60.4275)
		(end 96.694499 64.499499)
		(width 0.202)
		(layer "F.Cu")
		(net 25)
	)
	(segment
		(start 96.694499 64.499499)
		(end 96.999995 64.804995)
		(width 0.202)
		(layer "F.Cu")
		(net 25)
	)
	(segment
		(start 96.75 57.690001)
		(end 96.75 57.990001)
		(width 0.202)
		(layer "F.Cu")
		(net 25)
	)
	(segment
		(start 96.3055 59.5445)
		(end 96.25 59.6)
		(width 0.202)
		(layer "F.Cu")
		(net 26)
	)
	(segment
		(start 96.305499 64.499501)
		(end 96 64.805)
		(width 0.202)
		(layer "F.Cu")
		(net 26)
	)
	(segment
		(start 96.3055 58.045501)
		(end 96.3055 59.5445)
		(width 0.202)
		(layer "F.Cu")
		(net 26)
	)
	(segment
		(start 96.25 59.6)
		(end 96.25 60.372)
		(width 0.202)
		(layer "F.Cu")
		(net 26)
	)
	(segment
		(start 96.305499 60.427499)
		(end 96.305499 64.499501)
		(width 0.202)
		(layer "F.Cu")
		(net 26)
	)
	(segment
		(start 96.25 57.690001)
		(end 96.25 57.990001)
		(width 0.202)
		(layer "F.Cu")
		(net 26)
	)
	(segment
		(start 96.25 60.372)
		(end 96.305499 60.427499)
		(width 0.202)
		(layer "F.Cu")
		(net 26)
	)
	(segment
		(start 96.25 57.990001)
		(end 96.3055 58.045501)
		(width 0.202)
		(layer "F.Cu")
		(net 26)
	)
	(via
		(at 76.225 104.76)
		(size 0.45)
		(drill 0.2)
		(layers "F.Cu" "B.Cu")
		(remove_unused_layers yes)
		(keep_end_layers yes)
		(zone_layer_connections)
		(net 27)
	)
	(segment
		(start 97.25 60.372)
		(end 97.25 59.6)
		(width 0.3)
		(layer "F.Cu")
		(net 28)
	)
	(segment
		(start 104.25 55.500001)
		(end 104.25 54.835)
		(width 0.2)
		(layer "F.Cu")
		(net 28)
	)
	(segment
		(start 96.75 55.500001)
		(end 96.75 54.835)
		(width 0.2)
		(layer "F.Cu")
		(net 28)
	)
	(segment
		(start 90.4 96.975)
		(end 90.725 96.975)
		(width 0.5)
		(layer "F.Cu")
		(net 28)
	)
	(segment
		(start 87.1 112.93)
		(end 88.1 112.93)
		(width 0.15)
		(layer "F.Cu")
		(net 28)
	)
	(segment
		(start 90.4 98.705)
		(end 90.725 98.705)
		(width 0.5)
		(layer "F.Cu")
		(net 28)
	)
	(segment
		(start 101.25 55.500001)
		(end 101.25 54.835)
		(width 0.2)
		(layer "F.Cu")
		(net 28)
	)
	(segment
		(start 53.494 83.244)
		(end 53.161 82.911)
		(width 0.15)
		(layer "F.Cu")
		(net 28)
	)
	(segment
		(start 79.260999 57.316001)
		(end 79.260999 57.771999)
		(width 0.5)
		(layer "F.Cu")
		(net 28)
	)
	(segment
		(start 98.25 55.500001)
		(end 98.25 54.835)
		(width 0.2)
		(layer "F.Cu")
		(net 28)
	)
	(segment
		(start 69.262999 64.05)
		(end 69.262999 64.9)
		(width 0.15)
		(layer "F.Cu")
		(net 28)
	)
	(segment
		(start 102.75 55.500001)
		(end 102.75 54.835)
		(width 0.2)
		(layer "F.Cu")
		(net 28)
	)
	(segment
		(start 79.7 56.877)
		(end 79.260999 57.316001)
		(width 0.5)
		(layer "F.Cu")
		(net 28)
	)
	(segment
		(start 96.05 113.613001)
		(end 96.948 113.613001)
		(width 0.3)
		(layer "F.Cu")
		(net 28)
	)
	(segment
		(start 111.15 99.619999)
		(end 111.15 99.050001)
		(width 0.15)
		(layer "F.Cu")
		(net 28)
	)
	(segment
		(start 90.225 90.92)
		(end 91.225 90.92)
		(width 0.3)
		(layer "F.Cu")
		(net 28)
	)
	(segment
		(start 103.25 60.372)
		(end 103.25 59.6)
		(width 0.3)
		(layer "F.Cu")
		(net 28)
	)
	(segment
		(start 92.725 91.785)
		(end 91.725 91.785)
		(width 0.3)
		(layer "F.Cu")
		(net 28)
	)
	(segment
		(start 87.225 90.92)
		(end 86.225 90.92)
		(width 0.3)
		(layer "F.Cu")
		(net 28)
	)
	(segment
		(start 113.354 117.44)
		(end 115.4 117.44)
		(width 1)
		(layer "F.Cu")
		(net 28)
	)
	(segment
		(start 104.18 112.5)
		(end 105.22 112.5)
		(width 0.5)
		(layer "F.Cu")
		(net 28)
	)
	(segment
		(start 118.33 103.39)
		(end 118.33 103.392)
		(width 0.3)
		(layer "F.Cu")
		(net 28)
	)
	(segment
		(start 109.35 94.87)
		(end 109.35 93.93)
		(width 0.15)
		(layer "F.Cu")
		(net 28)
	)
	(segment
		(start 103.25 59.6)
		(end 103.25 57.690001)
		(width 0.3)
		(layer "F.Cu")
		(net 28)
	)
	(segment
		(start 58.24 80.22)
		(end 57.765 80.22)
		(width 0.15)
		(layer "F.Cu")
		(net 28)
	)
	(segment
		(start 87.225 90.92)
		(end 88.225 90.92)
		(width 0.3)
		(layer "F.Cu")
		(net 28)
	)
	(segment
		(start 98.75 57.690001)
		(end 98.75 58.355002)
		(width 0.2)
		(layer "F.Cu")
		(net 28)
	)
	(segment
		(start 70.9445 105.43)
		(end 70.0095 105.43)
		(width 0.3)
		(layer "F.Cu")
		(net 28)
	)
	(segment
		(start 57.765 80.22)
		(end 56.97 81.015)
		(width 0.15)
		(layer "F.Cu")
		(net 28)
	)
	(segment
		(start 69.04 107.0405)
		(end 68.8945 106.895)
		(width 0.3)
		(layer "F.Cu")
		(net 28)
	)
	(segment
		(start 100.25 60.372)
		(end 100.25 59.6)
		(width 0.3)
		(layer "F.Cu")
		(net 28)
	)
	(segment
		(start 107.288 93.15)
		(end 107.288 92.252)
		(width 0.3)
		(layer "F.Cu")
		(net 28)
	)
	(segment
		(start 95.75 57.690001)
		(end 95.75 58.355002)
		(width 0.2)
		(layer "F.Cu")
		(net 28)
	)
	(segment
		(start 113.01 117.784)
		(end 113.354 117.44)
		(width 1)
		(layer "F.Cu")
		(net 28)
	)
	(segment
		(start 84.225 90.92)
		(end 85.225 90.92)
		(width 0.3)
		(layer "F.Cu")
		(net 28)
	)
	(segment
		(start 85.402999 64.05)
		(end 85.402999 64.9)
		(width 0.125)
		(layer "F.Cu")
		(net 28)
	)
	(segment
		(start 95.25 55.500001)
		(end 95.25 54.835)
		(width 0.2)
		(layer "F.Cu")
		(net 28)
	)
	(segment
		(start 69.04 107.94)
		(end 69.04 107.0405)
		(width 0.3)
		(layer "F.Cu")
		(net 28)
	)
	(segment
		(start 85.55 115)
		(end 89.25 115)
		(width 0.15)
		(layer "F.Cu")
		(net 28)
	)
	(segment
		(start 84.225 90.92)
		(end 83.225 90.92)
		(width 0.3)
		(layer "F.Cu")
		(net 28)
	)
	(segment
		(start 54.431 83.244)
		(end 53.494 83.244)
		(width 0.15)
		(layer "F.Cu")
		(net 28)
	)
	(segment
		(start 118.33 103.392)
		(end 118.322 103.4)
		(width 0.3)
		(layer "F.Cu")
		(net 28)
	)
	(segment
		(start 113.15 99.62)
		(end 113.15 99.05)
		(width 0.15)
		(layer "F.Cu")
		(net 28)
	)
	(segment
		(start 97.25 59.6)
		(end 97.25 57.690001)
		(width 0.3)
		(layer "F.Cu")
		(net 28)
	)
	(segment
		(start 118.322 103.4)
		(end 117.251 103.4)
		(width 0.3)
		(layer "F.Cu")
		(net 28)
	)
	(segment
		(start 110.4 101.9)
		(end 110.4 102.65)
		(width 0.15)
		(layer "F.Cu")
		(net 28)
	)
	(segment
		(start 70.0095 105.43)
		(end 69.8945 105.545)
		(width 0.3)
		(layer "F.Cu")
		(net 28)
	)
	(segment
		(start 110.626 108.405)
		(end 110.045 108.405)
		(width 0.15)
		(layer "F.Cu")
		(net 28)
	)
	(segment
		(start 101.75 57.690001)
		(end 101.75 58.355002)
		(width 0.2)
		(layer "F.Cu")
		(net 28)
	)
	(segment
		(start 100.25 59.6)
		(end 100.25 57.690001)
		(width 0.3)
		(layer "F.Cu")
		(net 28)
	)
	(segment
		(start 103.25 60.355001)
		(end 103.25 59.583001)
		(width 0.125)
		(layer "F.Cu")
		(net 28)
	)
	(segment
		(start 110.4 102.65)
		(end 111.15 103.4)
		(width 0.15)
		(layer "F.Cu")
		(net 28)
	)
	(segment
		(start 70.213 63.7)
		(end 70.213 64.9)
		(width 0.5)
		(layer "F.Cu")
		(net 28)
	)
	(segment
		(start 92.725 91.785)
		(end 93.725 91.785)
		(width 0.3)
		(layer "F.Cu")
		(net 28)
	)
	(segment
		(start 53.161 82.911)
		(end 53.161 82.284)
		(width 0.15)
		(layer "F.Cu")
		(net 28)
	)
	(segment
		(start 56.599 73.715)
		(end 56.97 73.715)
		(width 0.15)
		(layer "F.Cu")
		(net 28)
	)
	(segment
		(start 109.15 107.03)
		(end 109.15 107.599997)
		(width 0.15)
		(layer "F.Cu")
		(net 28)
	)
	(segment
		(start 111.15 107.03)
		(end 111.15 107.599997)
		(width 0.15)
		(layer "F.Cu")
		(net 28)
	)
	(segment
		(start 99.75 55.500001)
		(end 99.75 54.835)
		(width 0.2)
		(layer "F.Cu")
		(net 28)
	)
	(segment
		(start 79.7 56.204)
		(end 79.7 56.877)
		(width 0.5)
		(layer "F.Cu")
		(net 28)
	)
	(segment
		(start 90.225 90.92)
		(end 89.225 90.92)
		(width 0.3)
		(layer "F.Cu")
		(net 28)
	)
	(segment
		(start 110.045 108.405)
		(end 110.02 108.43)
		(width 0.15)
		(layer "F.Cu")
		(net 28)
	)
	(segment
		(start 104.75 57.690001)
		(end 104.75 58.355002)
		(width 0.2)
		(layer "F.Cu")
		(net 28)
	)
	(segment
		(start 111.265 117.784)
		(end 113.01 117.784)
		(width 1)
		(layer "F.Cu")
		(net 28)
	)
	(segment
		(start 86.353 63.7)
		(end 86.353 64.9)
		(width 0.5)
		(layer "F.Cu")
		(net 28)
	)
	(segment
		(start 109.15 102.53)
		(end 109.15 103.099997)
		(width 0.15)
		(layer "F.Cu")
		(net 28)
	)
	(via
		(at 64.45 131.300001)
		(size 0.45)
		(drill 0.2)
		(layers "F.Cu" "B.Cu")
		(remove_unused_layers yes)
		(keep_end_layers yes)
		(zone_layer_connections "In1.Cu" "In3.Cu" "In4.Cu" "In6.Cu")
		(net 28)
	)
	(via
		(at 119.35 94.28)
		(size 0.45)
		(drill 0.2)
		(layers "F.Cu" "B.Cu")
		(remove_unused_layers yes)
		(keep_end_layers yes)
		(zone_layer_connections "In1.Cu" "In4.Cu" "In6.Cu")
		(net 28)
	)
	(via
		(at 52.575 111.225001)
		(size 0.45)
		(drill 0.1)
		(layers "F.Cu" "B.Cu")
		(remove_unused_layers yes)
		(keep_end_layers yes)
		(zone_layer_connections "In1.Cu" "In4.Cu" "In6.Cu")
		(net 28)
	)
	(via
		(at 97.23 61.535)
		(size 0.45)
		(drill 0.2)
		(layers "F.Cu" "B.Cu")
		(remove_unused_layers yes)
		(keep_end_layers yes)
		(zone_layer_connections "In1.Cu" "In2.Cu" "In4.Cu" "In6.Cu")
		(net 28)
	)
	(via
		(at 119.35 100.28)
		(size 0.45)
		(drill 0.2)
		(layers "F.Cu" "B.Cu")
		(remove_unused_layers yes)
		(keep_end_layers yes)
		(zone_layer_connections "In1.Cu" "In4.Cu" "In6.Cu")
		(net 28)
	)
	(via
		(at 53.65 67.499999)
		(size 0.45)
		(drill 0.2)
		(layers "F.Cu" "B.Cu")
		(remove_unused_layers yes)
		(keep_end_layers yes)
		(zone_layer_connections "In1.Cu" "In4.Cu" "In6.Cu")
		(net 28)
	)
	(via
		(at 119.35 118.28)
		(size 0.45)
		(drill 0.2)
		(layers "F.Cu" "B.Cu")
		(remove_unused_layers yes)
		(keep_end_layers yes)
		(zone_layer_connections "In1.Cu" "In3.Cu" "In4.Cu" "In6.Cu")
		(net 28)
	)
	(via
		(at 50.65 118.500002)
		(size 0.45)
		(drill 0.2)
		(layers "F.Cu" "B.Cu")
		(remove_unused_layers yes)
		(keep_end_layers yes)
		(zone_layer_connections "In1.Cu" "In3.Cu" "In4.Cu" "In6.Cu")
		(net 28)
	)
	(via
		(at 114.6 149.3)
		(size 0.45)
		(drill 0.2)
		(layers "F.Cu" "B.Cu")
		(remove_unused_layers yes)
		(keep_end_layers yes)
		(zone_layer_connections "In1.Cu" "In3.Cu" "In4.Cu" "In6.Cu")
		(net 28)
	)
	(via
		(at 70.18 68.38)
		(size 0.45)
		(drill 0.2)
		(layers "F.Cu" "B.Cu")
		(remove_unused_layers yes)
		(keep_end_layers yes)
		(zone_layer_connections "In1.Cu" "In4.Cu" "In6.Cu")
		(net 28)
	)
	(via
		(at 74.329999 81.039994)
		(size 0.45)
		(drill 0.1)
		(layers "F.Cu" "B.Cu")
		(remove_unused_layers yes)
		(keep_end_layers yes)
		(zone_layer_connections "In1.Cu" "In4.Cu" "In6.Cu")
		(net 28)
	)
	(via
		(at 109.15 107.599997)
		(size 0.45)
		(drill 0.2)
		(layers "F.Cu" "B.Cu")
		(remove_unused_layers yes)
		(keep_end_layers yes)
		(zone_layer_connections "In1.Cu" "In4.Cu" "In6.Cu")
		(net 28)
	)
	(via
		(at 84.95 76.499999)
		(size 0.45)
		(drill 0.2)
		(layers "F.Cu" "B.Cu")
		(remove_unused_layers yes)
		(keep_end_layers yes)
		(zone_layer_connections "In1.Cu" "In4.Cu" "In6.Cu")
		(net 28)
	)
	(via
		(at 75.479998 143.15)
		(size 0.45)
		(drill 0.2)
		(layers "F.Cu" "B.Cu")
		(remove_unused_layers yes)
		(keep_end_layers yes)
		(zone_layer_connections "In1.Cu" "In3.Cu" "In4.Cu" "In6.Cu")
		(net 28)
	)
	(via
		(at 93.725 93.515)
		(size 0.45)
		(drill 0.2)
		(layers "F.Cu" "B.Cu")
		(remove_unused_layers yes)
		(keep_end_layers yes)
		(zone_layer_connections "In1.Cu" "In4.Cu" "In6.Cu")
		(net 28)
	)
	(via
		(at 68.15 110.9)
		(size 0.45)
		(drill 0.2)
		(layers "F.Cu" "B.Cu")
		(remove_unused_layers yes)
		(keep_end_layers yes)
		(zone_layer_connections "In1.Cu" "In4.Cu" "In6.Cu")
		(net 28)
	)
	(via
		(at 63.89 100.52)
		(size 0.45)
		(drill 0.1)
		(layers "F.Cu" "B.Cu")
		(remove_unused_layers yes)
		(keep_end_layers yes)
		(zone_layer_connections "In1.Cu" "In4.Cu" "In6.Cu")
		(net 28)
	)
	(via
		(at 55.65 110.9)
		(size 0.45)
		(drill 0.1)
		(layers "F.Cu" "B.Cu")
		(remove_unused_layers yes)
		(keep_end_layers yes)
		(zone_layer_connections "In1.Cu" "In4.Cu" "In6.Cu")
		(net 28)
	)
	(via
		(at 50.65 52.499997)
		(size 0.45)
		(drill 0.2)
		(layers "F.Cu" "B.Cu")
		(remove_unused_layers yes)
		(keep_end_layers yes)
		(zone_layer_connections "In1.Cu" "In4.Cu" "In6.Cu")
		(net 28)
	)
	(via
		(at 86.725 98.705)
		(size 0.45)
		(drill 0.2)
		(layers "F.Cu" "B.Cu")
		(remove_unused_layers yes)
		(keep_end_layers yes)
		(zone_layer_connections "In1.Cu" "In4.Cu" "In6.Cu")
		(net 28)
	)
	(via
		(at 93.725 91.785)
		(size 0.45)
		(drill 0.2)
		(layers "F.Cu" "B.Cu")
		(remove_unused_layers yes)
		(keep_end_layers yes)
		(zone_layer_connections "In1.Cu" "In4.Cu" "In6.Cu")
		(net 28)
	)
	(via
		(at 73.48 144.859998)
		(size 0.45)
		(drill 0.2)
		(layers "F.Cu" "B.Cu")
		(remove_unused_layers yes)
		(keep_end_layers yes)
		(zone_layer_connections "In1.Cu" "In3.Cu" "In4.Cu" "In6.Cu")
		(net 28)
	)
	(via
		(at 75.725 93.515)
		(size 0.45)
		(drill 0.2)
		(layers "F.Cu" "B.Cu")
		(remove_unused_layers yes)
		(keep_end_layers yes)
		(zone_layer_connections "In1.Cu" "In4.Cu" "In6.Cu")
		(net 28)
	)
	(via
		(at 119.35 106.280001)
		(size 0.45)
		(drill 0.2)
		(layers "F.Cu" "B.Cu")
		(remove_unused_layers yes)
		(keep_end_layers yes)
		(zone_layer_connections "In1.Cu" "In4.Cu" "In6.Cu")
		(net 28)
	)
	(via
		(at 85.725 105.625)
		(size 0.45)
		(drill 0.2)
		(layers "F.Cu" "B.Cu")
		(remove_unused_layers yes)
		(keep_end_layers yes)
		(zone_layer_connections "In1.Cu" "In4.Cu" "In6.Cu")
		(net 28)
	)
	(via
		(at 59.24 108.85)
		(size 0.45)
		(drill 0.1)
		(layers "F.Cu" "B.Cu")
		(remove_unused_layers yes)
		(keep_end_layers yes)
		(zone_layer_connections "In1.Cu" "In4.Cu" "In6.Cu")
		(net 28)
	)
	(via
		(at 73.84 83.34)
		(size 0.45)
		(drill 0.1)
		(layers "F.Cu" "B.Cu")
		(remove_unused_layers yes)
		(keep_end_layers yes)
		(zone_layer_connections "In1.Cu" "In4.Cu" "In6.Cu")
		(net 28)
	)
	(via
		(at 119.35 97.280001)
		(size 0.45)
		(drill 0.2)
		(layers "F.Cu" "B.Cu")
		(remove_unused_layers yes)
		(keep_end_layers yes)
		(zone_layer_connections "In1.Cu" "In4.Cu" "In6.Cu")
		(net 28)
	)
	(via
		(at 57.6 149.3)
		(size 0.45)
		(drill 0.2)
		(layers "F.Cu" "B.Cu")
		(remove_unused_layers yes)
		(keep_end_layers yes)
		(zone_layer_connections "In1.Cu" "In3.Cu" "In4.Cu" "In6.Cu")
		(net 28)
	)
	(via
		(at 70.15 114.85)
		(size 0.45)
		(drill 0.2)
		(layers "F.Cu" "B.Cu")
		(remove_unused_layers yes)
		(keep_end_layers yes)
		(zone_layer_connections "In1.Cu" "In4.Cu" "In6.Cu")
		(net 28)
	)
	(via
		(at 61.5 67.499999)
		(size 0.45)
		(drill 0.2)
		(layers "F.Cu" "B.Cu")
		(remove_unused_layers yes)
		(keep_end_layers yes)
		(zone_layer_connections "In1.Cu" "In4.Cu" "In6.Cu")
		(net 28)
	)
	(via
		(at 78.725 91.785)
		(size 0.45)
		(drill 0.2)
		(layers "F.Cu" "B.Cu")
		(remove_unused_layers yes)
		(keep_end_layers yes)
		(zone_layer_connections "In1.Cu" "In4.Cu" "In6.Cu")
		(net 28)
	)
	(via
		(at 86.225 104.76)
		(size 0.45)
		(drill 0.2)
		(layers "F.Cu" "B.Cu")
		(remove_unused_layers yes)
		(keep_end_layers yes)
		(zone_layer_connections "In1.Cu" "In4.Cu" "In6.Cu")
		(net 28)
	)
	(via
		(at 85.225 106.49)
		(size 0.45)
		(drill 0.2)
		(layers "F.Cu" "B.Cu")
		(remove_unused_layers yes)
		(keep_end_layers yes)
		(zone_layer_connections "In1.Cu" "In4.Cu" "In6.Cu")
		(net 28)
	)
	(via
		(at 61.5 64.5)
		(size 0.45)
		(drill 0.2)
		(layers "F.Cu" "B.Cu")
		(remove_unused_layers yes)
		(keep_end_layers yes)
		(zone_layer_connections "In1.Cu" "In4.Cu" "In6.Cu")
		(net 28)
	)
	(via
		(at 119.35 76.28)
		(size 0.45)
		(drill 0.2)
		(layers "F.Cu" "B.Cu")
		(remove_unused_layers yes)
		(keep_end_layers yes)
		(zone_layer_connections "In1.Cu" "In4.Cu" "In6.Cu")
		(net 28)
	)
	(via
		(at 50.65 136.5)
		(size 0.45)
		(drill 0.2)
		(layers "F.Cu" "B.Cu")
		(remove_unused_layers yes)
		(keep_end_layers yes)
		(zone_layer_connections "In1.Cu" "In3.Cu" "In4.Cu" "In6.Cu")
		(net 28)
	)
	(via
		(at 117.6 149.3)
		(size 0.45)
		(drill 0.2)
		(layers "F.Cu" "B.Cu")
		(remove_unused_layers yes)
		(keep_end_layers yes)
		(zone_layer_connections "In1.Cu" "In3.Cu" "In4.Cu" "In6.Cu")
		(net 28)
	)
	(via
		(at 78.225 97.84)
		(size 0.45)
		(drill 0.2)
		(layers "F.Cu" "B.Cu")
		(remove_unused_layers yes)
		(keep_end_layers yes)
		(zone_layer_connections "In1.Cu" "In4.Cu" "In6.Cu")
		(net 28)
	)
	(via
		(at 80.225 109.95)
		(size 0.45)
		(drill 0.2)
		(layers "F.Cu" "B.Cu")
		(remove_unused_layers yes)
		(keep_end_layers yes)
		(zone_layer_connections "In1.Cu" "In4.Cu" "In6.Cu")
		(net 28)
	)
	(via
		(at 75.097239 108.58294)
		(size 0.45)
		(drill 0.2)
		(layers "F.Cu" "B.Cu")
		(remove_unused_layers yes)
		(keep_end_layers yes)
		(zone_layer_connections "In1.Cu" "In4.Cu" "In6.Cu")
		(net 28)
	)
	(via
		(at 80.07 126.100001)
		(size 0.45)
		(drill 0.2)
		(layers "F.Cu" "B.Cu")
		(remove_unused_layers yes)
		(keep_end_layers yes)
		(zone_layer_connections "In1.Cu" "In4.Cu" "In6.Cu")
		(net 28)
	)
	(via
		(at 111.15 99.050001)
		(size 0.45)
		(drill 0.2)
		(layers "F.Cu" "B.Cu")
		(remove_unused_layers yes)
		(keep_end_layers yes)
		(zone_layer_connections "In1.Cu" "In4.Cu" "In6.Cu")
		(net 28)
	)
	(via
		(at 59.26 91.51)
		(size 0.45)
		(drill 0.1)
		(layers "F.Cu" "B.Cu")
		(remove_unused_layers yes)
		(keep_end_layers yes)
		(free yes)
		(zone_layer_connections "In1.Cu" "In4.Cu" "In6.Cu")
		(net 28)
	)
	(via
		(at 62.65 115.500001)
		(size 0.45)
		(drill 0.2)
		(layers "F.Cu" "B.Cu")
		(remove_unused_layers yes)
		(keep_end_layers yes)
		(zone_layer_connections "In1.Cu" "In4.Cu" "In6.Cu")
		(net 28)
	)
	(via
		(at 79.725 105.625)
		(size 0.45)
		(drill 0.2)
		(layers "F.Cu" "B.Cu")
		(remove_unused_layers yes)
		(keep_end_layers yes)
		(zone_layer_connections "In1.Cu" "In4.Cu" "In6.Cu")
		(net 28)
	)
	(via
		(at 75.349999 63.35)
		(size 0.45)
		(drill 0.2)
		(layers "F.Cu" "B.Cu")
		(remove_unused_layers yes)
		(keep_end_layers yes)
		(zone_layer_connections "In1.Cu" "In4.Cu" "In6.Cu")
		(net 28)
	)
	(via
		(at 104.18 112.515)
		(size 0.45)
		(drill 0.2)
		(layers "F.Cu" "B.Cu")
		(remove_unused_layers yes)
		(keep_end_layers yes)
		(zone_layer_connections "In1.Cu" "In4.Cu" "In6.Cu")
		(net 28)
	)
	(via
		(at 87.225 103.03)
		(size 0.45)
		(drill 0.2)
		(layers "F.Cu" "B.Cu")
		(remove_unused_layers yes)
		(keep_end_layers yes)
		(zone_layer_connections "In1.Cu" "In4.Cu" "In6.Cu")
		(net 28)
	)
	(via
		(at 72.479999 143.15)
		(size 0.45)
		(drill 0.2)
		(layers "F.Cu" "B.Cu")
		(remove_unused_layers yes)
		(keep_end_layers yes)
		(zone_layer_connections "In1.Cu" "In3.Cu" "In4.Cu" "In6.Cu")
		(net 28)
	)
	(via
		(at 59.95 107.5)
		(size 0.45)
		(drill 0.1)
		(layers "F.Cu" "B.Cu")
		(remove_unused_layers yes)
		(keep_end_layers yes)
		(zone_layer_connections "In1.Cu" "In4.Cu" "In6.Cu")
		(net 28)
	)
	(via
		(at 119.35 109.28)
		(size 0.45)
		(drill 0.2)
		(layers "F.Cu" "B.Cu")
		(remove_unused_layers yes)
		(keep_end_layers yes)
		(zone_layer_connections "In1.Cu" "In3.Cu" "In4.Cu" "In6.Cu")
		(net 28)
	)
	(via
		(at 114.15 97.1)
		(size 0.45)
		(drill 0.2)
		(layers "F.Cu" "B.Cu")
		(remove_unused_layers yes)
		(keep_end_layers yes)
		(zone_layer_connections "In1.Cu" "In4.Cu" "In6.Cu")
		(net 28)
	)
	(via
		(at 106.59 90.26)
		(size 0.45)
		(drill 0.2)
		(layers "F.Cu" "B.Cu")
		(remove_unused_layers yes)
		(keep_end_layers yes)
		(zone_layer_connections "In1.Cu" "In4.Cu" "In5.Cu" "In6.Cu")
		(net 28)
	)
	(via
		(at 78.6 149.3)
		(size 0.45)
		(drill 0.2)
		(layers "F.Cu" "B.Cu")
		(remove_unused_layers yes)
		(keep_end_layers yes)
		(zone_layer_connections "In1.Cu" "In3.Cu" "In4.Cu" "In6.Cu")
		(net 28)
	)
	(via
		(at 100.63 87.36)
		(size 0.45)
		(drill 0.2)
		(layers "F.Cu" "B.Cu")
		(remove_unused_layers yes)
		(keep_end_layers yes)
		(zone_layer_connections "In1.Cu" "In4.Cu" "In6.Cu")
		(net 28)
	)
	(via
		(at 69.15 115.85)
		(size 0.45)
		(drill 0.2)
		(layers "F.Cu" "B.Cu")
		(remove_unused_layers yes)
		(keep_end_layers yes)
		(zone_layer_connections "In1.Cu" "In4.Cu" "In6.Cu")
		(net 28)
	)
	(via
		(at 78.349999 60.35)
		(size 0.45)
		(drill 0.2)
		(layers "F.Cu" "B.Cu")
		(remove_unused_layers yes)
		(keep_end_layers yes)
		(zone_layer_connections "In1.Cu" "In4.Cu" "In6.Cu")
		(net 28)
	)
	(via
		(at 96.950001 50.65)
		(size 0.45)
		(drill 0.2)
		(layers "F.Cu" "B.Cu")
		(remove_unused_layers yes)
		(keep_end_layers yes)
		(zone_layer_connections "In1.Cu" "In4.Cu" "In6.Cu")
		(net 28)
	)
	(via
		(at 87.949999 76.499999)
		(size 0.45)
		(drill 0.2)
		(layers "F.Cu" "B.Cu")
		(remove_unused_layers yes)
		(keep_end_layers yes)
		(zone_layer_connections "In1.Cu" "In4.Cu" "In6.Cu")
		(net 28)
	)
	(via
		(at 89.225 103.03)
		(size 0.45)
		(drill 0.2)
		(layers "F.Cu" "B.Cu")
		(remove_unused_layers yes)
		(keep_end_layers yes)
		(zone_layer_connections "In1.Cu" "In4.Cu" "In6.Cu")
		(net 28)
	)
	(via
		(at 51.575 110.225001)
		(size 0.45)
		(drill 0.1)
		(layers "F.Cu" "B.Cu")
		(remove_unused_layers yes)
		(keep_end_layers yes)
		(zone_layer_connections "In1.Cu" "In4.Cu" "In6.Cu")
		(net 28)
	)
	(via
		(at 111.15 103.4)
		(size 0.45)
		(drill 0.2)
		(layers "F.Cu" "B.Cu")
		(remove_unused_layers yes)
		(keep_end_layers yes)
		(zone_layer_connections "In1.Cu" "In4.Cu" "In6.Cu")
		(net 28)
	)
	(via
		(at 53.65 64.5)
		(size 0.45)
		(drill 0.2)
		(layers "F.Cu" "B.Cu")
		(remove_unused_layers yes)
		(keep_end_layers yes)
		(zone_layer_connections "In1.Cu" "In4.Cu" "In6.Cu")
		(net 28)
	)
	(via
		(at 78.725 103.895)
		(size 0.45)
		(drill 0.2)
		(layers "F.Cu" "B.Cu")
		(remove_unused_layers yes)
		(keep_end_layers yes)
		(zone_layer_connections "In1.Cu" "In4.Cu" "In6.Cu")
		(net 28)
	)
	(via
		(at 54.575001 87.125)
		(size 0.45)
		(drill 0.1)
		(layers "F.Cu" "B.Cu")
		(remove_unused_layers yes)
		(keep_end_layers yes)
		(zone_layer_connections "In1.Cu" "In4.Cu" "In6.Cu")
		(net 28)
	)
	(via
		(at 52.575 110.225001)
		(size 0.45)
		(drill 0.1)
		(layers "F.Cu" "B.Cu")
		(remove_unused_layers yes)
		(keep_end_layers yes)
		(zone_layer_connections "In1.Cu" "In4.Cu" "In6.Cu")
		(net 28)
	)
	(via
		(at 66.95 50.65)
		(size 0.45)
		(drill 0.2)
		(layers "F.Cu" "B.Cu")
		(remove_unused_layers yes)
		(keep_end_layers yes)
		(zone_layer_connections "In1.Cu" "In4.Cu" "In6.Cu")
		(net 28)
	)
	(via
		(at 110.35 121.28)
		(size 0.45)
		(drill 0.2)
		(layers "F.Cu" "B.Cu")
		(remove_unused_layers yes)
		(keep_end_layers yes)
		(zone_layer_connections "In1.Cu" "In3.Cu" "In4.Cu" "In6.Cu")
		(net 28)
	)
	(via
		(at 85.725 109.085)
		(size 0.45)
		(drill 0.2)
		(layers "F.Cu" "B.Cu")
		(remove_unused_layers yes)
		(keep_end_layers yes)
		(zone_layer_connections "In1.Cu" "In4.Cu" "In6.Cu")
		(net 28)
	)
	(via
		(at 50.65 67.499998)
		(size 0.45)
		(drill 0.2)
		(layers "F.Cu" "B.Cu")
		(remove_unused_layers yes)
		(keep_end_layers yes)
		(zone_layer_connections "In1.Cu" "In4.Cu" "In6.Cu")
		(net 28)
	)
	(via
		(at 86.43 58.591999)
		(size 0.45)
		(drill 0.2)
		(layers "F.Cu" "B.Cu")
		(remove_unused_layers yes)
		(keep_end_layers yes)
		(zone_layer_connections "In1.Cu" "In4.Cu" "In6.Cu")
		(net 28)
	)
	(via
		(at 119.35 55.279997)
		(size 0.45)
		(drill 0.2)
		(layers "F.Cu" "B.Cu")
		(remove_unused_layers yes)
		(keep_end_layers yes)
		(zone_layer_connections "In1.Cu" "In4.Cu" "In6.Cu")
		(net 28)
	)
	(via
		(at 71.15 114.85)
		(size 0.45)
		(drill 0.2)
		(layers "F.Cu" "B.Cu")
		(remove_unused_layers yes)
		(keep_end_layers yes)
		(zone_layer_connections "In1.Cu" "In4.Cu" "In6.Cu")
		(net 28)
	)
	(via
		(at 94.725 109.085)
		(size 0.45)
		(drill 0.2)
		(layers "F.Cu" "B.Cu")
		(remove_unused_layers yes)
		(keep_end_layers yes)
		(zone_layer_connections "In1.Cu" "In4.Cu" "In6.Cu")
		(net 28)
	)
	(via
		(at 67.4 91.549999)
		(size 0.45)
		(drill 0.2)
		(layers "F.Cu" "B.Cu")
		(remove_unused_layers yes)
		(keep_end_layers yes)
		(zone_layer_connections "In1.Cu" "In4.Cu" "In6.Cu")
		(net 28)
	)
	(via
		(at 119.35 61.279999)
		(size 0.45)
		(drill 0.2)
		(layers "F.Cu" "B.Cu")
		(remove_unused_layers yes)
		(keep_end_layers yes)
		(zone_layer_connections "In1.Cu" "In4.Cu" "In6.Cu")
		(net 28)
	)
	(via
		(at 72.45 104.4)
		(size 0.45)
		(drill 0.2)
		(layers "F.Cu" "B.Cu")
		(remove_unused_layers yes)
		(keep_end_layers yes)
		(zone_layer_connections "In1.Cu" "In4.Cu" "In6.Cu")
		(net 28)
	)
	(via
		(at 59.23 100.58)
		(size 0.45)
		(drill 0.1)
		(layers "F.Cu" "B.Cu")
		(remove_unused_layers yes)
		(keep_end_layers yes)
		(zone_layer_connections "In1.Cu" "In4.Cu" "In6.Cu")
		(net 28)
	)
	(via
		(at 63.6 149.3)
		(size 0.45)
		(drill 0.2)
		(layers "F.Cu" "B.Cu")
		(remove_unused_layers yes)
		(keep_end_layers yes)
		(zone_layer_connections "In1.Cu" "In3.Cu" "In4.Cu" "In6.Cu")
		(net 28)
	)
	(via
		(at 84.725 107.355)
		(size 0.45)
		(drill 0.2)
		(layers "F.Cu" "B.Cu")
		(remove_unused_layers yes)
		(keep_end_layers yes)
		(zone_layer_connections "In1.Cu" "In4.Cu" "In6.Cu")
		(net 28)
	)
	(via
		(at 64.900001 134.7)
		(size 0.45)
		(drill 0.2)
		(layers "F.Cu" "B.Cu")
		(remove_unused_layers yes)
		(keep_end_layers yes)
		(zone_layer_connections "In1.Cu" "In3.Cu" "In4.Cu" "In6.Cu")
		(net 28)
	)
	(via
		(at 70.874999 77.514996)
		(size 0.45)
		(drill 0.1)
		(layers "F.Cu" "B.Cu")
		(remove_unused_layers yes)
		(keep_end_layers yes)
		(zone_layer_connections "In1.Cu" "In4.Cu" "In6.Cu")
		(net 28)
	)
	(via
		(at 83.725 107.355)
		(size 0.45)
		(drill 0.2)
		(layers "F.Cu" "B.Cu")
		(remove_unused_layers yes)
		(keep_end_layers yes)
		(zone_layer_connections "In1.Cu" "In4.Cu" "In6.Cu")
		(net 28)
	)
	(via
		(at 77.9 81.625)
		(size 0.45)
		(drill 0.2)
		(layers "F.Cu" "B.Cu")
		(remove_unused_layers yes)
		(keep_end_layers yes)
		(zone_layer_connections "In1.Cu" "In4.Cu" "In6.Cu")
		(net 28)
	)
	(via
		(at 55.65 103.200001)
		(size 0.45)
		(drill 0.1)
		(layers "F.Cu" "B.Cu")
		(remove_unused_layers yes)
		(keep_end_layers yes)
		(zone_layer_connections "In1.Cu" "In4.Cu" "In6.Cu")
		(net 28)
	)
	(via
		(at 119.35 79.279999)
		(size 0.45)
		(drill 0.2)
		(layers "F.Cu" "B.Cu")
		(remove_unused_layers yes)
		(keep_end_layers yes)
		(zone_layer_connections "In1.Cu" "In4.Cu" "In6.Cu")
		(net 28)
	)
	(via
		(at 69.58 98.95)
		(size 0.45)
		(drill 0.2)
		(layers "F.Cu" "B.Cu")
		(remove_unused_layers yes)
		(keep_end_layers yes)
		(zone_layer_connections "In1.Cu" "In4.Cu" "In6.Cu")
		(net 28)
	)
	(via
		(at 101.149905 72.095413)
		(size 0.45)
		(drill 0.2)
		(layers "F.Cu" "B.Cu")
		(remove_unused_layers yes)
		(keep_end_layers yes)
		(zone_layer_connections "In1.Cu" "In4.Cu" "In6.Cu")
		(net 28)
	)
	(via
		(at 91.749999 68.35)
		(size 0.45)
		(drill 0.2)
		(layers "F.Cu" "B.Cu")
		(remove_unused_layers yes)
		(keep_end_layers yes)
		(zone_layer_connections "In1.Cu" "In4.Cu" "In6.Cu")
		(net 28)
	)
	(via
		(at 81.225 92.65)
		(size 0.45)
		(drill 0.2)
		(layers "F.Cu" "B.Cu")
		(remove_unused_layers yes)
		(keep_end_layers yes)
		(zone_layer_connections "In1.Cu" "In4.Cu" "In6.Cu")
		(net 28)
	)
	(via
		(at 59.26 92.1)
		(size 0.45)
		(drill 0.1)
		(layers "F.Cu" "B.Cu")
		(remove_unused_layers yes)
		(keep_end_layers yes)
		(zone_layer_connections "In1.Cu" "In4.Cu" "In6.Cu")
		(net 28)
	)
	(via
		(at 84.2 52.552)
		(size 0.45)
		(drill 0.2)
		(layers "F.Cu" "B.Cu")
		(remove_unused_layers yes)
		(keep_end_layers yes)
		(zone_layer_connections "In1.Cu" "In4.Cu" "In6.Cu")
		(net 28)
	)
	(via
		(at 50.65 61.499997)
		(size 0.45)
		(drill 0.2)
		(layers "F.Cu" "B.Cu")
		(remove_unused_layers yes)
		(keep_end_layers yes)
		(zone_layer_connections "In1.Cu" "In4.Cu" "In6.Cu")
		(net 28)
	)
	(via
		(at 60.6 149.3)
		(size 0.45)
		(drill 0.2)
		(layers "F.Cu" "B.Cu")
		(remove_unused_layers yes)
		(keep_end_layers yes)
		(zone_layer_connections "In1.Cu" "In3.Cu" "In4.Cu" "In6.Cu")
		(net 28)
	)
	(via
		(at 69.800001 91.785001)
		(size 0.45)
		(drill 0.2)
		(layers "F.Cu" "B.Cu")
		(remove_unused_layers yes)
		(keep_end_layers yes)
		(zone_layer_connections "In1.Cu" "In4.Cu" "In6.Cu")
		(net 28)
	)
	(via
		(at 59.24 108.26)
		(size 0.45)
		(drill 0.1)
		(layers "F.Cu" "B.Cu")
		(remove_unused_layers yes)
		(keep_end_layers yes)
		(zone_layer_connections "In1.Cu" "In4.Cu" "In6.Cu")
		(net 28)
	)
	(via
		(at 59.96 93.46)
		(size 0.45)
		(drill 0.1)
		(layers "F.Cu" "B.Cu")
		(remove_unused_layers yes)
		(keep_end_layers yes)
		(zone_layer_connections "In1.Cu" "In4.Cu" "In6.Cu")
		(net 28)
	)
	(via
		(at 88.75 68.35)
		(size 0.45)
		(drill 0.2)
		(layers "F.Cu" "B.Cu")
		(remove_unused_layers yes)
		(keep_end_layers yes)
		(zone_layer_connections "In1.Cu" "In4.Cu" "In6.Cu")
		(net 28)
	)
	(via
		(at 97.479998 144.86)
		(size 0.45)
		(drill 0.2)
		(layers "F.Cu" "B.Cu")
		(remove_unused_layers yes)
		(keep_end_layers yes)
		(zone_layer_connections "In1.Cu" "In3.Cu" "In4.Cu" "In6.Cu")
		(net 28)
	)
	(via
		(at 99.85 101.325)
		(size 0.45)
		(drill 0.2)
		(layers "F.Cu" "B.Cu")
		(remove_unused_layers yes)
		(keep_end_layers yes)
		(zone_layer_connections "In1.Cu" "In4.Cu" "In6.Cu")
		(net 28)
	)
	(via
		(at 51.574999 95.825001)
		(size 0.45)
		(drill 0.1)
		(layers "F.Cu" "B.Cu")
		(remove_unused_layers yes)
		(keep_end_layers yes)
		(zone_layer_connections "In1.Cu" "In4.Cu" "In6.Cu")
		(net 28)
	)
	(via
		(at 59.96 92.1)
		(size 0.45)
		(drill 0.1)
		(layers "F.Cu" "B.Cu")
		(remove_unused_layers yes)
		(keep_end_layers yes)
		(zone_layer_connections "In1.Cu" "In4.Cu" "In6.Cu")
		(net 28)
	)
	(via
		(at 59.27 83.81)
		(size 0.45)
		(drill 0.1)
		(layers "F.Cu" "B.Cu")
		(remove_unused_layers yes)
		(keep_end_layers yes)
		(free yes)
		(zone_layer_connections "In1.Cu" "In4.Cu" "In6.Cu")
		(net 28)
	)
	(via
		(at 82.6 125.8)
		(size 0.45)
		(drill 0.2)
		(layers "F.Cu" "B.Cu")
		(remove_unused_layers yes)
		(keep_end_layers yes)
		(zone_layer_connections "In1.Cu" "In4.Cu" "In6.Cu")
		(net 28)
	)
	(via
		(at 99.95 50.65)
		(size 0.45)
		(drill 0.2)
		(layers "F.Cu" "B.Cu")
		(remove_unused_layers yes)
		(keep_end_layers yes)
		(zone_layer_connections "In1.Cu" "In4.Cu" "In6.Cu")
		(net 28)
	)
	(via
		(at 78.950001 76.499999)
		(size 0.45)
		(drill 0.2)
		(layers "F.Cu" "B.Cu")
		(remove_unused_layers yes)
		(keep_end_layers yes)
		(zone_layer_connections "In1.Cu" "In4.Cu" "In6.Cu")
		(net 28)
	)
	(via
		(at 119.35 127.28)
		(size 0.45)
		(drill 0.2)
		(layers "F.Cu" "B.Cu")
		(remove_unused_layers yes)
		(keep_end_layers yes)
		(zone_layer_connections "In1.Cu" "In3.Cu" "In4.Cu" "In6.Cu")
		(net 28)
	)
	(via
		(at 69.58 96.55)
		(size 0.45)
		(drill 0.2)
		(layers "F.Cu" "B.Cu")
		(remove_unused_layers yes)
		(keep_end_layers yes)
		(zone_layer_connections "In1.Cu" "In4.Cu" "In6.Cu")
		(net 28)
	)
	(via
		(at 88.725 91.785)
		(size 0.45)
		(drill 0.2)
		(layers "F.Cu" "B.Cu")
		(remove_unused_layers yes)
		(keep_end_layers yes)
		(zone_layer_connections "In1.Cu" "In4.Cu" "In6.Cu")
		(net 28)
	)
	(via
		(at 54.574999 94.825001)
		(size 0.45)
		(drill 0.1)
		(layers "F.Cu" "B.Cu")
		(remove_unused_layers yes)
		(keep_end_layers yes)
		(zone_layer_connections "In1.Cu" "In4.Cu" "In6.Cu")
		(net 28)
	)
	(via
		(at 59.95 106.91)
		(size 0.45)
		(drill 0.1)
		(layers "F.Cu" "B.Cu")
		(remove_unused_layers yes)
		(keep_end_layers yes)
		(zone_layer_connections "In1.Cu" "In4.Cu" "In6.Cu")
		(net 28)
	)
	(via
		(at 90.225 109.95)
		(size 0.45)
		(drill 0.2)
		(layers "F.Cu" "B.Cu")
		(remove_unused_layers yes)
		(keep_end_layers yes)
		(zone_layer_connections "In1.Cu" "In4.Cu" "In6.Cu")
		(net 28)
	)
	(via
		(at 62.65 133.499999)
		(size 0.45)
		(drill 0.2)
		(layers "F.Cu" "B.Cu")
		(remove_unused_layers yes)
		(keep_end_layers yes)
		(zone_layer_connections "In1.Cu" "In3.Cu" "In4.Cu" "In6.Cu")
		(net 28)
	)
	(via
		(at 101.35 115.28)
		(size 0.45)
		(drill 0.2)
		(layers "F.Cu" "B.Cu")
		(remove_unused_layers yes)
		(keep_end_layers yes)
		(zone_layer_connections "In1.Cu" "In4.Cu" "In6.Cu")
		(net 28)
	)
	(via
		(at 75.2 82.76)
		(size 0.45)
		(drill 0.1)
		(layers "F.Cu" "B.Cu")
		(remove_unused_layers yes)
		(keep_end_layers yes)
		(zone_layer_connections "In1.Cu" "In4.Cu" "In6.Cu")
		(net 28)
	)
	(via
		(at 77.225 90.92)
		(size 0.45)
		(drill 0.2)
		(layers "F.Cu" "B.Cu")
		(remove_unused_layers yes)
		(keep_end_layers yes)
		(zone_layer_connections "In1.Cu" "In4.Cu" "In6.Cu")
		(net 28)
	)
	(via
		(at 90.75 51.95)
		(size 0.45)
		(drill 0.2)
		(layers "F.Cu" "B.Cu")
		(remove_unused_layers yes)
		(keep_end_layers yes)
		(zone_layer_connections "In1.Cu" "In4.Cu" "In6.Cu")
		(net 28)
	)
	(via
		(at 69.15 110.9)
		(size 0.45)
		(drill 0.2)
		(layers "F.Cu" "B.Cu")
		(remove_unused_layers yes)
		(keep_end_layers yes)
		(zone_layer_connections "In1.Cu" "In4.Cu" "In6.Cu")
		(net 28)
	)
	(via
		(at 53.575 110.225001)
		(size 0.45)
		(drill 0.1)
		(layers "F.Cu" "B.Cu")
		(remove_unused_layers yes)
		(keep_end_layers yes)
		(zone_layer_connections "In1.Cu" "In4.Cu" "In6.Cu")
		(net 28)
	)
	(via
		(at 65.65 127.500001)
		(size 0.45)
		(drill 0.2)
		(layers "F.Cu" "B.Cu")
		(remove_unused_layers yes)
		(keep_end_layers yes)
		(zone_layer_connections "In1.Cu" "In4.Cu" "In6.Cu")
		(net 28)
	)
	(via
		(at 79.725 103.895)
		(size 0.45)
		(drill 0.2)
		(layers "F.Cu" "B.Cu")
		(remove_unused_layers yes)
		(keep_end_layers yes)
		(zone_layer_connections "In1.Cu" "In4.Cu" "In6.Cu")
		(net 28)
	)
	(via
		(at 82.82 127.1)
		(size 0.45)
		(drill 0.2)
		(layers "F.Cu" "B.Cu")
		(remove_unused_layers yes)
		(keep_end_layers yes)
		(zone_layer_connections "In1.Cu" "In4.Cu" "In6.Cu")
		(net 28)
	)
	(via
		(at 71.64 54.521)
		(size 0.45)
		(drill 0.2)
		(layers "F.Cu" "B.Cu")
		(remove_unused_layers yes)
		(keep_end_layers yes)
		(zone_layer_connections "In1.Cu" "In4.Cu" "In6.Cu")
		(net 28)
	)
	(via
		(at 68.15 111.9)
		(size 0.45)
		(drill 0.2)
		(layers "F.Cu" "B.Cu")
		(remove_unused_layers yes)
		(keep_end_layers yes)
		(zone_layer_connections "In1.Cu" "In4.Cu" "In6.Cu")
		(net 28)
	)
	(via
		(at 90.4 96.975)
		(size 0.45)
		(drill 0.2)
		(layers "F.Cu" "B.Cu")
		(remove_unused_layers yes)
		(keep_end_layers yes)
		(zone_layer_connections "In1.Cu" "In4.Cu" "In6.Cu")
		(net 28)
	)
	(via
		(at 56.97 73.715)
		(size 0.45)
		(drill 0.2)
		(layers "F.Cu" "B.Cu")
		(remove_unused_layers yes)
		(keep_end_layers yes)
		(zone_layer_connections "In1.Cu" "In4.Cu" "In6.Cu")
		(net 28)
	)
	(via
		(at 50.65 106.500001)
		(size 0.45)
		(drill 0.2)
		(layers "F.Cu" "B.Cu")
		(remove_unused_layers yes)
		(keep_end_layers yes)
		(zone_layer_connections "In1.Cu" "In4.Cu" "In6.Cu")
		(net 28)
	)
	(via
		(at 105.6 149.3)
		(size 0.45)
		(drill 0.2)
		(layers "F.Cu" "B.Cu")
		(remove_unused_layers yes)
		(keep_end_layers yes)
		(zone_layer_connections "In1.Cu" "In3.Cu" "In4.Cu" "In6.Cu")
		(net 28)
	)
	(via
		(at 81.725 103.895)
		(size 0.45)
		(drill 0.2)
		(layers "F.Cu" "B.Cu")
		(remove_unused_layers yes)
		(keep_end_layers yes)
		(zone_layer_connections "In1.Cu" "In4.Cu" "In6.Cu")
		(net 28)
	)
	(via
		(at 52.575001 87.125)
		(size 0.45)
		(drill 0.1)
		(layers "F.Cu" "B.Cu")
		(remove_unused_layers yes)
		(keep_end_layers yes)
		(zone_layer_connections "In1.Cu" "In4.Cu" "In6.Cu")
		(net 28)
	)
	(via
		(at 107.700001 83.8)
		(size 0.45)
		(drill 0.2)
		(layers "F.Cu" "B.Cu")
		(remove_unused_layers yes)
		(keep_end_layers yes)
		(zone_layer_connections "In1.Cu" "In4.Cu" "In6.Cu")
		(net 28)
	)
	(via
		(at 94.725 90.055)
		(size 0.45)
		(drill 0.2)
		(layers "F.Cu" "B.Cu")
		(remove_unused_layers yes)
		(keep_end_layers yes)
		(zone_layer_connections "In1.Cu" "In4.Cu" "In6.Cu")
		(net 28)
	)
	(via
		(at 67.4 90.55)
		(size 0.45)
		(drill 0.2)
		(layers "F.Cu" "B.Cu")
		(remove_unused_layers yes)
		(keep_end_layers yes)
		(zone_layer_connections "In1.Cu" "In4.Cu" "In6.Cu")
		(net 28)
	)
	(via
		(at 94.225 94.38)
		(size 0.45)
		(drill 0.2)
		(layers "F.Cu" "B.Cu")
		(remove_unused_layers yes)
		(keep_end_layers yes)
		(zone_layer_connections "In1.Cu" "In4.Cu" "In6.Cu")
		(net 28)
	)
	(via
		(at 50.65 73.5)
		(size 0.45)
		(drill 0.2)
		(layers "F.Cu" "B.Cu")
		(remove_unused_layers yes)
		(keep_end_layers yes)
		(zone_layer_connections "In1.Cu" "In4.Cu" "In6.Cu")
		(net 28)
	)
	(via
		(at 94.479999 137.15)
		(size 0.45)
		(drill 0.2)
		(layers "F.Cu" "B.Cu")
		(remove_unused_layers yes)
		(keep_end_layers yes)
		(zone_layer_connections "In1.Cu" "In3.Cu" "In4.Cu" "In6.Cu")
		(net 28)
	)
	(via
		(at 59.95 108.86)
		(size 0.45)
		(drill 0.1)
		(layers "F.Cu" "B.Cu")
		(remove_unused_layers yes)
		(keep_end_layers yes)
		(zone_layer_connections "In1.Cu" "In4.Cu" "In6.Cu")
		(net 28)
	)
	(via
		(at 70.15 110.9)
		(size 0.45)
		(drill 0.2)
		(layers "F.Cu" "B.Cu")
		(remove_unused_layers yes)
		(keep_end_layers yes)
		(zone_layer_connections "In1.Cu" "In4.Cu" "In6.Cu")
		(net 28)
	)
	(via
		(at 98.25 54.835)
		(size 0.45)
		(drill 0.2)
		(layers "F.Cu" "B.Cu")
		(remove_unused_layers yes)
		(keep_end_layers yes)
		(zone_layer_connections "In1.Cu" "In2.Cu" "In4.Cu" "In6.Cu")
		(net 28)
	)
	(via
		(at 82.725 93.515)
		(size 0.45)
		(drill 0.2)
		(layers "F.Cu" "B.Cu")
		(remove_unused_layers yes)
		(keep_end_layers yes)
		(zone_layer_connections "In1.Cu" "In4.Cu" "In6.Cu")
		(net 28)
	)
	(via
		(at 50.65 97.500001)
		(size 0.45)
		(drill 0.2)
		(layers "F.Cu" "B.Cu")
		(remove_unused_layers yes)
		(keep_end_layers yes)
		(zone_layer_connections "In1.Cu" "In4.Cu" "In6.Cu")
		(net 28)
	)
	(via
		(at 59.96 92.87)
		(size 0.45)
		(drill 0.1)
		(layers "F.Cu" "B.Cu")
		(remove_unused_layers yes)
		(keep_end_layers yes)
		(zone_layer_connections "In1.Cu" "In4.Cu" "In6.Cu")
		(net 28)
	)
	(via
		(at 88.725 107.355)
		(size 0.45)
		(drill 0.2)
		(layers "F.Cu" "B.Cu")
		(remove_unused_layers yes)
		(keep_end_layers yes)
		(zone_layer_connections "In1.Cu" "In4.Cu" "In6.Cu")
		(net 28)
	)
	(via
		(at 86.102 56.204)
		(size 0.45)
		(drill 0.2)
		(layers "F.Cu" "B.Cu")
		(remove_unused_layers yes)
		(keep_end_layers yes)
		(zone_layer_connections "In1.Cu" "In4.Cu" "In6.Cu")
		(net 28)
	)
	(via
		(at 58.5 58.5)
		(size 0.45)
		(drill 0.2)
		(layers "F.Cu" "B.Cu")
		(remove_unused_layers yes)
		(keep_end_layers yes)
		(zone_layer_connections "In1.Cu" "In4.Cu" "In6.Cu")
		(net 28)
	)
	(via
		(at 72.15 114.85)
		(size 0.45)
		(drill 0.2)
		(layers "F.Cu" "B.Cu")
		(remove_unused_layers yes)
		(keep_end_layers yes)
		(zone_layer_connections "In1.Cu" "In4.Cu" "In6.Cu")
		(net 28)
	)
	(via
		(at 67.25 84.05)
		(size 0.45)
		(drill 0.2)
		(layers "F.Cu" "B.Cu")
		(remove_unused_layers yes)
		(keep_end_layers yes)
		(zone_layer_connections "In1.Cu" "In4.Cu" "In6.Cu")
		(net 28)
	)
	(via
		(at 104.700002 83.8)
		(size 0.45)
		(drill 0.2)
		(layers "F.Cu" "B.Cu")
		(remove_unused_layers yes)
		(keep_end_layers yes)
		(zone_layer_connections "In1.Cu" "In4.Cu" "In6.Cu")
		(net 28)
	)
	(via
		(at 87.43 58.591999)
		(size 0.45)
		(drill 0.2)
		(layers "F.Cu" "B.Cu")
		(remove_unused_layers yes)
		(keep_end_layers yes)
		(zone_layer_connections "In1.Cu" "In4.Cu" "In6.Cu")
		(net 28)
	)
	(via
		(at 59.96 91.51)
		(size 0.45)
		(drill 0.1)
		(layers "F.Cu" "B.Cu")
		(remove_unused_layers yes)
		(keep_end_layers yes)
		(zone_layer_connections "In1.Cu" "In4.Cu" "In6.Cu")
		(net 28)
	)
	(via
		(at 119.35 133.28)
		(size 0.45)
		(drill 0.2)
		(layers "F.Cu" "B.Cu")
		(remove_unused_layers yes)
		(keep_end_layers yes)
		(zone_layer_connections "In1.Cu" "In3.Cu" "In4.Cu" "In6.Cu")
		(net 28)
	)
	(via
		(at 84.225 92.65)
		(size 0.45)
		(drill 0.2)
		(layers "F.Cu" "B.Cu")
		(remove_unused_layers yes)
		(keep_end_layers yes)
		(zone_layer_connections "In1.Cu" "In4.Cu" "In6.Cu")
		(net 28)
	)
	(via
		(at 76.725 107.355)
		(size 0.45)
		(drill 0.2)
		(layers "F.Cu" "B.Cu")
		(remove_unused_layers yes)
		(keep_end_layers yes)
		(zone_layer_connections "In1.Cu" "In4.Cu" "In6.Cu")
		(net 28)
	)
	(via
		(at 84.225 106.49)
		(size 0.45)
		(drill 0.2)
		(layers "F.Cu" "B.Cu")
		(remove_unused_layers yes)
		(keep_end_layers yes)
		(zone_layer_connections "In1.Cu" "In4.Cu" "In6.Cu")
		(net 28)
	)
	(via
		(at 85.225 92.65)
		(size 0.45)
		(drill 0.2)
		(layers "F.Cu" "B.Cu")
		(remove_unused_layers yes)
		(keep_end_layers yes)
		(zone_layer_connections "In1.Cu" "In4.Cu" "In6.Cu")
		(net 28)
	)
	(via
		(at 51.574999 94.825001)
		(size 0.45)
		(drill 0.1)
		(layers "F.Cu" "B.Cu")
		(remove_unused_layers yes)
		(keep_end_layers yes)
		(zone_layer_connections "In1.Cu" "In4.Cu" "In6.Cu")
		(net 28)
	)
	(via
		(at 106.91 57.300001)
		(size 0.45)
		(drill 0.2)
		(layers "F.Cu" "B.Cu")
		(remove_unused_layers yes)
		(keep_end_layers yes)
		(zone_layer_connections "In1.Cu" "In4.Cu" "In6.Cu")
		(net 28)
	)
	(via
		(at 64.55 103)
		(size 0.45)
		(drill 0.2)
		(layers "F.Cu" "B.Cu")
		(remove_unused_layers yes)
		(keep_end_layers yes)
		(zone_layer_connections "In1.Cu" "In4.Cu" "In6.Cu")
		(net 28)
	)
	(via
		(at 107.285 95.39)
		(size 0.45)
		(drill 0.2)
		(layers "F.Cu" "B.Cu")
		(remove_unused_layers yes)
		(keep_end_layers yes)
		(zone_layer_connections "In1.Cu" "In4.Cu" "In6.Cu")
		(net 28)
	)
	(via
		(at 87.725 95.255)
		(size 0.45)
		(drill 0.2)
		(layers "F.Cu" "B.Cu")
		(remove_unused_layers yes)
		(keep_end_layers yes)
		(zone_layer_connections "In1.Cu" "In4.Cu" "In6.Cu")
		(net 28)
	)
	(via
		(at 63.85 85.26)
		(size 0.45)
		(drill 0.1)
		(layers "F.Cu" "B.Cu")
		(remove_unused_layers yes)
		(keep_end_layers yes)
		(zone_layer_connections "In1.Cu" "In4.Cu" "In6.Cu")
		(net 28)
	)
	(via
		(at 59.24 99.81)
		(size 0.45)
		(drill 0.1)
		(layers "F.Cu" "B.Cu")
		(remove_unused_layers yes)
		(keep_end_layers yes)
		(zone_layer_connections "In1.Cu" "In4.Cu" "In6.Cu")
		(net 28)
	)
	(via
		(at 97.88 103.3)
		(size 0.45)
		(drill 0.2)
		(layers "F.Cu" "B.Cu")
		(remove_unused_layers yes)
		(keep_end_layers yes)
		(zone_layer_connections "In1.Cu" "In4.Cu" "In6.Cu")
		(net 28)
	)
	(via
		(at 99.175 99.3)
		(size 0.45)
		(drill 0.2)
		(layers "F.Cu" "B.Cu")
		(remove_unused_layers yes)
		(keep_end_layers yes)
		(zone_layer_connections "In1.Cu" "In4.Cu" "In6.Cu")
		(net 28)
	)
	(via
		(at 77.225 94.38)
		(size 0.45)
		(drill 0.2)
		(layers "F.Cu" "B.Cu")
		(remove_unused_layers yes)
		(keep_end_layers yes)
		(zone_layer_connections "In1.Cu" "In4.Cu" "In6.Cu")
		(net 28)
	)
	(via
		(at 83.725 105.625)
		(size 0.45)
		(drill 0.2)
		(layers "F.Cu" "B.Cu")
		(remove_unused_layers yes)
		(keep_end_layers yes)
		(zone_layer_connections "In1.Cu" "In4.Cu" "In6.Cu")
		(net 28)
	)
	(via
		(at 53.575 103.525002)
		(size 0.45)
		(drill 0.1)
		(layers "F.Cu" "B.Cu")
		(remove_unused_layers yes)
		(keep_end_layers yes)
		(zone_layer_connections "In1.Cu" "In4.Cu" "In6.Cu")
		(net 28)
	)
	(via
		(at 104.35 127.28)
		(size 0.45)
		(drill 0.2)
		(layers "F.Cu" "B.Cu")
		(remove_unused_layers yes)
		(keep_end_layers yes)
		(zone_layer_connections "In1.Cu" "In4.Cu" "In6.Cu")
		(net 28)
	)
	(via
		(at 118.33 103.39)
		(size 0.45)
		(drill 0.2)
		(layers "F.Cu" "B.Cu")
		(remove_unused_layers yes)
		(keep_end_layers yes)
		(zone_layer_connections "In1.Cu" "In4.Cu" "In6.Cu")
		(net 28)
	)
	(via
		(at 97.479998 143.15)
		(size 0.45)
		(drill 0.2)
		(layers "F.Cu" "B.Cu")
		(remove_unused_layers yes)
		(keep_end_layers yes)
		(zone_layer_connections "In1.Cu" "In3.Cu" "In4.Cu" "In6.Cu")
		(net 28)
	)
	(via
		(at 59.27 84.4)
		(size 0.45)
		(drill 0.1)
		(layers "F.Cu" "B.Cu")
		(remove_unused_layers yes)
		(keep_end_layers yes)
		(zone_layer_connections "In1.Cu" "In4.Cu" "In6.Cu")
		(net 28)
	)
	(via
		(at 71.2 79.589996)
		(size 0.45)
		(drill 0.1)
		(layers "F.Cu" "B.Cu")
		(remove_unused_layers yes)
		(keep_end_layers yes)
		(zone_layer_connections "In1.Cu" "In4.Cu" "In6.Cu")
		(net 28)
	)
	(via
		(at 79.725 93.515)
		(size 0.45)
		(drill 0.2)
		(layers "F.Cu" "B.Cu")
		(remove_unused_layers yes)
		(keep_end_layers yes)
		(zone_layer_connections "In1.Cu" "In4.Cu" "In6.Cu")
		(net 28)
	)
	(via
		(at 77.225 99.57)
		(size 0.45)
		(drill 0.2)
		(layers "F.Cu" "B.Cu")
		(remove_unused_layers yes)
		(keep_end_layers yes)
		(zone_layer_connections "In1.Cu" "In4.Cu" "In6.Cu")
		(net 28)
	)
	(via
		(at 81.95 73.499999)
		(size 0.45)
		(drill 0.2)
		(layers "F.Cu" "B.Cu")
		(remove_unused_layers yes)
		(keep_end_layers yes)
		(zone_layer_connections "In1.Cu" "In4.Cu" "In6.Cu")
		(net 28)
	)
	(via
		(at 105.5 129.300002)
		(size 0.45)
		(drill 0.2)
		(layers "F.Cu" "B.Cu")
		(remove_unused_layers yes)
		(keep_end_layers yes)
		(zone_layer_connections "In1.Cu" "In3.Cu" "In4.Cu" "In6.Cu")
		(net 28)
	)
	(via
		(at 90.25 56.05)
		(size 0.45)
		(drill 0.2)
		(layers "F.Cu" "B.Cu")
		(remove_unused_layers yes)
		(keep_end_layers yes)
		(zone_layer_connections "In1.Cu" "In4.Cu" "In6.Cu")
		(net 28)
	)
	(via
		(at 119.35 52.279997)
		(size 0.45)
		(drill 0.2)
		(layers "F.Cu" "B.Cu")
		(remove_unused_layers yes)
		(keep_end_layers yes)
		(zone_layer_connections "In1.Cu" "In4.Cu" "In6.Cu")
		(net 28)
	)
	(via
		(at 54.575 103.525002)
		(size 0.45)
		(drill 0.1)
		(layers "F.Cu" "B.Cu")
		(remove_unused_layers yes)
		(keep_end_layers yes)
		(zone_layer_connections "In1.Cu" "In4.Cu" "In6.Cu")
		(net 28)
	)
	(via
		(at 82.725 91.785)
		(size 0.45)
		(drill 0.2)
		(layers "F.Cu" "B.Cu")
		(remove_unused_layers yes)
		(keep_end_layers yes)
		(zone_layer_connections "In1.Cu" "In4.Cu" "In6.Cu")
		(net 28)
	)
	(via
		(at 92.725 90.055)
		(size 0.45)
		(drill 0.2)
		(layers "F.Cu" "B.Cu")
		(remove_unused_layers yes)
		(keep_end_layers yes)
		(zone_layer_connections "In1.Cu" "In4.Cu" "In6.Cu")
		(net 28)
	)
	(via
		(at 59.97 85.76)
		(size 0.45)
		(drill 0.1)
		(layers "F.Cu" "B.Cu")
		(remove_unused_layers yes)
		(keep_end_layers yes)
		(zone_layer_connections "In1.Cu" "In4.Cu" "In6.Cu")
		(net 28)
	)
	(via
		(at 107.35 133.28)
		(size 0.45)
		(drill 0.2)
		(layers "F.Cu" "B.Cu")
		(remove_unused_layers yes)
		(keep_end_layers yes)
		(zone_layer_connections "In1.Cu" "In3.Cu" "In4.Cu" "In6.Cu")
		(net 28)
	)
	(via
		(at 50.65 115.500001)
		(size 0.45)
		(drill 0.2)
		(layers "F.Cu" "B.Cu")
		(remove_unused_layers yes)
		(keep_end_layers yes)
		(zone_layer_connections "In1.Cu" "In4.Cu" "In6.Cu")
		(net 28)
	)
	(via
		(at 89.725 100.435)
		(size 0.45)
		(drill 0.2)
		(layers "F.Cu" "B.Cu")
		(remove_unused_layers yes)
		(keep_end_layers yes)
		(zone_layer_connections "In1.Cu" "In4.Cu" "In6.Cu")
		(net 28)
	)
	(via
		(at 82.725 103.895)
		(size 0.45)
		(drill 0.2)
		(layers "F.Cu" "B.Cu")
		(remove_unused_layers yes)
		(keep_end_layers yes)
		(zone_layer_connections "In1.Cu" "In4.Cu" "In6.Cu")
		(net 28)
	)
	(via
		(at 106.91 52.580001)
		(size 0.45)
		(drill 0.2)
		(layers "F.Cu" "B.Cu")
		(remove_unused_layers yes)
		(keep_end_layers yes)
		(zone_layer_connections "In1.Cu" "In4.Cu" "In6.Cu")
		(net 28)
	)
	(via
		(at 57.95 50.65)
		(size 0.45)
		(drill 0.2)
		(layers "F.Cu" "B.Cu")
		(remove_unused_layers yes)
		(keep_end_layers yes)
		(zone_layer_connections "In1.Cu" "In4.Cu" "In6.Cu")
		(net 28)
	)
	(via
		(at 86.725 100.435)
		(size 0.45)
		(drill 0.2)
		(layers "F.Cu" "B.Cu")
		(remove_unused_layers yes)
		(keep_end_layers yes)
		(zone_layer_connections "In1.Cu" "In4.Cu" "In6.Cu")
		(net 28)
	)
	(via
		(at 87.725 102.185)
		(size 0.45)
		(drill 0.2)
		(layers "F.Cu" "B.Cu")
		(remove_unused_layers yes)
		(keep_end_layers yes)
		(zone_layer_connections "In1.Cu" "In4.Cu" "In6.Cu")
		(net 28)
	)
	(via
		(at 88.725 100.435)
		(size 0.45)
		(drill 0.2)
		(layers "F.Cu" "B.Cu")
		(remove_unused_layers yes)
		(keep_end_layers yes)
		(zone_layer_connections "In1.Cu" "In4.Cu" "In6.Cu")
		(net 28)
	)
	(via
		(at 52.575 103.525002)
		(size 0.45)
		(drill 0.1)
		(layers "F.Cu" "B.Cu")
		(remove_unused_layers yes)
		(keep_end_layers yes)
		(zone_layer_connections "In1.Cu" "In4.Cu" "In6.Cu")
		(net 28)
	)
	(via
		(at 107.8 63.45)
		(size 0.45)
		(drill 0.2)
		(layers "F.Cu" "B.Cu")
		(remove_unused_layers yes)
		(keep_end_layers yes)
		(zone_layer_connections "In1.Cu" "In4.Cu" "In6.Cu")
		(net 28)
	)
	(via
		(at 92.35 115.28)
		(size 0.45)
		(drill 0.2)
		(layers "F.Cu" "B.Cu")
		(remove_unused_layers yes)
		(keep_end_layers yes)
		(zone_layer_connections "In1.Cu" "In4.Cu" "In6.Cu")
		(net 28)
	)
	(via
		(at 72.15 110.9)
		(size 0.45)
		(drill 0.2)
		(layers "F.Cu" "B.Cu")
		(remove_unused_layers yes)
		(keep_end_layers yes)
		(zone_layer_connections "In1.Cu" "In4.Cu" "In6.Cu")
		(net 28)
	)
	(via
		(at 98.35 118.28)
		(size 0.45)
		(drill 0.2)
		(layers "F.Cu" "B.Cu")
		(remove_unused_layers yes)
		(keep_end_layers yes)
		(zone_layer_connections "In1.Cu" "In4.Cu" "In6.Cu")
		(net 28)
	)
	(via
		(at 76.7 51.95)
		(size 0.45)
		(drill 0.2)
		(layers "F.Cu" "B.Cu")
		(remove_unused_layers yes)
		(keep_end_layers yes)
		(zone_layer_connections "In1.Cu" "In4.Cu" "In6.Cu")
		(net 28)
	)
	(via
		(at 85.225 103.03)
		(size 0.45)
		(drill 0.2)
		(layers "F.Cu" "B.Cu")
		(remove_unused_layers yes)
		(keep_end_layers yes)
		(zone_layer_connections "In1.Cu" "In4.Cu" "In6.Cu")
		(net 28)
	)
	(via
		(at 63.89 108.27)
		(size 0.45)
		(drill 0.1)
		(layers "F.Cu" "B.Cu")
		(remove_unused_layers yes)
		(keep_end_layers yes)
		(zone_layer_connections "In1.Cu" "In4.Cu" "In6.Cu")
		(net 28)
	)
	(via
		(at 53.575 111.225001)
		(size 0.45)
		(drill 0.1)
		(layers "F.Cu" "B.Cu")
		(remove_unused_layers yes)
		(keep_end_layers yes)
		(zone_layer_connections "In1.Cu" "In4.Cu" "In6.Cu")
		(net 28)
	)
	(via
		(at 94.479999 140.15)
		(size 0.45)
		(drill 0.2)
		(layers "F.Cu" "B.Cu")
		(remove_unused_layers yes)
		(keep_end_layers yes)
		(zone_layer_connections "In1.Cu" "In3.Cu" "In4.Cu" "In6.Cu")
		(net 28)
	)
	(via
		(at 60.190003 103.849999)
		(size 0.45)
		(drill 0.1)
		(layers "F.Cu" "B.Cu")
		(remove_unused_layers yes)
		(keep_end_layers yes)
		(zone_layer_connections "In1.Cu" "In4.Cu" "In6.Cu")
		(net 28)
	)
	(via
		(at 94.225 109.95)
		(size 0.45)
		(drill 0.2)
		(layers "F.Cu" "B.Cu")
		(remove_unused_layers yes)
		(keep_end_layers yes)
		(zone_layer_connections "In1.Cu" "In4.Cu" "In6.Cu")
		(net 28)
	)
	(via
		(at 69.745 58.776)
		(size 0.45)
		(drill 0.2)
		(layers "F.Cu" "B.Cu")
		(remove_unused_layers yes)
		(keep_end_layers yes)
		(zone_layer_connections "In1.Cu" "In4.Cu" "In6.Cu")
		(net 28)
	)
	(via
		(at 92.225 108.22)
		(size 0.45)
		(drill 0.2)
		(layers "F.Cu" "B.Cu")
		(remove_unused_layers yes)
		(keep_end_layers yes)
		(zone_layer_connections "In1.Cu" "In4.Cu" "In6.Cu")
		(net 28)
	)
	(via
		(at 52.575 102.525002)
		(size 0.45)
		(drill 0.1)
		(layers "F.Cu" "B.Cu")
		(remove_unused_layers yes)
		(keep_end_layers yes)
		(zone_layer_connections "In1.Cu" "In4.Cu" "In6.Cu")
		(net 28)
	)
	(via
		(at 71.874999 77.514996)
		(size 0.45)
		(drill 0.1)
		(layers "F.Cu" "B.Cu")
		(remove_unused_layers yes)
		(keep_end_layers yes)
		(zone_layer_connections "In1.Cu" "In4.Cu" "In6.Cu")
		(net 28)
	)
	(via
		(at 84.999 132.95)
		(size 0.45)
		(drill 0.2)
		(layers "F.Cu" "B.Cu")
		(remove_unused_layers yes)
		(keep_end_layers yes)
		(zone_layer_connections "In1.Cu" "In3.Cu" "In4.Cu" "In6.Cu")
		(net 28)
	)
	(via
		(at 93.81 113.610001)
		(size 0.45)
		(drill 0.2)
		(layers "F.Cu" "B.Cu")
		(remove_unused_layers yes)
		(keep_end_layers yes)
		(zone_layer_connections "In1.Cu" "In4.Cu" "In6.Cu")
		(net 28)
	)
	(via
		(at 100.25 58.765)
		(size 0.45)
		(drill 0.2)
		(layers "F.Cu" "B.Cu")
		(remove_unused_layers yes)
		(keep_end_layers yes)
		(zone_layer_connections "In1.Cu" "In2.Cu" "In4.Cu" "In6.Cu")
		(net 28)
	)
	(via
		(at 82.82 128.5)
		(size 0.45)
		(drill 0.2)
		(layers "F.Cu" "B.Cu")
		(remove_unused_layers yes)
		(keep_end_layers yes)
		(zone_layer_connections "In1.Cu" "In3.Cu" "In4.Cu" "In6.Cu")
		(net 28)
	)
	(via
		(at 98.5 99.975)
		(size 0.45)
		(drill 0.2)
		(layers "F.Cu" "B.Cu")
		(remove_unused_layers yes)
		(keep_end_layers yes)
		(zone_layer_connections "In1.Cu" "In4.Cu" "In6.Cu")
		(net 28)
	)
	(via
		(at 72.35 63.35)
		(size 0.45)
		(drill 0.2)
		(layers "F.Cu" "B.Cu")
		(remove_unused_layers yes)
		(keep_end_layers yes)
		(zone_layer_connections "In1.Cu" "In4.Cu" "In6.Cu")
		(net 28)
	)
	(via
		(at 108.6 149.3)
		(size 0.45)
		(drill 0.2)
		(layers "F.Cu" "B.Cu")
		(remove_unused_layers yes)
		(keep_end_layers yes)
		(zone_layer_connections "In1.Cu" "In3.Cu" "In4.Cu" "In6.Cu")
		(net 28)
	)
	(via
		(at 105.19 91.25)
		(size 0.45)
		(drill 0.2)
		(layers "F.Cu" "B.Cu")
		(remove_unused_layers yes)
		(keep_end_layers yes)
		(zone_layer_connections "In1.Cu" "In4.Cu" "In5.Cu" "In6.Cu")
		(net 28)
	)
	(via
		(at 50.65 112.5)
		(size 0.45)
		(drill 0.2)
		(layers "F.Cu" "B.Cu")
		(remove_unused_layers yes)
		(keep_end_layers yes)
		(zone_layer_connections "In1.Cu" "In4.Cu" "In6.Cu")
		(net 28)
	)
	(via
		(at 83.725 90.055)
		(size 0.45)
		(drill 0.2)
		(layers "F.Cu" "B.Cu")
		(remove_unused_layers yes)
		(keep_end_layers yes)
		(zone_layer_connections "In1.Cu" "In4.Cu" "In6.Cu")
		(net 28)
	)
	(via
		(at 59.26 85.76)
		(size 0.45)
		(drill 0.1)
		(layers "F.Cu" "B.Cu")
		(remove_unused_layers yes)
		(keep_end_layers yes)
		(free yes)
		(zone_layer_connections "In1.Cu" "In4.Cu" "In6.Cu")
		(net 28)
	)
	(via
		(at 78.349999 66.35)
		(size 0.45)
		(drill 0.2)
		(layers "F.Cu" "B.Cu")
		(remove_unused_layers yes)
		(keep_end_layers yes)
		(zone_layer_connections "In1.Cu" "In4.Cu" "In6.Cu")
		(net 28)
	)
	(via
		(at 108.95 50.65)
		(size 0.45)
		(drill 0.2)
		(layers "F.Cu" "B.Cu")
		(remove_unused_layers yes)
		(keep_end_layers yes)
		(zone_layer_connections "In1.Cu" "In4.Cu" "In6.Cu")
		(net 28)
	)
	(via
		(at 59.25 93.46)
		(size 0.45)
		(drill 0.1)
		(layers "F.Cu" "B.Cu")
		(remove_unused_layers yes)
		(keep_end_layers yes)
		(zone_layer_connections "In1.Cu" "In4.Cu" "In6.Cu")
		(net 28)
	)
	(via
		(at 71.64 52.521)
		(size 0.45)
		(drill 0.2)
		(layers "F.Cu" "B.Cu")
		(remove_unused_layers yes)
		(keep_end_layers yes)
		(zone_layer_connections "In1.Cu" "In4.Cu" "In6.Cu")
		(net 28)
	)
	(via
		(at 87.725 96.975)
		(size 0.45)
		(drill 0.2)
		(layers "F.Cu" "B.Cu")
		(remove_unused_layers yes)
		(keep_end_layers yes)
		(zone_layer_connections "In1.Cu" "In4.Cu" "In6.Cu")
		(net 28)
	)
	(via
		(at 116.35 127.28)
		(size 0.45)
		(drill 0.2)
		(layers "F.Cu" "B.Cu")
		(remove_unused_layers yes)
		(keep_end_layers yes)
		(zone_layer_connections "In1.Cu" "In3.Cu" "In4.Cu" "In6.Cu")
		(net 28)
	)
	(via
		(at 86.225 108.22)
		(size 0.45)
		(drill 0.2)
		(layers "F.Cu" "B.Cu")
		(remove_unused_layers yes)
		(keep_end_layers yes)
		(zone_layer_connections "In1.Cu" "In4.Cu" "In6.Cu")
		(net 28)
	)
	(via
		(at 54.575001 88.125)
		(size 0.45)
		(drill 0.1)
		(layers "F.Cu" "B.Cu")
		(remove_unused_layers yes)
		(keep_end_layers yes)
		(zone_layer_connections "In1.Cu" "In4.Cu" "In6.Cu")
		(net 28)
	)
	(via
		(at 59.97 83.81)
		(size 0.45)
		(drill 0.1)
		(layers "F.Cu" "B.Cu")
		(remove_unused_layers yes)
		(keep_end_layers yes)
		(zone_layer_connections "In1.Cu" "In4.Cu" "In6.Cu")
		(net 28)
	)
	(via
		(at 71.48 144.86)
		(size 0.45)
		(drill 0.2)
		(layers "F.Cu" "B.Cu")
		(remove_unused_layers yes)
		(keep_end_layers yes)
		(zone_layer_connections "In1.Cu" "In3.Cu" "In4.Cu" "In6.Cu")
		(net 28)
	)
	(via
		(at 76.725 105.625)
		(size 0.45)
		(drill 0.2)
		(layers "F.Cu" "B.Cu")
		(remove_unused_layers yes)
		(keep_end_layers yes)
		(zone_layer_connections "In1.Cu" "In4.Cu" "In6.Cu")
		(net 28)
	)
	(via
		(at 53.65 70.499999)
		(size 0.45)
		(drill 0.2)
		(layers "F.Cu" "B.Cu")
		(remove_unused_layers yes)
		(keep_end_layers yes)
		(zone_layer_connections "In1.Cu" "In4.Cu" "In6.Cu")
		(net 28)
	)
	(via
		(at 97.265 66.445)
		(size 0.45)
		(drill 0.2)
		(layers "F.Cu" "B.Cu")
		(remove_unused_layers yes)
		(keep_end_layers yes)
		(zone_layer_connections "In1.Cu" "In2.Cu" "In4.Cu" "In6.Cu")
		(net 28)
	)
	(via
		(at 67.25 86.050001)
		(size 0.45)
		(drill 0.2)
		(layers "F.Cu" "B.Cu")
		(remove_unused_layers yes)
		(keep_end_layers yes)
		(zone_layer_connections "In1.Cu" "In4.Cu" "In6.Cu")
		(net 28)
	)
	(via
		(at 119.35 130.28)
		(size 0.45)
		(drill 0.2)
		(layers "F.Cu" "B.Cu")
		(remove_unused_layers yes)
		(keep_end_layers yes)
		(zone_layer_connections "In1.Cu" "In3.Cu" "In4.Cu" "In6.Cu")
		(net 28)
	)
	(via
		(at 110.35 127.28)
		(size 0.45)
		(drill 0.2)
		(layers "F.Cu" "B.Cu")
		(remove_unused_layers yes)
		(keep_end_layers yes)
		(zone_layer_connections "In1.Cu" "In3.Cu" "In4.Cu" "In6.Cu")
		(net 28)
	)
	(via
		(at 111.265 117.784)
		(size 0.45)
		(drill 0.2)
		(layers "F.Cu" "B.Cu")
		(remove_unused_layers yes)
		(keep_end_layers yes)
		(zone_layer_connections "In1.Cu" "In3.Cu" "In4.Cu" "In6.Cu")
		(net 28)
	)
	(via
		(at 105.22 112.5)
		(size 0.45)
		(drill 0.2)
		(layers "F.Cu" "B.Cu")
		(remove_unused_layers yes)
		(keep_end_layers yes)
		(zone_layer_connections "In1.Cu" "In4.Cu" "In6.Cu")
		(net 28)
	)
	(via
		(at 95.25 54.835)
		(size 0.45)
		(drill 0.2)
		(layers "F.Cu" "B.Cu")
		(remove_unused_layers yes)
		(keep_end_layers yes)
		(zone_layer_connections "In1.Cu" "In2.Cu" "In4.Cu" "In6.Cu")
		(net 28)
	)
	(via
		(at 117.95 50.65)
		(size 0.45)
		(drill 0.2)
		(layers "F.Cu" "B.Cu")
		(remove_unused_layers yes)
		(keep_end_layers yes)
		(zone_layer_connections "In1.Cu" "In4.Cu" "In6.Cu")
		(net 28)
	)
	(via
		(at 62.26 51.947)
		(size 0.45)
		(drill 0.2)
		(layers "F.Cu" "B.Cu")
		(remove_unused_layers yes)
		(keep_end_layers yes)
		(zone_layer_connections "In1.Cu" "In4.Cu" "In6.Cu")
		(net 28)
	)
	(via
		(at 81.725 107.355)
		(size 0.45)
		(drill 0.2)
		(layers "F.Cu" "B.Cu")
		(remove_unused_layers yes)
		(keep_end_layers yes)
		(zone_layer_connections "In1.Cu" "In4.Cu" "In6.Cu")
		(net 28)
	)
	(via
		(at 72.479999 137.15)
		(size 0.45)
		(drill 0.2)
		(layers "F.Cu" "B.Cu")
		(remove_unused_layers yes)
		(keep_end_layers yes)
		(zone_layer_connections "In1.Cu" "In3.Cu" "In4.Cu" "In6.Cu")
		(net 28)
	)
	(via
		(at 88.225 108.22)
		(size 0.45)
		(drill 0.2)
		(layers "F.Cu" "B.Cu")
		(remove_unused_layers yes)
		(keep_end_layers yes)
		(zone_layer_connections "In1.Cu" "In4.Cu" "In6.Cu")
		(net 28)
	)
	(via
		(at 69.745 61.476)
		(size 0.45)
		(drill 0.2)
		(layers "F.Cu" "B.Cu")
		(remove_unused_layers yes)
		(keep_end_layers yes)
		(zone_layer_connections "In1.Cu" "In4.Cu" "In6.Cu")
		(net 28)
	)
	(via
		(at 86.725 95.255)
		(size 0.45)
		(drill 0.2)
		(layers "F.Cu" "B.Cu")
		(remove_unused_layers yes)
		(keep_end_layers yes)
		(zone_layer_connections "In1.Cu" "In4.Cu" "In6.Cu")
		(net 28)
	)
	(via
		(at 78.950001 73.499999)
		(size 0.45)
		(drill 0.2)
		(layers "F.Cu" "B.Cu")
		(remove_unused_layers yes)
		(keep_end_layers yes)
		(zone_layer_connections "In1.Cu" "In4.Cu" "In6.Cu")
		(net 28)
	)
	(via
		(at 59.94 101.17)
		(size 0.45)
		(drill 0.1)
		(layers "F.Cu" "B.Cu")
		(remove_unused_layers yes)
		(keep_end_layers yes)
		(zone_layer_connections "In1.Cu" "In4.Cu" "In6.Cu")
		(net 28)
	)
	(via
		(at 83.7 124.6)
		(size 0.45)
		(drill 0.2)
		(layers "F.Cu" "B.Cu")
		(remove_unused_layers yes)
		(keep_end_layers yes)
		(zone_layer_connections "In1.Cu" "In4.Cu" "In6.Cu")
		(net 28)
	)
	(via
		(at 84.725 105.625)
		(size 0.45)
		(drill 0.2)
		(layers "F.Cu" "B.Cu")
		(remove_unused_layers yes)
		(keep_end_layers yes)
		(zone_layer_connections "In1.Cu" "In4.Cu" "In6.Cu")
		(net 28)
	)
	(via
		(at 53.575 102.525002)
		(size 0.45)
		(drill 0.1)
		(layers "F.Cu" "B.Cu")
		(remove_unused_layers yes)
		(keep_end_layers yes)
		(zone_layer_connections "In1.Cu" "In4.Cu" "In6.Cu")
		(net 28)
	)
	(via
		(at 75.479998 144.86)
		(size 0.45)
		(drill 0.2)
		(layers "F.Cu" "B.Cu")
		(remove_unused_layers yes)
		(keep_end_layers yes)
		(zone_layer_connections "In1.Cu" "In3.Cu" "In4.Cu" "In6.Cu")
		(net 28)
	)
	(via
		(at 113.35 121.28)
		(size 0.45)
		(drill 0.2)
		(layers "F.Cu" "B.Cu")
		(remove_unused_layers yes)
		(keep_end_layers yes)
		(zone_layer_connections "In1.Cu" "In3.Cu" "In4.Cu" "In6.Cu")
		(net 28)
	)
	(via
		(at 95.829499 64.115)
		(size 0.45)
		(drill 0.2)
		(layers "F.Cu" "B.Cu")
		(remove_unused_layers yes)
		(keep_end_layers yes)
		(zone_layer_connections "In1.Cu" "In2.Cu" "In4.Cu" "In6.Cu")
		(net 28)
	)
	(via
		(at 98.5 98.625)
		(size 0.45)
		(drill 0.2)
		(layers "F.Cu" "B.Cu")
		(remove_unused_layers yes)
		(keep_end_layers yes)
		(zone_layer_connections "In1.Cu" "In4.Cu" "In6.Cu")
		(net 28)
	)
	(via
		(at 113.01 117.784)
		(size 0.45)
		(drill 0.2)
		(layers "F.Cu" "B.Cu")
		(remove_unused_layers yes)
		(keep_end_layers yes)
		(zone_layer_connections "In1.Cu" "In3.Cu" "In4.Cu" "In6.Cu")
		(net 28)
	)
	(via
		(at 50.65 55.499998)
		(size 0.45)
		(drill 0.2)
		(layers "F.Cu" "B.Cu")
		(remove_unused_layers yes)
		(keep_end_layers yes)
		(zone_layer_connections "In1.Cu" "In4.Cu" "In6.Cu")
		(net 28)
	)
	(via
		(at 59.94 99.22)
		(size 0.45)
		(drill 0.1)
		(layers "F.Cu" "B.Cu")
		(remove_unused_layers yes)
		(keep_end_layers yes)
		(zone_layer_connections "In1.Cu" "In4.Cu" "In6.Cu")
		(net 28)
	)
	(via
		(at 68.15 115.85)
		(size 0.45)
		(drill 0.2)
		(layers "F.Cu" "B.Cu")
		(remove_unused_layers yes)
		(keep_end_layers yes)
		(zone_layer_connections "In1.Cu" "In4.Cu" "In6.Cu")
		(net 28)
	)
	(via
		(at 104.35 115.45)
		(size 0.45)
		(drill 0.2)
		(layers "F.Cu" "B.Cu")
		(remove_unused_layers yes)
		(keep_end_layers yes)
		(free yes)
		(zone_layer_connections "In1.Cu" "In4.Cu" "In6.Cu")
		(net 28)
	)
	(via
		(at 84.6 149.3)
		(size 0.45)
		(drill 0.2)
		(layers "F.Cu" "B.Cu")
		(remove_unused_layers yes)
		(keep_end_layers yes)
		(zone_layer_connections "In1.Cu" "In3.Cu" "In4.Cu" "In6.Cu")
		(net 28)
	)
	(via
		(at 91.725 93.515)
		(size 0.45)
		(drill 0.2)
		(layers "F.Cu" "B.Cu")
		(remove_unused_layers yes)
		(keep_end_layers yes)
		(zone_layer_connections "In1.Cu" "In4.Cu" "In6.Cu")
		(net 28)
	)
	(via
		(at 81.725 105.625)
		(size 0.45)
		(drill 0.2)
		(layers "F.Cu" "B.Cu")
		(remove_unused_layers yes)
		(keep_end_layers yes)
		(zone_layer_connections "In1.Cu" "In4.Cu" "In6.Cu")
		(net 28)
	)
	(via
		(at 59.95 108.27)
		(size 0.45)
		(drill 0.1)
		(layers "F.Cu" "B.Cu")
		(remove_unused_layers yes)
		(keep_end_layers yes)
		(zone_layer_connections "In1.Cu" "In4.Cu" "In6.Cu")
		(net 28)
	)
	(via
		(at 90.95 50.65)
		(size 0.45)
		(drill 0.2)
		(layers "F.Cu" "B.Cu")
		(remove_unused_layers yes)
		(keep_end_layers yes)
		(zone_layer_connections "In1.Cu" "In4.Cu" "In6.Cu")
		(net 28)
	)
	(via
		(at 101.25 54.835)
		(size 0.45)
		(drill 0.2)
		(layers "F.Cu" "B.Cu")
		(remove_unused_layers yes)
		(keep_end_layers yes)
		(zone_layer_connections "In1.Cu" "In2.Cu" "In4.Cu" "In6.Cu")
		(net 28)
	)
	(via
		(at 67.25 83.05)
		(size 0.45)
		(drill 0.2)
		(layers "F.Cu" "B.Cu")
		(remove_unused_layers yes)
		(keep_end_layers yes)
		(zone_layer_connections "In1.Cu" "In4.Cu" "In6.Cu")
		(net 28)
	)
	(via
		(at 94.725 93.515)
		(size 0.45)
		(drill 0.2)
		(layers "F.Cu" "B.Cu")
		(remove_unused_layers yes)
		(keep_end_layers yes)
		(zone_layer_connections "In1.Cu" "In4.Cu" "In6.Cu")
		(net 28)
	)
	(via
		(at 50.65 127.5)
		(size 0.45)
		(drill 0.2)
		(layers "F.Cu" "B.Cu")
		(remove_unused_layers yes)
		(keep_end_layers yes)
		(zone_layer_connections "In1.Cu" "In3.Cu" "In4.Cu" "In6.Cu")
		(net 28)
	)
	(via
		(at 59.94 99.81)
		(size 0.45)
		(drill 0.1)
		(layers "F.Cu" "B.Cu")
		(remove_unused_layers yes)
		(keep_end_layers yes)
		(zone_layer_connections "In1.Cu" "In4.Cu" "In6.Cu")
		(net 28)
	)
	(via
		(at 111.15 107.599997)
		(size 0.45)
		(drill 0.2)
		(layers "F.Cu" "B.Cu")
		(remove_unused_layers yes)
		(keep_end_layers yes)
		(zone_layer_connections "In1.Cu" "In4.Cu" "In6.Cu")
		(net 28)
	)
	(via
		(at 59.23 101.17)
		(size 0.45)
		(drill 0.1)
		(layers "F.Cu" "B.Cu")
		(remove_unused_layers yes)
		(keep_end_layers yes)
		(zone_layer_connections "In1.Cu" "In4.Cu" "In6.Cu")
		(net 28)
	)
	(via
		(at 116.35 130.28)
		(size 0.45)
		(drill 0.2)
		(layers "F.Cu" "B.Cu")
		(remove_unused_layers yes)
		(keep_end_layers yes)
		(zone_layer_connections "In1.Cu" "In3.Cu" "In4.Cu" "In6.Cu")
		(net 28)
	)
	(via
		(at 87.225 92.65)
		(size 0.45)
		(drill 0.2)
		(layers "F.Cu" "B.Cu")
		(remove_unused_layers yes)
		(keep_end_layers yes)
		(zone_layer_connections "In1.Cu" "In4.Cu" "In6.Cu")
		(net 28)
	)
	(via
		(at 67.4 93.550001)
		(size 0.45)
		(drill 0.2)
		(layers "F.Cu" "B.Cu")
		(remove_unused_layers yes)
		(keep_end_layers yes)
		(zone_layer_connections "In1.Cu" "In4.Cu" "In6.Cu")
		(net 28)
	)
	(via
		(at 101.35 112.28)
		(size 0.45)
		(drill 0.2)
		(layers "F.Cu" "B.Cu")
		(remove_unused_layers yes)
		(keep_end_layers yes)
		(zone_layer_connections "In1.Cu" "In4.Cu" "In6.Cu")
		(net 28)
	)
	(via
		(at 61.5 58.5)
		(size 0.45)
		(drill 0.2)
		(layers "F.Cu" "B.Cu")
		(remove_unused_layers yes)
		(keep_end_layers yes)
		(zone_layer_connections "In1.Cu" "In4.Cu" "In6.Cu")
		(net 28)
	)
	(via
		(at 119.35 91.28)
		(size 0.45)
		(drill 0.2)
		(layers "F.Cu" "B.Cu")
		(remove_unused_layers yes)
		(keep_end_layers yes)
		(zone_layer_connections "In1.Cu" "In4.Cu" "In6.Cu")
		(net 28)
	)
	(via
		(at 64.600999 52.521)
		(size 0.45)
		(drill 0.2)
		(layers "F.Cu" "B.Cu")
		(remove_unused_layers yes)
		(keep_end_layers yes)
		(zone_layer_connections "In1.Cu" "In4.Cu" "In6.Cu")
		(net 28)
	)
	(via
		(at 78.725 105.625)
		(size 0.45)
		(drill 0.2)
		(layers "F.Cu" "B.Cu")
		(remove_unused_layers yes)
		(keep_end_layers yes)
		(zone_layer_connections "In1.Cu" "In4.Cu" "In6.Cu")
		(net 28)
	)
	(via
		(at 68.15 55.9)
		(size 0.45)
		(drill 0.2)
		(layers "F.Cu" "B.Cu")
		(remove_unused_layers yes)
		(keep_end_layers yes)
		(zone_layer_connections "In1.Cu" "In4.Cu" "In6.Cu")
		(net 28)
	)
	(via
		(at 73.84 82.76)
		(size 0.45)
		(drill 0.1)
		(layers "F.Cu" "B.Cu")
		(remove_unused_layers yes)
		(keep_end_layers yes)
		(zone_layer_connections "In1.Cu" "In4.Cu" "In6.Cu")
		(net 28)
	)
	(via
		(at 91.225 90.92)
		(size 0.45)
		(drill 0.2)
		(layers "F.Cu" "B.Cu")
		(remove_unused_layers yes)
		(keep_end_layers yes)
		(zone_layer_connections "In1.Cu" "In4.Cu" "In6.Cu")
		(net 28)
	)
	(via
		(at 77.9 84.325)
		(size 0.45)
		(drill 0.2)
		(layers "F.Cu" "B.Cu")
		(remove_unused_layers yes)
		(keep_end_layers yes)
		(zone_layer_connections "In1.Cu" "In4.Cu" "In6.Cu")
		(net 28)
	)
	(via
		(at 80.225 94.38)
		(size 0.45)
		(drill 0.2)
		(layers "F.Cu" "B.Cu")
		(remove_unused_layers yes)
		(keep_end_layers yes)
		(zone_layer_connections "In1.Cu" "In4.Cu" "In6.Cu")
		(net 28)
	)
	(via
		(at 87.6 149.3)
		(size 0.45)
		(drill 0.2)
		(layers "F.Cu" "B.Cu")
		(remove_unused_layers yes)
		(keep_end_layers yes)
		(zone_layer_connections "In1.Cu" "In3.Cu" "In4.Cu" "In6.Cu")
		(net 28)
	)
	(via
		(at 55.6 121.7)
		(size 0.45)
		(drill 0.2)
		(layers "F.Cu" "B.Cu")
		(remove_unused_layers yes)
		(keep_end_layers yes)
		(zone_layer_connections "In1.Cu" "In3.Cu" "In4.Cu" "In6.Cu")
		(net 28)
	)
	(via
		(at 87.52 132.4)
		(size 0.45)
		(drill 0.2)
		(layers "F.Cu" "B.Cu")
		(remove_unused_layers yes)
		(keep_end_layers yes)
		(zone_layer_connections "In1.Cu" "In3.Cu" "In4.Cu" "In6.Cu")
		(net 28)
	)
	(via
		(at 109.49 89.34)
		(size 0.45)
		(drill 0.2)
		(layers "F.Cu" "B.Cu")
		(remove_unused_layers yes)
		(keep_end_layers yes)
		(zone_layer_connections "In1.Cu" "In4.Cu" "In6.Cu")
		(net 28)
	)
	(via
		(at 95.75 58.355002)
		(size 0.45)
		(drill 0.2)
		(layers "F.Cu" "B.Cu")
		(remove_unused_layers yes)
		(keep_end_layers yes)
		(zone_layer_connections "In1.Cu" "In2.Cu" "In4.Cu" "In6.Cu")
		(net 28)
	)
	(via
		(at 99.175 97.95)
		(size 0.45)
		(drill 0.2)
		(layers "F.Cu" "B.Cu")
		(remove_unused_layers yes)
		(keep_end_layers yes)
		(zone_layer_connections "In1.Cu" "In4.Cu" "In6.Cu")
		(net 28)
	)
	(via
		(at 92.725 107.355)
		(size 0.45)
		(drill 0.2)
		(layers "F.Cu" "B.Cu")
		(remove_unused_layers yes)
		(keep_end_layers yes)
		(zone_layer_connections "In1.Cu" "In4.Cu" "In6.Cu")
		(net 28)
	)
	(via
		(at 69.950001 73.499999)
		(size 0.45)
		(drill 0.2)
		(layers "F.Cu" "B.Cu")
		(remove_unused_layers yes)
		(keep_end_layers yes)
		(zone_layer_connections "In1.Cu" "In4.Cu" "In6.Cu")
		(net 28)
	)
	(via
		(at 107.35 127.28)
		(size 0.45)
		(drill 0.2)
		(layers "F.Cu" "B.Cu")
		(remove_unused_layers yes)
		(keep_end_layers yes)
		(zone_layer_connections "In1.Cu" "In4.Cu" "In6.Cu")
		(net 28)
	)
	(via
		(at 85.402999 64.05)
		(size 0.45)
		(drill 0.2)
		(layers "F.Cu" "B.Cu")
		(remove_unused_layers yes)
		(keep_end_layers yes)
		(zone_layer_connections "In1.Cu" "In4.Cu" "In6.Cu")
		(net 28)
	)
	(via
		(at 69.262999 64.05)
		(size 0.45)
		(drill 0.2)
		(layers "F.Cu" "B.Cu")
		(remove_unused_layers yes)
		(keep_end_layers yes)
		(zone_layer_connections "In1.Cu" "In4.Cu" "In6.Cu")
		(net 28)
	)
	(via
		(at 89.225 90.92)
		(size 0.45)
		(drill 0.2)
		(layers "F.Cu" "B.Cu")
		(remove_unused_layers yes)
		(keep_end_layers yes)
		(zone_layer_connections "In1.Cu" "In4.Cu" "In6.Cu")
		(net 28)
	)
	(via
		(at 50.65 88.500001)
		(size 0.45)
		(drill 0.2)
		(layers "F.Cu" "B.Cu")
		(remove_unused_layers yes)
		(keep_end_layers yes)
		(zone_layer_connections "In1.Cu" "In4.Cu" "In6.Cu")
		(net 28)
	)
	(via
		(at 63.89 93.48)
		(size 0.45)
		(drill 0.1)
		(layers "F.Cu" "B.Cu")
		(remove_unused_layers yes)
		(keep_end_layers yes)
		(zone_layer_connections "In1.Cu" "In4.Cu" "In6.Cu")
		(net 28)
	)
	(via
		(at 67.4 92.550001)
		(size 0.45)
		(drill 0.2)
		(layers "F.Cu" "B.Cu")
		(remove_unused_layers yes)
		(keep_end_layers yes)
		(zone_layer_connections "In1.Cu" "In4.Cu" "In6.Cu")
		(net 28)
	)
	(via
		(at 85.225 109.95)
		(size 0.45)
		(drill 0.2)
		(layers "F.Cu" "B.Cu")
		(remove_unused_layers yes)
		(keep_end_layers yes)
		(zone_layer_connections "In1.Cu" "In4.Cu" "In6.Cu")
		(net 28)
	)
	(via
		(at 52.574999 95.825001)
		(size 0.45)
		(drill 0.1)
		(layers "F.Cu" "B.Cu")
		(remove_unused_layers yes)
		(keep_end_layers yes)
		(zone_layer_connections "In1.Cu" "In4.Cu" "In6.Cu")
		(net 28)
	)
	(via
		(at 59.25 106.9)
		(size 0.45)
		(drill 0.1)
		(layers "F.Cu" "B.Cu")
		(remove_unused_layers yes)
		(keep_end_layers yes)
		(zone_layer_connections "In1.Cu" "In4.Cu" "In6.Cu")
		(net 28)
	)
	(via
		(at 71.15 115.85)
		(size 0.45)
		(drill 0.2)
		(layers "F.Cu" "B.Cu")
		(remove_unused_layers yes)
		(keep_end_layers yes)
		(zone_layer_connections "In1.Cu" "In4.Cu" "In6.Cu")
		(net 28)
	)
	(via
		(at 59.65 127.500001)
		(size 0.45)
		(drill 0.2)
		(layers "F.Cu" "B.Cu")
		(remove_unused_layers yes)
		(keep_end_layers yes)
		(zone_layer_connections "In1.Cu" "In3.Cu" "In4.Cu" "In6.Cu")
		(net 28)
	)
	(via
		(at 95.35 115.28)
		(size 0.45)
		(drill 0.2)
		(layers "F.Cu" "B.Cu")
		(remove_unused_layers yes)
		(keep_end_layers yes)
		(zone_layer_connections "In1.Cu" "In4.Cu" "In6.Cu")
		(net 28)
	)
	(via
		(at 90.4 98.705)
		(size 0.45)
		(drill 0.2)
		(layers "F.Cu" "B.Cu")
		(remove_unused_layers yes)
		(keep_end_layers yes)
		(zone_layer_connections "In1.Cu" "In4.Cu" "In6.Cu")
		(net 28)
	)
	(via
		(at 73.25 83.34)
		(size 0.45)
		(drill 0.1)
		(layers "F.Cu" "B.Cu")
		(remove_unused_layers yes)
		(keep_end_layers yes)
		(zone_layer_connections "In1.Cu" "In4.Cu" "In6.Cu")
		(net 28)
	)
	(via
		(at 114.95 50.65)
		(size 0.45)
		(drill 0.2)
		(layers "F.Cu" "B.Cu")
		(remove_unused_layers yes)
		(keep_end_layers yes)
		(zone_layer_connections "In1.Cu" "In4.Cu" "In6.Cu")
		(net 28)
	)
	(via
		(at 99.6 149.3)
		(size 0.45)
		(drill 0.2)
		(layers "F.Cu" "B.Cu")
		(remove_unused_layers yes)
		(keep_end_layers yes)
		(zone_layer_connections "In1.Cu" "In3.Cu" "In4.Cu" "In6.Cu")
		(net 28)
	)
	(via
		(at 113.35 124.280001)
		(size 0.45)
		(drill 0.2)
		(layers "F.Cu" "B.Cu")
		(remove_unused_layers yes)
		(keep_end_layers yes)
		(zone_layer_connections "In1.Cu" "In3.Cu" "In4.Cu" "In6.Cu")
		(net 28)
	)
	(via
		(at 52.575001 88.125)
		(size 0.45)
		(drill 0.1)
		(layers "F.Cu" "B.Cu")
		(remove_unused_layers yes)
		(keep_end_layers yes)
		(zone_layer_connections "In1.Cu" "In4.Cu" "In6.Cu")
		(net 28)
	)
	(via
		(at 78.349999 63.35)
		(size 0.45)
		(drill 0.2)
		(layers "F.Cu" "B.Cu")
		(remove_unused_layers yes)
		(keep_end_layers yes)
		(zone_layer_connections "In1.Cu" "In4.Cu" "In6.Cu")
		(net 28)
	)
	(via
		(at 85.725 96.975)
		(size 0.45)
		(drill 0.2)
		(layers "F.Cu" "B.Cu")
		(remove_unused_layers yes)
		(keep_end_layers yes)
		(zone_layer_connections "In1.Cu" "In4.Cu" "In6.Cu")
		(net 28)
	)
	(via
		(at 92.225 90.92)
		(size 0.45)
		(drill 0.2)
		(layers "F.Cu" "B.Cu")
		(remove_unused_layers yes)
		(keep_end_layers yes)
		(zone_layer_connections "In1.Cu" "In4.Cu" "In6.Cu")
		(net 28)
	)
	(via
		(at 85.725 91.785)
		(size 0.45)
		(drill 0.2)
		(layers "F.Cu" "B.Cu")
		(remove_unused_layers yes)
		(keep_end_layers yes)
		(zone_layer_connections "In1.Cu" "In4.Cu" "In6.Cu")
		(net 28)
	)
	(via
		(at 51.6 149.3)
		(size 0.45)
		(drill 0.2)
		(layers "F.Cu" "B.Cu")
		(remove_unused_layers yes)
		(keep_end_layers yes)
		(zone_layer_connections "In1.Cu" "In3.Cu" "In4.Cu" "In6.Cu")
		(net 28)
	)
	(via
		(at 77.725 93.515)
		(size 0.45)
		(drill 0.2)
		(layers "F.Cu" "B.Cu")
		(remove_unused_layers yes)
		(keep_end_layers yes)
		(zone_layer_connections "In1.Cu" "In4.Cu" "In6.Cu")
		(net 28)
	)
	(via
		(at 104.35 118.28)
		(size 0.45)
		(drill 0.2)
		(layers "F.Cu" "B.Cu")
		(remove_unused_layers yes)
		(keep_end_layers yes)
		(zone_layer_connections "In1.Cu" "In4.Cu" "In6.Cu")
		(net 28)
	)
	(via
		(at 75.6 149.3)
		(size 0.45)
		(drill 0.2)
		(layers "F.Cu" "B.Cu")
		(remove_unused_layers yes)
		(keep_end_layers yes)
		(zone_layer_connections "In1.Cu" "In3.Cu" "In4.Cu" "In6.Cu")
		(net 28)
	)
	(via
		(at 57.099998 92.37)
		(size 0.45)
		(drill 0.1)
		(layers "F.Cu" "B.Cu")
		(remove_unused_layers yes)
		(keep_end_layers yes)
		(zone_layer_connections "In1.Cu" "In4.Cu" "In6.Cu")
		(net 28)
	)
	(via
		(at 101.35 127.28)
		(size 0.45)
		(drill 0.2)
		(layers "F.Cu" "B.Cu")
		(remove_unused_layers yes)
		(keep_end_layers yes)
		(zone_layer_connections "In1.Cu" "In4.Cu" "In6.Cu")
		(net 28)
	)
	(via
		(at 53.65 61.5)
		(size 0.45)
		(drill 0.2)
		(layers "F.Cu" "B.Cu")
		(remove_unused_layers yes)
		(keep_end_layers yes)
		(zone_layer_connections "In1.Cu" "In4.Cu" "In6.Cu")
		(net 28)
	)
	(via
		(at 69.15 111.9)
		(size 0.45)
		(drill 0.2)
		(layers "F.Cu" "B.Cu")
		(remove_unused_layers yes)
		(keep_end_layers yes)
		(zone_layer_connections "In1.Cu" "In4.Cu" "In6.Cu")
		(net 28)
	)
	(via
		(at 79.7 56.204)
		(size 0.45)
		(drill 0.2)
		(layers "F.Cu" "B.Cu")
		(remove_unused_layers yes)
		(keep_end_layers yes)
		(zone_layer_connections "In1.Cu" "In4.Cu" "In6.Cu")
		(net 28)
	)
	(via
		(at 105.049999 134.7)
		(size 0.45)
		(drill 0.2)
		(layers "F.Cu" "B.Cu")
		(remove_unused_layers yes)
		(keep_end_layers yes)
		(zone_layer_connections "In1.Cu" "In3.Cu" "In4.Cu" "In6.Cu")
		(net 28)
	)
	(via
		(at 59.25 92.87)
		(size 0.45)
		(drill 0.1)
		(layers "F.Cu" "B.Cu")
		(remove_unused_layers yes)
		(keep_end_layers yes)
		(zone_layer_connections "In1.Cu" "In4.Cu" "In6.Cu")
		(net 28)
	)
	(via
		(at 116.38 101.100001)
		(size 0.45)
		(drill 0.2)
		(layers "F.Cu" "B.Cu")
		(remove_unused_layers yes)
		(keep_end_layers yes)
		(zone_layer_connections "In1.Cu" "In4.Cu" "In6.Cu")
		(net 28)
	)
	(via
		(at 105.5 131.300001)
		(size 0.45)
		(drill 0.2)
		(layers "F.Cu" "B.Cu")
		(remove_unused_layers yes)
		(keep_end_layers yes)
		(zone_layer_connections "In1.Cu" "In3.Cu" "In4.Cu" "In6.Cu")
		(net 28)
	)
	(via
		(at 73.15 114.85)
		(size 0.45)
		(drill 0.2)
		(layers "F.Cu" "B.Cu")
		(remove_unused_layers yes)
		(keep_end_layers yes)
		(zone_layer_connections "In1.Cu" "In4.Cu" "In6.Cu")
		(net 28)
	)
	(via
		(at 72.6 149.3)
		(size 0.45)
		(drill 0.2)
		(layers "F.Cu" "B.Cu")
		(remove_unused_layers yes)
		(keep_end_layers yes)
		(zone_layer_connections "In1.Cu" "In3.Cu" "In4.Cu" "In6.Cu")
		(net 28)
	)
	(via
		(at 119.35 64.28)
		(size 0.45)
		(drill 0.2)
		(layers "F.Cu" "B.Cu")
		(remove_unused_layers yes)
		(keep_end_layers yes)
		(zone_layer_connections "In1.Cu" "In4.Cu" "In6.Cu")
		(net 28)
	)
	(via
		(at 64.600999 54.521)
		(size 0.45)
		(drill 0.2)
		(layers "F.Cu" "B.Cu")
		(remove_unused_layers yes)
		(keep_end_layers yes)
		(zone_layer_connections "In1.Cu" "In4.Cu" "In6.Cu")
		(net 28)
	)
	(via
		(at 98.68 88.5)
		(size 0.45)
		(drill 0.2)
		(layers "F.Cu" "B.Cu")
		(remove_unused_layers yes)
		(keep_end_layers yes)
		(zone_layer_connections "In1.Cu" "In4.Cu" "In5.Cu" "In6.Cu")
		(net 28)
	)
	(via
		(at 113.7 83.8)
		(size 0.45)
		(drill 0.2)
		(layers "F.Cu" "B.Cu")
		(remove_unused_layers yes)
		(keep_end_layers yes)
		(zone_layer_connections "In1.Cu" "In4.Cu" "In6.Cu")
		(net 28)
	)
	(via
		(at 78.225 94.38)
		(size 0.45)
		(drill 0.2)
		(layers "F.Cu" "B.Cu")
		(remove_unused_layers yes)
		(keep_end_layers yes)
		(zone_layer_connections "In1.Cu" "In4.Cu" "In6.Cu")
		(net 28)
	)
	(via
		(at 64.45 133.3)
		(size 0.45)
		(drill 0.2)
		(layers "F.Cu" "B.Cu")
		(remove_unused_layers yes)
		(keep_end_layers yes)
		(zone_layer_connections "In1.Cu" "In3.Cu" "In4.Cu" "In6.Cu")
		(net 28)
	)
	(via
		(at 50.65 79.499999)
		(size 0.45)
		(drill 0.2)
		(layers "F.Cu" "B.Cu")
		(remove_unused_layers yes)
		(keep_end_layers yes)
		(zone_layer_connections "In1.Cu" "In4.Cu" "In6.Cu")
		(net 28)
	)
	(via
		(at 72.15 115.85)
		(size 0.45)
		(drill 0.2)
		(layers "F.Cu" "B.Cu")
		(remove_unused_layers yes)
		(keep_end_layers yes)
		(zone_layer_connections "In1.Cu" "In4.Cu" "In6.Cu")
		(net 28)
	)
	(via
		(at 80.725 105.625)
		(size 0.45)
		(drill 0.2)
		(layers "F.Cu" "B.Cu")
		(remove_unused_layers yes)
		(keep_end_layers yes)
		(zone_layer_connections "In1.Cu" "In4.Cu" "In6.Cu")
		(net 28)
	)
	(via
		(at 101.35 118.28)
		(size 0.45)
		(drill 0.2)
		(layers "F.Cu" "B.Cu")
		(remove_unused_layers yes)
		(keep_end_layers yes)
		(zone_layer_connections "In1.Cu" "In4.Cu" "In6.Cu")
		(net 28)
	)
	(via
		(at 90.225 108.22)
		(size 0.45)
		(drill 0.2)
		(layers "F.Cu" "B.Cu")
		(remove_unused_layers yes)
		(keep_end_layers yes)
		(zone_layer_connections "In1.Cu" "In4.Cu" "In6.Cu")
		(net 28)
	)
	(via
		(at 61.5 55.5)
		(size 0.45)
		(drill 0.2)
		(layers "F.Cu" "B.Cu")
		(remove_unused_layers yes)
		(keep_end_layers yes)
		(zone_layer_connections "In1.Cu" "In4.Cu" "In6.Cu")
		(net 28)
	)
	(via
		(at 50.65 124.500001)
		(size 0.45)
		(drill 0.2)
		(layers "F.Cu" "B.Cu")
		(remove_unused_layers yes)
		(keep_end_layers yes)
		(zone_layer_connections "In1.Cu" "In3.Cu" "In4.Cu" "In6.Cu")
		(net 28)
	)
	(via
		(at 97.25 59.035)
		(size 0.45)
		(drill 0.2)
		(layers "F.Cu" "B.Cu")
		(remove_unused_layers yes)
		(keep_end_layers yes)
		(zone_layer_connections "In1.Cu" "In2.Cu" "In4.Cu" "In6.Cu")
		(net 28)
	)
	(via
		(at 68.65 121.500002)
		(size 0.45)
		(drill 0.2)
		(layers "F.Cu" "B.Cu")
		(remove_unused_layers yes)
		(keep_end_layers yes)
		(zone_layer_connections "In1.Cu" "In4.Cu" "In6.Cu")
		(net 28)
	)
	(via
		(at 84.95 73.499999)
		(size 0.45)
		(drill 0.2)
		(layers "F.Cu" "B.Cu")
		(remove_unused_layers yes)
		(keep_end_layers yes)
		(zone_layer_connections "In1.Cu" "In4.Cu" "In6.Cu")
		(net 28)
	)
	(via
		(at 107.35 130.28)
		(size 0.45)
		(drill 0.2)
		(layers "F.Cu" "B.Cu")
		(remove_unused_layers yes)
		(keep_end_layers yes)
		(zone_layer_connections "In1.Cu" "In3.Cu" "In4.Cu" "In6.Cu")
		(net 28)
	)
	(via
		(at 91.749999 65.35)
		(size 0.45)
		(drill 0.2)
		(layers "F.Cu" "B.Cu")
		(remove_unused_layers yes)
		(keep_end_layers yes)
		(zone_layer_connections "In1.Cu" "In4.Cu" "In6.Cu")
		(net 28)
	)
	(via
		(at 77.225 92.65)
		(size 0.45)
		(drill 0.2)
		(layers "F.Cu" "B.Cu")
		(remove_unused_layers yes)
		(keep_end_layers yes)
		(zone_layer_connections "In1.Cu" "In4.Cu" "In6.Cu")
		(net 28)
	)
	(via
		(at 79.225 90.92)
		(size 0.45)
		(drill 0.2)
		(layers "F.Cu" "B.Cu")
		(remove_unused_layers yes)
		(keep_end_layers yes)
		(zone_layer_connections "In1.Cu" "In4.Cu" "In6.Cu")
		(net 28)
	)
	(via
		(at 79.95 87.299)
		(size 0.45)
		(drill 0.2)
		(layers "F.Cu" "B.Cu")
		(remove_unused_layers yes)
		(keep_end_layers yes)
		(zone_layer_connections "In1.Cu" "In4.Cu" "In6.Cu")
		(net 28)
	)
	(via
		(at 59.97 85.17)
		(size 0.45)
		(drill 0.1)
		(layers "F.Cu" "B.Cu")
		(remove_unused_layers yes)
		(keep_end_layers yes)
		(zone_layer_connections "In1.Cu" "In4.Cu" "In6.Cu")
		(net 28)
	)
	(via
		(at 72.95 50.65)
		(size 0.45)
		(drill 0.2)
		(layers "F.Cu" "B.Cu")
		(remove_unused_layers yes)
		(keep_end_layers yes)
		(zone_layer_connections "In1.Cu" "In4.Cu" "In6.Cu")
		(net 28)
	)
	(via
		(at 50.65 109.5)
		(size 0.45)
		(drill 0.2)
		(layers "F.Cu" "B.Cu")
		(remove_unused_layers yes)
		(keep_end_layers yes)
		(zone_layer_connections "In1.Cu" "In4.Cu" "In6.Cu")
		(net 28)
	)
	(via
		(at 62.65 118.5)
		(size 0.45)
		(drill 0.2)
		(layers "F.Cu" "B.Cu")
		(remove_unused_layers yes)
		(keep_end_layers yes)
		(zone_layer_connections "In1.Cu" "In3.Cu" "In4.Cu" "In6.Cu")
		(net 28)
	)
	(via
		(at 50.65 64.499998)
		(size 0.45)
		(drill 0.2)
		(layers "F.Cu" "B.Cu")
		(remove_unused_layers yes)
		(keep_end_layers yes)
		(zone_layer_connections "In1.Cu" "In4.Cu" "In6.Cu")
		(net 28)
	)
	(via
		(at 75.95 50.65)
		(size 0.45)
		(drill 0.2)
		(layers "F.Cu" "B.Cu")
		(remove_unused_layers yes)
		(keep_end_layers yes)
		(zone_layer_connections "In1.Cu" "In4.Cu" "In6.Cu")
		(net 28)
	)
	(via
		(at 86.725 103.895)
		(size 0.45)
		(drill 0.2)
		(layers "F.Cu" "B.Cu")
		(remove_unused_layers yes)
		(keep_end_layers yes)
		(zone_layer_connections "In1.Cu" "In4.Cu" "In6.Cu")
		(net 28)
	)
	(via
		(at 93.09 52.580001)
		(size 0.45)
		(drill 0.2)
		(layers "F.Cu" "B.Cu")
		(remove_unused_layers yes)
		(keep_end_layers yes)
		(zone_layer_connections "In1.Cu" "In4.Cu" "In6.Cu")
		(net 28)
	)
	(via
		(at 75.725 107.355)
		(size 0.45)
		(drill 0.2)
		(layers "F.Cu" "B.Cu")
		(remove_unused_layers yes)
		(keep_end_layers yes)
		(zone_layer_connections "In1.Cu" "In4.Cu" "In6.Cu")
		(net 28)
	)
	(via
		(at 81.95 76.499999)
		(size 0.45)
		(drill 0.2)
		(layers "F.Cu" "B.Cu")
		(remove_unused_layers yes)
		(keep_end_layers yes)
		(zone_layer_connections "In1.Cu" "In4.Cu" "In6.Cu")
		(net 28)
	)
	(via
		(at 97.479998 137.15)
		(size 0.45)
		(drill 0.2)
		(layers "F.Cu" "B.Cu")
		(remove_unused_layers yes)
		(keep_end_layers yes)
		(zone_layer_connections "In1.Cu" "In3.Cu" "In4.Cu" "In6.Cu")
		(net 28)
	)
	(via
		(at 77.725 91.785)
		(size 0.45)
		(drill 0.2)
		(layers "F.Cu" "B.Cu")
		(remove_unused_layers yes)
		(keep_end_layers yes)
		(zone_layer_connections "In1.Cu" "In4.Cu" "In6.Cu")
		(net 28)
	)
	(via
		(at 116.35 133.28)
		(size 0.45)
		(drill 0.2)
		(layers "F.Cu" "B.Cu")
		(remove_unused_layers yes)
		(keep_end_layers yes)
		(zone_layer_connections "In1.Cu" "In3.Cu" "In4.Cu" "In6.Cu")
		(net 28)
	)
	(via
		(at 103.25 59.035)
		(size 0.45)
		(drill 0.2)
		(layers "F.Cu" "B.Cu")
		(remove_unused_layers yes)
		(keep_end_layers yes)
		(zone_layer_connections "In1.Cu" "In2.Cu" "In4.Cu" "In6.Cu")
		(net 28)
	)
	(via
		(at 99.829999 110.1)
		(size 0.45)
		(drill 0.2)
		(layers "F.Cu" "B.Cu")
		(remove_unused_layers yes)
		(keep_end_layers yes)
		(zone_layer_connections "In1.Cu" "In4.Cu" "In6.Cu")
		(net 28)
	)
	(via
		(at 93.725 109.085)
		(size 0.45)
		(drill 0.2)
		(layers "F.Cu" "B.Cu")
		(remove_unused_layers yes)
		(keep_end_layers yes)
		(zone_layer_connections "In1.Cu" "In4.Cu" "In6.Cu")
		(net 28)
	)
	(via
		(at 52.574999 94.825001)
		(size 0.45)
		(drill 0.1)
		(layers "F.Cu" "B.Cu")
		(remove_unused_layers yes)
		(keep_end_layers yes)
		(zone_layer_connections "In1.Cu" "In4.Cu" "In6.Cu")
		(net 28)
	)
	(via
		(at 91.749999 62.35)
		(size 0.45)
		(drill 0.2)
		(layers "F.Cu" "B.Cu")
		(remove_unused_layers yes)
		(keep_end_layers yes)
		(zone_layer_connections "In1.Cu" "In4.Cu" "In6.Cu")
		(net 28)
	)
	(via
		(at 86.32 68.38)
		(size 0.45)
		(drill 0.2)
		(layers "F.Cu" "B.Cu")
		(remove_unused_layers yes)
		(keep_end_layers yes)
		(zone_layer_connections "In1.Cu" "In4.Cu" "In6.Cu")
		(net 28)
	)
	(via
		(at 86.353 63.7)
		(size 0.45)
		(drill 0.2)
		(layers "F.Cu" "B.Cu")
		(remove_unused_layers yes)
		(keep_end_layers yes)
		(zone_layer_connections "In1.Cu" "In4.Cu" "In6.Cu")
		(net 28)
	)
	(via
		(at 53.574999 95.825001)
		(size 0.45)
		(drill 0.1)
		(layers "F.Cu" "B.Cu")
		(remove_unused_layers yes)
		(keep_end_layers yes)
		(zone_layer_connections "In1.Cu" "In4.Cu" "In6.Cu")
		(net 28)
	)
	(via
		(at 89.25 115)
		(size 0.45)
		(drill 0.2)
		(layers "F.Cu" "B.Cu")
		(remove_unused_layers yes)
		(keep_end_layers yes)
		(zone_layer_connections "In1.Cu" "In4.Cu" "In6.Cu")
		(net 28)
	)
	(via
		(at 54.6 149.3)
		(size 0.45)
		(drill 0.2)
		(layers "F.Cu" "B.Cu")
		(remove_unused_layers yes)
		(keep_end_layers yes)
		(zone_layer_connections "In1.Cu" "In3.Cu" "In4.Cu" "In6.Cu")
		(net 28)
	)
	(via
		(at 79.225 94.38)
		(size 0.45)
		(drill 0.2)
		(layers "F.Cu" "B.Cu")
		(remove_unused_layers yes)
		(keep_end_layers yes)
		(zone_layer_connections "In1.Cu" "In4.Cu" "In6.Cu")
		(net 28)
	)
	(via
		(at 92.225 109.95)
		(size 0.45)
		(drill 0.2)
		(layers "F.Cu" "B.Cu")
		(remove_unused_layers yes)
		(keep_end_layers yes)
		(zone_layer_connections "In1.Cu" "In4.Cu" "In6.Cu")
		(net 28)
	)
	(via
		(at 64.45 129.300002)
		(size 0.45)
		(drill 0.2)
		(layers "F.Cu" "B.Cu")
		(remove_unused_layers yes)
		(keep_end_layers yes)
		(zone_layer_connections "In1.Cu" "In3.Cu" "In4.Cu" "In6.Cu")
		(net 28)
	)
	(via
		(at 66 103)
		(size 0.45)
		(drill 0.2)
		(layers "F.Cu" "B.Cu")
		(remove_unused_layers yes)
		(keep_end_layers yes)
		(zone_layer_connections "In1.Cu" "In4.Cu" "In6.Cu")
		(net 28)
	)
	(via
		(at 113.2 102.700001)
		(size 0.45)
		(drill 0.2)
		(layers "F.Cu" "B.Cu")
		(remove_unused_layers yes)
		(keep_end_layers yes)
		(zone_layer_connections "In1.Cu" "In4.Cu" "In6.Cu")
		(net 28)
	)
	(via
		(at 57.63 127.45)
		(size 0.45)
		(drill 0.2)
		(layers "F.Cu" "B.Cu")
		(remove_unused_layers yes)
		(keep_end_layers yes)
		(zone_layer_connections "In1.Cu" "In3.Cu" "In4.Cu" "In6.Cu")
		(net 28)
	)
	(via
		(at 63.89 101.17)
		(size 0.45)
		(drill 0.1)
		(layers "F.Cu" "B.Cu")
		(remove_unused_layers yes)
		(keep_end_layers yes)
		(zone_layer_connections "In1.Cu" "In4.Cu" "In6.Cu")
		(net 28)
	)
	(via
		(at 72.950001 73.499999)
		(size 0.45)
		(drill 0.2)
		(layers "F.Cu" "B.Cu")
		(remove_unused_layers yes)
		(keep_end_layers yes)
		(zone_layer_connections "In1.Cu" "In4.Cu" "In6.Cu")
		(net 28)
	)
	(via
		(at 87.725 98.705)
		(size 0.45)
		(drill 0.2)
		(layers "F.Cu" "B.Cu")
		(remove_unused_layers yes)
		(keep_end_layers yes)
		(zone_layer_connections "In1.Cu" "In4.Cu" "In6.Cu")
		(net 28)
	)
	(via
		(at 113.35 130.28)
		(size 0.45)
		(drill 0.2)
		(layers "F.Cu" "B.Cu")
		(remove_unused_layers yes)
		(keep_end_layers yes)
		(zone_layer_connections "In1.Cu" "In3.Cu" "In4.Cu" "In6.Cu")
		(net 28)
	)
	(via
		(at 60.189999 96.149996)
		(size 0.45)
		(drill 0.1)
		(layers "F.Cu" "B.Cu")
		(remove_unused_layers yes)
		(keep_end_layers yes)
		(zone_layer_connections "In1.Cu" "In4.Cu" "In6.Cu")
		(net 28)
	)
	(via
		(at 86.225 109.95)
		(size 0.45)
		(drill 0.2)
		(layers "F.Cu" "B.Cu")
		(remove_unused_layers yes)
		(keep_end_layers yes)
		(zone_layer_connections "In1.Cu" "In4.Cu" "In6.Cu")
		(net 28)
	)
	(via
		(at 69.950001 50.65)
		(size 0.45)
		(drill 0.2)
		(layers "F.Cu" "B.Cu")
		(remove_unused_layers yes)
		(keep_end_layers yes)
		(zone_layer_connections "In1.Cu" "In4.Cu" "In6.Cu")
		(net 28)
	)
	(via
		(at 96.05 113.613001)
		(size 0.45)
		(drill 0.2)
		(layers "F.Cu" "B.Cu")
		(remove_unused_layers yes)
		(keep_end_layers yes)
		(zone_layer_connections "In1.Cu" "In4.Cu" "In6.Cu")
		(net 28)
	)
	(via
		(at 98.35 121.28)
		(size 0.45)
		(drill 0.2)
		(layers "F.Cu" "B.Cu")
		(remove_unused_layers yes)
		(keep_end_layers yes)
		(zone_layer_connections "In1.Cu" "In4.Cu" "In6.Cu")
		(net 28)
	)
	(via
		(at 67.25 89.050003)
		(size 0.45)
		(drill 0.2)
		(layers "F.Cu" "B.Cu")
		(remove_unused_layers yes)
		(keep_end_layers yes)
		(zone_layer_connections "In1.Cu" "In4.Cu" "In6.Cu")
		(net 28)
	)
	(via
		(at 110.35 130.28)
		(size 0.45)
		(drill 0.2)
		(layers "F.Cu" "B.Cu")
		(remove_unused_layers yes)
		(keep_end_layers yes)
		(zone_layer_connections "In1.Cu" "In3.Cu" "In4.Cu" "In6.Cu")
		(net 28)
	)
	(via
		(at 69.9 105.55)
		(size 0.45)
		(drill 0.2)
		(layers "F.Cu" "B.Cu")
		(remove_unused_layers yes)
		(keep_end_layers yes)
		(zone_layer_connections "In1.Cu" "In4.Cu" "In6.Cu")
		(net 28)
	)
	(via
		(at 53.161 82.284)
		(size 0.45)
		(drill 0.2)
		(layers "F.Cu" "B.Cu")
		(remove_unused_layers yes)
		(keep_end_layers yes)
		(zone_layer_connections "In1.Cu" "In4.Cu" "In6.Cu")
		(net 28)
	)
	(via
		(at 62.65 136.499998)
		(size 0.45)
		(drill 0.2)
		(layers "F.Cu" "B.Cu")
		(remove_unused_layers yes)
		(keep_end_layers yes)
		(zone_layer_connections "In1.Cu" "In3.Cu" "In4.Cu" "In6.Cu")
		(net 28)
	)
	(via
		(at 119.35 124.280001)
		(size 0.45)
		(drill 0.2)
		(layers "F.Cu" "B.Cu")
		(remove_unused_layers yes)
		(keep_end_layers yes)
		(zone_layer_connections "In1.Cu" "In3.Cu" "In4.Cu" "In6.Cu")
		(net 28)
	)
	(via
		(at 115.55 88.6)
		(size 0.45)
		(drill 0.2)
		(layers "F.Cu" "B.Cu")
		(remove_unused_layers yes)
		(keep_end_layers yes)
		(zone_layer_connections "In1.Cu" "In4.Cu" "In6.Cu")
		(net 28)
	)
	(via
		(at 73.15 115.85)
		(size 0.45)
		(drill 0.2)
		(layers "F.Cu" "B.Cu")
		(remove_unused_layers yes)
		(keep_end_layers yes)
		(zone_layer_connections "In1.Cu" "In4.Cu" "In6.Cu")
		(net 28)
	)
	(via
		(at 86.725 90.055)
		(size 0.45)
		(drill 0.2)
		(layers "F.Cu" "B.Cu")
		(remove_unused_layers yes)
		(keep_end_layers yes)
		(zone_layer_connections "In1.Cu" "In4.Cu" "In6.Cu")
		(net 28)
	)
	(via
		(at 100.82 104.25)
		(size 0.45)
		(drill 0.2)
		(layers "F.Cu" "B.Cu")
		(remove_unused_layers yes)
		(keep_end_layers yes)
		(zone_layer_connections "In1.Cu" "In4.Cu" "In6.Cu")
		(net 28)
	)
	(via
		(at 57.099999 107.769999)
		(size 0.45)
		(drill 0.1)
		(layers "F.Cu" "B.Cu")
		(remove_unused_layers yes)
		(keep_end_layers yes)
		(zone_layer_connections "In1.Cu" "In4.Cu" "In6.Cu")
		(net 28)
	)
	(via
		(at 54.099999 107.769997)
		(size 0.45)
		(drill 0.1)
		(layers "F.Cu" "B.Cu")
		(remove_unused_layers yes)
		(keep_end_layers yes)
		(zone_layer_connections "In1.Cu" "In4.Cu" "In6.Cu")
		(net 28)
	)
	(via
		(at 83.37 57.771999)
		(size 0.45)
		(drill 0.2)
		(layers "F.Cu" "B.Cu")
		(remove_unused_layers yes)
		(keep_end_layers yes)
		(zone_layer_connections "In1.Cu" "In4.Cu" "In6.Cu")
		(net 28)
	)
	(via
		(at 70.213 63.7)
		(size 0.45)
		(drill 0.2)
		(layers "F.Cu" "B.Cu")
		(remove_unused_layers yes)
		(keep_end_layers yes)
		(zone_layer_connections "In1.Cu" "In4.Cu" "In6.Cu")
		(net 28)
	)
	(via
		(at 99.85 98.625)
		(size 0.45)
		(drill 0.2)
		(layers "F.Cu" "B.Cu")
		(remove_unused_layers yes)
		(keep_end_layers yes)
		(zone_layer_connections "In1.Cu" "In4.Cu" "In6.Cu")
		(net 28)
	)
	(via
		(at 80.7 121.600001)
		(size 0.45)
		(drill 0.2)
		(layers "F.Cu" "B.Cu")
		(remove_unused_layers yes)
		(keep_end_layers yes)
		(zone_layer_connections "In1.Cu" "In4.Cu" "In6.Cu")
		(net 28)
	)
	(via
		(at 87.52 131.4)
		(size 0.45)
		(drill 0.2)
		(layers "F.Cu" "B.Cu")
		(remove_unused_layers yes)
		(keep_end_layers yes)
		(zone_layer_connections "In1.Cu" "In3.Cu" "In4.Cu" "In6.Cu")
		(net 28)
	)
	(via
		(at 79.725 91.785)
		(size 0.45)
		(drill 0.2)
		(layers "F.Cu" "B.Cu")
		(remove_unused_layers yes)
		(keep_end_layers yes)
		(zone_layer_connections "In1.Cu" "In4.Cu" "In6.Cu")
		(net 28)
	)
	(via
		(at 90.725 100.435)
		(size 0.45)
		(drill 0.2)
		(layers "F.Cu" "B.Cu")
		(remove_unused_layers yes)
		(keep_end_layers yes)
		(zone_layer_connections "In1.Cu" "In4.Cu" "In6.Cu")
		(net 28)
	)
	(via
		(at 56.65 130.5)
		(size 0.45)
		(drill 0.2)
		(layers "F.Cu" "B.Cu")
		(remove_unused_layers yes)
		(keep_end_layers yes)
		(zone_layer_connections "In1.Cu" "In3.Cu" "In4.Cu" "In6.Cu")
		(net 28)
	)
	(via
		(at 110.35 112.279999)
		(size 0.45)
		(drill 0.2)
		(layers "F.Cu" "B.Cu")
		(remove_unused_layers yes)
		(keep_end_layers yes)
		(zone_layer_connections "In1.Cu" "In3.Cu" "In4.Cu" "In6.Cu")
		(net 28)
	)
	(via
		(at 67.25 88.050003)
		(size 0.45)
		(drill 0.2)
		(layers "F.Cu" "B.Cu")
		(remove_unused_layers yes)
		(keep_end_layers yes)
		(zone_layer_connections "In1.Cu" "In4.Cu" "In6.Cu")
		(net 28)
	)
	(via
		(at 104.43 131.4)
		(size 0.45)
		(drill 0.2)
		(layers "F.Cu" "B.Cu")
		(remove_unused_layers yes)
		(keep_end_layers yes)
		(zone_layer_connections "In1.Cu" "In3.Cu" "In4.Cu" "In6.Cu")
		(net 28)
	)
	(via
		(at 50.65 58.499999)
		(size 0.45)
		(drill 0.2)
		(layers "F.Cu" "B.Cu")
		(remove_unused_layers yes)
		(keep_end_layers yes)
		(zone_layer_connections "In1.Cu" "In4.Cu" "In6.Cu")
		(net 28)
	)
	(via
		(at 101.42 91.15)
		(size 0.45)
		(drill 0.2)
		(layers "F.Cu" "B.Cu")
		(remove_unused_layers yes)
		(keep_end_layers yes)
		(zone_layer_connections "In1.Cu" "In4.Cu" "In5.Cu" "In6.Cu")
		(net 28)
	)
	(via
		(at 104.78 63.985)
		(size 0.45)
		(drill 0.2)
		(layers "F.Cu" "B.Cu")
		(remove_unused_layers yes)
		(keep_end_layers yes)
		(zone_layer_connections "In1.Cu" "In2.Cu" "In4.Cu" "In6.Cu")
		(net 28)
	)
	(via
		(at 106 107.965)
		(size 0.45)
		(drill 0.2)
		(layers "F.Cu" "B.Cu")
		(remove_unused_layers yes)
		(keep_end_layers yes)
		(zone_layer_connections "In1.Cu" "In4.Cu" "In6.Cu")
		(net 28)
	)
	(via
		(at 116.35 124.280001)
		(size 0.45)
		(drill 0.2)
		(layers "F.Cu" "B.Cu")
		(remove_unused_layers yes)
		(keep_end_layers yes)
		(zone_layer_connections "In1.Cu" "In3.Cu" "In4.Cu" "In6.Cu")
		(net 28)
	)
	(via
		(at 81.95 79.499999)
		(size 0.45)
		(drill 0.2)
		(layers "F.Cu" "B.Cu")
		(remove_unused_layers yes)
		(keep_end_layers yes)
		(zone_layer_connections "In1.Cu" "In4.Cu" "In6.Cu")
		(net 28)
	)
	(via
		(at 114.15 91.099999)
		(size 0.45)
		(drill 0.2)
		(layers "F.Cu" "B.Cu")
		(remove_unused_layers yes)
		(keep_end_layers yes)
		(zone_layer_connections "In1.Cu" "In4.Cu" "In6.Cu")
		(net 28)
	)
	(via
		(at 83.7 121.600001)
		(size 0.45)
		(drill 0.2)
		(layers "F.Cu" "B.Cu")
		(remove_unused_layers yes)
		(keep_end_layers yes)
		(zone_layer_connections "In1.Cu" "In4.Cu" "In6.Cu")
		(net 28)
	)
	(via
		(at 91.725 109.085)
		(size 0.45)
		(drill 0.2)
		(layers "F.Cu" "B.Cu")
		(remove_unused_layers yes)
		(keep_end_layers yes)
		(zone_layer_connections "In1.Cu" "In4.Cu" "In6.Cu")
		(net 28)
	)
	(via
		(at 72.45 100.249999)
		(size 0.45)
		(drill 0.2)
		(layers "F.Cu" "B.Cu")
		(remove_unused_layers yes)
		(keep_end_layers yes)
		(zone_layer_connections "In1.Cu" "In4.Cu" "In6.Cu")
		(net 28)
	)
	(via
		(at 85.725 98.705)
		(size 0.45)
		(drill 0.2)
		(layers "F.Cu" "B.Cu")
		(remove_unused_layers yes)
		(keep_end_layers yes)
		(zone_layer_connections "In1.Cu" "In4.Cu" "In6.Cu")
		(net 28)
	)
	(via
		(at 90.225 92.55)
		(size 0.45)
		(drill 0.2)
		(layers "F.Cu" "B.Cu")
		(remove_unused_layers yes)
		(keep_end_layers yes)
		(zone_layer_connections "In1.Cu" "In4.Cu" "In6.Cu")
		(net 28)
	)
	(via
		(at 69.07 59.451)
		(size 0.45)
		(drill 0.2)
		(layers "F.Cu" "B.Cu")
		(remove_unused_layers yes)
		(keep_end_layers yes)
		(zone_layer_connections "In1.Cu" "In4.Cu" "In6.Cu")
		(net 28)
	)
	(via
		(at 55.649999 95.5)
		(size 0.45)
		(drill 0.1)
		(layers "F.Cu" "B.Cu")
		(remove_unused_layers yes)
		(keep_end_layers yes)
		(zone_layer_connections "In1.Cu" "In4.Cu" "In6.Cu")
		(net 28)
	)
	(via
		(at 72.35 60.35)
		(size 0.45)
		(drill 0.2)
		(layers "F.Cu" "B.Cu")
		(remove_unused_layers yes)
		(keep_end_layers yes)
		(zone_layer_connections "In1.Cu" "In4.Cu" "In6.Cu")
		(net 28)
	)
	(via
		(at 69.745 62.801)
		(size 0.45)
		(drill 0.2)
		(layers "F.Cu" "B.Cu")
		(remove_unused_layers yes)
		(keep_end_layers yes)
		(zone_layer_connections "In1.Cu" "In4.Cu" "In6.Cu")
		(net 28)
	)
	(via
		(at 87.725 109.085)
		(size 0.45)
		(drill 0.2)
		(layers "F.Cu" "B.Cu")
		(remove_unused_layers yes)
		(keep_end_layers yes)
		(zone_layer_connections "In1.Cu" "In4.Cu" "In6.Cu")
		(net 28)
	)
	(via
		(at 87.949999 73.499999)
		(size 0.45)
		(drill 0.2)
		(layers "F.Cu" "B.Cu")
		(remove_unused_layers yes)
		(keep_end_layers yes)
		(zone_layer_connections "In1.Cu" "In4.Cu" "In6.Cu")
		(net 28)
	)
	(via
		(at 70.874999 76.514996)
		(size 0.45)
		(drill 0.1)
		(layers "F.Cu" "B.Cu")
		(remove_unused_layers yes)
		(keep_end_layers yes)
		(zone_layer_connections "In1.Cu" "In4.Cu" "In6.Cu")
		(net 28)
	)
	(via
		(at 69.04 107.91)
		(size 0.45)
		(drill 0.2)
		(layers "F.Cu" "B.Cu")
		(remove_unused_layers yes)
		(keep_end_layers yes)
		(zone_layer_connections "In1.Cu" "In4.Cu" "In6.Cu")
		(net 28)
	)
	(via
		(at 70.85 83.45)
		(size 0.45)
		(drill 0.1)
		(layers "F.Cu" "B.Cu")
		(remove_unused_layers yes)
		(keep_end_layers yes)
		(zone_layer_connections "In1.Cu" "In4.Cu" "In6.Cu")
		(net 28)
	)
	(via
		(at 63.88 92.83)
		(size 0.45)
		(drill 0.1)
		(layers "F.Cu" "B.Cu")
		(remove_unused_layers yes)
		(keep_end_layers yes)
		(zone_layer_connections "In1.Cu" "In4.Cu" "In6.Cu")
		(net 28)
	)
	(via
		(at 88.225 92.65)
		(size 0.45)
		(drill 0.2)
		(layers "F.Cu" "B.Cu")
		(remove_unused_layers yes)
		(keep_end_layers yes)
		(zone_layer_connections "In1.Cu" "In4.Cu" "In6.Cu")
		(net 28)
	)
	(via
		(at 53.575001 87.125)
		(size 0.45)
		(drill 0.1)
		(layers "F.Cu" "B.Cu")
		(remove_unused_layers yes)
		(keep_end_layers yes)
		(zone_layer_connections "In1.Cu" "In4.Cu" "In6.Cu")
		(net 28)
	)
	(via
		(at 67.25 85.049999)
		(size 0.45)
		(drill 0.2)
		(layers "F.Cu" "B.Cu")
		(remove_unused_layers yes)
		(keep_end_layers yes)
		(zone_layer_connections "In1.Cu" "In4.Cu" "In6.Cu")
		(net 28)
	)
	(via
		(at 75.95 73.499999)
		(size 0.45)
		(drill 0.2)
		(layers "F.Cu" "B.Cu")
		(remove_unused_layers yes)
		(keep_end_layers yes)
		(zone_layer_connections "In1.Cu" "In4.Cu" "In6.Cu")
		(net 28)
	)
	(via
		(at 75.225 105.15)
		(size 0.45)
		(drill 0.2)
		(layers "F.Cu" "B.Cu")
		(remove_unused_layers yes)
		(keep_end_layers yes)
		(zone_layer_connections "In1.Cu" "In4.Cu" "In6.Cu")
		(net 28)
	)
	(via
		(at 82.43 57.771999)
		(size 0.45)
		(drill 0.2)
		(layers "F.Cu" "B.Cu")
		(remove_unused_layers yes)
		(keep_end_layers yes)
		(zone_layer_connections "In1.Cu" "In4.Cu" "In6.Cu")
		(net 28)
	)
	(via
		(at 89.725 95.245)
		(size 0.45)
		(drill 0.2)
		(layers "F.Cu" "B.Cu")
		(remove_unused_layers yes)
		(keep_end_layers yes)
		(zone_layer_connections "In1.Cu" "In4.Cu" "In6.Cu")
		(net 28)
	)
	(via
		(at 83.225 106.49)
		(size 0.45)
		(drill 0.2)
		(layers "F.Cu" "B.Cu")
		(remove_unused_layers yes)
		(keep_end_layers yes)
		(zone_layer_connections "In1.Cu" "In4.Cu" "In6.Cu")
		(net 28)
	)
	(via
		(at 69.745 60.126)
		(size 0.45)
		(drill 0.2)
		(layers "F.Cu" "B.Cu")
		(remove_unused_layers yes)
		(keep_end_layers yes)
		(zone_layer_connections "In1.Cu" "In4.Cu" "In6.Cu")
		(net 28)
	)
	(via
		(at 70.874999 75.514995)
		(size 0.45)
		(drill 0.1)
		(layers "F.Cu" "B.Cu")
		(remove_unused_layers yes)
		(keep_end_layers yes)
		(zone_layer_connections "In1.Cu" "In4.Cu" "In6.Cu")
		(net 28)
	)
	(via
		(at 69.07 62.151)
		(size 0.45)
		(drill 0.2)
		(layers "F.Cu" "B.Cu")
		(remove_unused_layers yes)
		(keep_end_layers yes)
		(zone_layer_connections "In1.Cu" "In4.Cu" "In6.Cu")
		(net 28)
	)
	(via
		(at 75.725 105.635)
		(size 0.45)
		(drill 0.2)
		(layers "F.Cu" "B.Cu")
		(remove_unused_layers yes)
		(keep_end_layers yes)
		(zone_layer_connections "In1.Cu" "In4.Cu" "In6.Cu")
		(net 28)
	)
	(via
		(at 69.6 149.3)
		(size 0.45)
		(drill 0.2)
		(layers "F.Cu" "B.Cu")
		(remove_unused_layers yes)
		(keep_end_layers yes)
		(zone_layer_connections "In1.Cu" "In3.Cu" "In4.Cu" "In6.Cu")
		(net 28)
	)
	(via
		(at 91.725 91.785)
		(size 0.45)
		(drill 0.2)
		(layers "F.Cu" "B.Cu")
		(remove_unused_layers yes)
		(keep_end_layers yes)
		(zone_layer_connections "In1.Cu" "In4.Cu" "In6.Cu")
		(net 28)
	)
	(via
		(at 116.7 83.8)
		(size 0.45)
		(drill 0.2)
		(layers "F.Cu" "B.Cu")
		(remove_unused_layers yes)
		(keep_end_layers yes)
		(zone_layer_connections "In1.Cu" "In4.Cu" "In6.Cu")
		(net 28)
	)
	(via
		(at 95.35 118.28)
		(size 0.45)
		(drill 0.2)
		(layers "F.Cu" "B.Cu")
		(remove_unused_layers yes)
		(keep_end_layers yes)
		(zone_layer_connections "In1.Cu" "In4.Cu" "In6.Cu")
		(net 28)
	)
	(via
		(at 92.725 93.515)
		(size 0.45)
		(drill 0.2)
		(layers "F.Cu" "B.Cu")
		(remove_unused_layers yes)
		(keep_end_layers yes)
		(zone_layer_connections "In1.Cu" "In4.Cu" "In6.Cu")
		(net 28)
	)
	(via
		(at 109.35 93.93)
		(size 0.45)
		(drill 0.2)
		(layers "F.Cu" "B.Cu")
		(remove_unused_layers yes)
		(keep_end_layers yes)
		(zone_layer_connections "In1.Cu" "In4.Cu" "In6.Cu")
		(net 28)
	)
	(via
		(at 80.07 128.1)
		(size 0.45)
		(drill 0.2)
		(layers "F.Cu" "B.Cu")
		(remove_unused_layers yes)
		(keep_end_layers yes)
		(zone_layer_connections "In1.Cu" "In3.Cu" "In4.Cu" "In6.Cu")
		(net 28)
	)
	(via
		(at 101.75 58.355002)
		(size 0.45)
		(drill 0.2)
		(layers "F.Cu" "B.Cu")
		(remove_unused_layers yes)
		(keep_end_layers yes)
		(zone_layer_connections "In1.Cu" "In2.Cu" "In4.Cu" "In6.Cu")
		(net 28)
	)
	(via
		(at 51.575 102.525002)
		(size 0.45)
		(drill 0.1)
		(layers "F.Cu" "B.Cu")
		(remove_unused_layers yes)
		(keep_end_layers yes)
		(zone_layer_connections "In1.Cu" "In4.Cu" "In6.Cu")
		(net 28)
	)
	(via
		(at 85.725 95.255)
		(size 0.45)
		(drill 0.2)
		(layers "F.Cu" "B.Cu")
		(remove_unused_layers yes)
		(keep_end_layers yes)
		(zone_layer_connections "In1.Cu" "In4.Cu" "In6.Cu")
		(net 28)
	)
	(via
		(at 80.725 91.785)
		(size 0.45)
		(drill 0.2)
		(layers "F.Cu" "B.Cu")
		(remove_unused_layers yes)
		(keep_end_layers yes)
		(zone_layer_connections "In1.Cu" "In4.Cu" "In6.Cu")
		(net 28)
	)
	(via
		(at 84.95 79.499999)
		(size 0.45)
		(drill 0.2)
		(layers "F.Cu" "B.Cu")
		(remove_unused_layers yes)
		(keep_end_layers yes)
		(zone_layer_connections "In1.Cu" "In4.Cu" "In6.Cu")
		(net 28)
	)
	(via
		(at 98.668501 63.928655)
		(size 0.45)
		(drill 0.2)
		(layers "F.Cu" "B.Cu")
		(remove_unused_layers yes)
		(keep_end_layers yes)
		(zone_layer_connections "In1.Cu" "In2.Cu" "In4.Cu" "In6.Cu")
		(net 28)
	)
	(via
		(at 65.65 124.500002)
		(size 0.45)
		(drill 0.2)
		(layers "F.Cu" "B.Cu")
		(remove_unused_layers yes)
		(keep_end_layers yes)
		(zone_layer_connections "In1.Cu" "In4.Cu" "In6.Cu")
		(net 28)
	)
	(via
		(at 80.725 90.055)
		(size 0.45)
		(drill 0.2)
		(layers "F.Cu" "B.Cu")
		(remove_unused_layers yes)
		(keep_end_layers yes)
		(zone_layer_connections "In1.Cu" "In4.Cu" "In6.Cu")
		(net 28)
	)
	(via
		(at 73.25 82.76)
		(size 0.45)
		(drill 0.1)
		(layers "F.Cu" "B.Cu")
		(remove_unused_layers yes)
		(keep_end_layers yes)
		(zone_layer_connections "In1.Cu" "In4.Cu" "In6.Cu")
		(net 28)
	)
	(via
		(at 101.78 66.495)
		(size 0.45)
		(drill 0.2)
		(layers "F.Cu" "B.Cu")
		(remove_unused_layers yes)
		(keep_end_layers yes)
		(zone_layer_connections "In1.Cu" "In2.Cu" "In4.Cu" "In6.Cu")
		(net 28)
	)
	(via
		(at 93.225 108.22)
		(size 0.45)
		(drill 0.2)
		(layers "F.Cu" "B.Cu")
		(remove_unused_layers yes)
		(keep_end_layers yes)
		(zone_layer_connections "In1.Cu" "In4.Cu" "In6.Cu")
		(net 28)
	)
	(via
		(at 119.35 82.28)
		(size 0.45)
		(drill 0.2)
		(layers "F.Cu" "B.Cu")
		(remove_unused_layers yes)
		(keep_end_layers yes)
		(zone_layer_connections "In1.Cu" "In4.Cu" "In6.Cu")
		(net 28)
	)
	(via
		(at 62.65 127.500001)
		(size 0.45)
		(drill 0.2)
		(layers "F.Cu" "B.Cu")
		(remove_unused_layers yes)
		(keep_end_layers yes)
		(zone_layer_connections "In1.Cu" "In3.Cu" "In4.Cu" "In6.Cu")
		(net 28)
	)
	(via
		(at 102.75 54.835)
		(size 0.45)
		(drill 0.2)
		(layers "F.Cu" "B.Cu")
		(remove_unused_layers yes)
		(keep_end_layers yes)
		(zone_layer_connections "In1.Cu" "In2.Cu" "In4.Cu" "In6.Cu")
		(net 28)
	)
	(via
		(at 103.21 66.485)
		(size 0.45)
		(drill 0.2)
		(layers "F.Cu" "B.Cu")
		(remove_unused_layers yes)
		(keep_end_layers yes)
		(zone_layer_connections "In1.Cu" "In2.Cu" "In4.Cu" "In6.Cu")
		(net 28)
	)
	(via
		(at 54.099998 92.369999)
		(size 0.45)
		(drill 0.1)
		(layers "F.Cu" "B.Cu")
		(remove_unused_layers yes)
		(keep_end_layers yes)
		(zone_layer_connections "In1.Cu" "In4.Cu" "In6.Cu")
		(net 28)
	)
	(via
		(at 100.82 105.2)
		(size 0.45)
		(drill 0.2)
		(layers "F.Cu" "B.Cu")
		(remove_unused_layers yes)
		(keep_end_layers yes)
		(zone_layer_connections "In1.Cu" "In4.Cu" "In6.Cu")
		(net 28)
	)
	(via
		(at 50.65 94.5)
		(size 0.45)
		(drill 0.2)
		(layers "F.Cu" "B.Cu")
		(remove_unused_layers yes)
		(keep_end_layers yes)
		(zone_layer_connections "In1.Cu" "In4.Cu" "In6.Cu")
		(net 28)
	)
	(via
		(at 99.175 100.65)
		(size 0.45)
		(drill 0.2)
		(layers "F.Cu" "B.Cu")
		(remove_unused_layers yes)
		(keep_end_layers yes)
		(zone_layer_connections "In1.Cu" "In4.Cu" "In6.Cu")
		(net 28)
	)
	(via
		(at 62.65 130.5)
		(size 0.45)
		(drill 0.2)
		(layers "F.Cu" "B.Cu")
		(remove_unused_layers yes)
		(keep_end_layers yes)
		(zone_layer_connections "In1.Cu" "In3.Cu" "In4.Cu" "In6.Cu")
		(net 28)
	)
	(via
		(at 85.225 104.76)
		(size 0.45)
		(drill 0.2)
		(layers "F.Cu" "B.Cu")
		(remove_unused_layers yes)
		(keep_end_layers yes)
		(zone_layer_connections "In1.Cu" "In4.Cu" "In6.Cu")
		(net 28)
	)
	(via
		(at 70.95 105.43)
		(size 0.45)
		(drill 0.2)
		(layers "F.Cu" "B.Cu")
		(remove_unused_layers yes)
		(keep_end_layers yes)
		(zone_layer_connections "In1.Cu" "In4.Cu" "In6.Cu")
		(net 28)
	)
	(via
		(at 81.225 94.38)
		(size 0.45)
		(drill 0.2)
		(layers "F.Cu" "B.Cu")
		(remove_unused_layers yes)
		(keep_end_layers yes)
		(zone_layer_connections "In1.Cu" "In4.Cu" "In6.Cu")
		(net 28)
	)
	(via
		(at 74.2 58.3)
		(size 0.45)
		(drill 0.2)
		(layers "F.Cu" "B.Cu")
		(remove_unused_layers yes)
		(keep_end_layers yes)
		(zone_layer_connections "In1.Cu" "In4.Cu" "In6.Cu")
		(net 28)
	)
	(via
		(at 95.829505 66.435)
		(size 0.45)
		(drill 0.2)
		(layers "F.Cu" "B.Cu")
		(remove_unused_layers yes)
		(keep_end_layers yes)
		(zone_layer_connections "In1.Cu" "In2.Cu" "In4.Cu" "In6.Cu")
		(net 28)
	)
	(via
		(at 81.725 93.515)
		(size 0.45)
		(drill 0.2)
		(layers "F.Cu" "B.Cu")
		(remove_unused_layers yes)
		(keep_end_layers yes)
		(zone_layer_connections "In1.Cu" "In4.Cu" "In6.Cu")
		(net 28)
	)
	(via
		(at 95.225 96.11)
		(size 0.45)
		(drill 0.2)
		(layers "F.Cu" "B.Cu")
		(remove_unused_layers yes)
		(keep_end_layers yes)
		(zone_layer_connections "In1.Cu" "In4.Cu" "In6.Cu")
		(net 28)
	)
	(via
		(at 51.575 111.225001)
		(size 0.45)
		(drill 0.1)
		(layers "F.Cu" "B.Cu")
		(remove_unused_layers yes)
		(keep_end_layers yes)
		(zone_layer_connections "In1.Cu" "In4.Cu" "In6.Cu")
		(net 28)
	)
	(via
		(at 80.225 106.49)
		(size 0.45)
		(drill 0.2)
		(layers "F.Cu" "B.Cu")
		(remove_unused_layers yes)
		(keep_end_layers yes)
		(zone_layer_connections "In1.Cu" "In4.Cu" "In6.Cu")
		(net 28)
	)
	(via
		(at 77.725 105.625)
		(size 0.45)
		(drill 0.2)
		(layers "F.Cu" "B.Cu")
		(remove_unused_layers yes)
		(keep_end_layers yes)
		(zone_layer_connections "In1.Cu" "In4.Cu" "In6.Cu")
		(net 28)
	)
	(via
		(at 113.15 99.05)
		(size 0.45)
		(drill 0.2)
		(layers "F.Cu" "B.Cu")
		(remove_unused_layers yes)
		(keep_end_layers yes)
		(zone_layer_connections "In1.Cu" "In4.Cu" "In6.Cu")
		(net 28)
	)
	(via
		(at 57.099999 84.670001)
		(size 0.45)
		(drill 0.1)
		(layers "F.Cu" "B.Cu")
		(remove_unused_layers yes)
		(keep_end_layers yes)
		(zone_layer_connections "In1.Cu" "In4.Cu" "In6.Cu")
		(net 28)
	)
	(via
		(at 75.95 76.499999)
		(size 0.45)
		(drill 0.2)
		(layers "F.Cu" "B.Cu")
		(remove_unused_layers yes)
		(keep_end_layers yes)
		(zone_layer_connections "In1.Cu" "In4.Cu" "In6.Cu")
		(net 28)
	)
	(via
		(at 82.43 131.4)
		(size 0.45)
		(drill 0.2)
		(layers "F.Cu" "B.Cu")
		(remove_unused_layers yes)
		(keep_end_layers yes)
		(zone_layer_connections "In1.Cu" "In3.Cu" "In4.Cu" "In6.Cu")
		(net 28)
	)
	(via
		(at 79.225 106.49)
		(size 0.45)
		(drill 0.2)
		(layers "F.Cu" "B.Cu")
		(remove_unused_layers yes)
		(keep_end_layers yes)
		(zone_layer_connections "In1.Cu" "In4.Cu" "In6.Cu")
		(net 28)
	)
	(via
		(at 99.829999 107.099999)
		(size 0.45)
		(drill 0.2)
		(layers "F.Cu" "B.Cu")
		(remove_unused_layers yes)
		(keep_end_layers yes)
		(zone_layer_connections "In1.Cu" "In4.Cu" "In6.Cu")
		(net 28)
	)
	(via
		(at 75.225 90.92)
		(size 0.45)
		(drill 0.2)
		(layers "F.Cu" "B.Cu")
		(remove_unused_layers yes)
		(keep_end_layers yes)
		(zone_layer_connections "In1.Cu" "In4.Cu" "In6.Cu")
		(net 28)
	)
	(via
		(at 119.35 67.279998)
		(size 0.45)
		(drill 0.2)
		(layers "F.Cu" "B.Cu")
		(remove_unused_layers yes)
		(keep_end_layers yes)
		(zone_layer_connections "In1.Cu" "In4.Cu" "In6.Cu")
		(net 28)
	)
	(via
		(at 88.715 102.185)
		(size 0.45)
		(drill 0.2)
		(layers "F.Cu" "B.Cu")
		(remove_unused_layers yes)
		(keep_end_layers yes)
		(zone_layer_connections "In1.Cu" "In4.Cu" "In6.Cu")
		(net 28)
	)
	(via
		(at 80.725 103.895)
		(size 0.45)
		(drill 0.2)
		(layers "F.Cu" "B.Cu")
		(remove_unused_layers yes)
		(keep_end_layers yes)
		(zone_layer_connections "In1.Cu" "In4.Cu" "In6.Cu")
		(net 28)
	)
	(via
		(at 86.225 92.65)
		(size 0.45)
		(drill 0.2)
		(layers "F.Cu" "B.Cu")
		(remove_unused_layers yes)
		(keep_end_layers yes)
		(zone_layer_connections "In1.Cu" "In4.Cu" "In6.Cu")
		(net 28)
	)
	(via
		(at 88.225 90.92)
		(size 0.45)
		(drill 0.2)
		(layers "F.Cu" "B.Cu")
		(remove_unused_layers yes)
		(keep_end_layers yes)
		(zone_layer_connections "In1.Cu" "In4.Cu" "In6.Cu")
		(net 28)
	)
	(via
		(at 87.725 100.435)
		(size 0.45)
		(drill 0.2)
		(layers "F.Cu" "B.Cu")
		(remove_unused_layers yes)
		(keep_end_layers yes)
		(zone_layer_connections "In1.Cu" "In4.Cu" "In6.Cu")
		(net 28)
	)
	(via
		(at 95.225 90.92)
		(size 0.45)
		(drill 0.2)
		(layers "F.Cu" "B.Cu")
		(remove_unused_layers yes)
		(keep_end_layers yes)
		(zone_layer_connections "In1.Cu" "In4.Cu" "In6.Cu")
		(net 28)
	)
	(via
		(at 74.725 90.055)
		(size 0.45)
		(drill 0.2)
		(layers "F.Cu" "B.Cu")
		(remove_unused_layers yes)
		(keep_end_layers yes)
		(zone_layer_connections "In1.Cu" "In4.Cu" "In6.Cu")
		(net 28)
	)
	(via
		(at 89.725 102.185)
		(size 0.45)
		(drill 0.2)
		(layers "F.Cu" "B.Cu")
		(remove_unused_layers yes)
		(keep_end_layers yes)
		(zone_layer_connections "In1.Cu" "In4.Cu" "In6.Cu")
		(net 28)
	)
	(via
		(at 80.7 124.6)
		(size 0.45)
		(drill 0.2)
		(layers "F.Cu" "B.Cu")
		(remove_unused_layers yes)
		(keep_end_layers yes)
		(zone_layer_connections "In1.Cu" "In4.Cu" "In6.Cu")
		(net 28)
	)
	(via
		(at 89.725 90.055)
		(size 0.45)
		(drill 0.2)
		(layers "F.Cu" "B.Cu")
		(remove_unused_layers yes)
		(keep_end_layers yes)
		(zone_layer_connections "In1.Cu" "In4.Cu" "In6.Cu")
		(net 28)
	)
	(via
		(at 63.950001 73.499999)
		(size 0.45)
		(drill 0.2)
		(layers "F.Cu" "B.Cu")
		(remove_unused_layers yes)
		(keep_end_layers yes)
		(zone_layer_connections "In1.Cu" "In4.Cu" "In6.Cu")
		(net 28)
	)
	(via
		(at 53.161 74.984)
		(size 0.45)
		(drill 0.2)
		(layers "F.Cu" "B.Cu")
		(remove_unused_layers yes)
		(keep_end_layers yes)
		(zone_layer_connections "In1.Cu" "In4.Cu" "In6.Cu")
		(net 28)
	)
	(via
		(at 113.35 127.28)
		(size 0.45)
		(drill 0.2)
		(layers "F.Cu" "B.Cu")
		(remove_unused_layers yes)
		(keep_end_layers yes)
		(zone_layer_connections "In1.Cu" "In3.Cu" "In4.Cu" "In6.Cu")
		(net 28)
	)
	(via
		(at 75.349999 60.35)
		(size 0.45)
		(drill 0.2)
		(layers "F.Cu" "B.Cu")
		(remove_unused_layers yes)
		(keep_end_layers yes)
		(zone_layer_connections "In1.Cu" "In4.Cu" "In6.Cu")
		(net 28)
	)
	(via
		(at 72.479999 140.15)
		(size 0.45)
		(drill 0.2)
		(layers "F.Cu" "B.Cu")
		(remove_unused_layers yes)
		(keep_end_layers yes)
		(zone_layer_connections "In1.Cu" "In3.Cu" "In4.Cu" "In6.Cu")
		(net 28)
	)
	(via
		(at 71.874999 75.514995)
		(size 0.45)
		(drill 0.1)
		(layers "F.Cu" "B.Cu")
		(remove_unused_layers yes)
		(keep_end_layers yes)
		(zone_layer_connections "In1.Cu" "In4.Cu" "In6.Cu")
		(net 28)
	)
	(via
		(at 71.874999 76.514996)
		(size 0.45)
		(drill 0.1)
		(layers "F.Cu" "B.Cu")
		(remove_unused_layers yes)
		(keep_end_layers yes)
		(zone_layer_connections "In1.Cu" "In4.Cu" "In6.Cu")
		(net 28)
	)
	(via
		(at 119.35 88.280001)
		(size 0.45)
		(drill 0.2)
		(layers "F.Cu" "B.Cu")
		(remove_unused_layers yes)
		(keep_end_layers yes)
		(zone_layer_connections "In1.Cu" "In4.Cu" "In6.Cu")
		(net 28)
	)
	(via
		(at 119.35 73.279999)
		(size 0.45)
		(drill 0.2)
		(layers "F.Cu" "B.Cu")
		(remove_unused_layers yes)
		(keep_end_layers yes)
		(zone_layer_connections "In1.Cu" "In4.Cu" "In6.Cu")
		(net 28)
	)
	(via
		(at 103.23 61.385)
		(size 0.45)
		(drill 0.2)
		(layers "F.Cu" "B.Cu")
		(remove_unused_layers yes)
		(keep_end_layers yes)
		(zone_layer_connections "In1.Cu" "In2.Cu" "In4.Cu" "In6.Cu")
		(net 28)
	)
	(via
		(at 98.75 58.355002)
		(size 0.45)
		(drill 0.2)
		(layers "F.Cu" "B.Cu")
		(remove_unused_layers yes)
		(keep_end_layers yes)
		(zone_layer_connections "In1.Cu" "In2.Cu" "In4.Cu" "In6.Cu")
		(net 28)
	)
	(via
		(at 59.24 99.22)
		(size 0.45)
		(drill 0.1)
		(layers "F.Cu" "B.Cu")
		(remove_unused_layers yes)
		(keep_end_layers yes)
		(zone_layer_connections "In1.Cu" "In4.Cu" "In6.Cu")
		(net 28)
	)
	(via
		(at 72.45 99)
		(size 0.45)
		(drill 0.2)
		(layers "F.Cu" "B.Cu")
		(remove_unused_layers yes)
		(keep_end_layers yes)
		(zone_layer_connections "In1.Cu" "In4.Cu" "In6.Cu")
		(net 28)
	)
	(via
		(at 54.099998 100.07)
		(size 0.45)
		(drill 0.1)
		(layers "F.Cu" "B.Cu")
		(remove_unused_layers yes)
		(keep_end_layers yes)
		(zone_layer_connections "In1.Cu" "In4.Cu" "In6.Cu")
		(net 28)
	)
	(via
		(at 80.225 108.22)
		(size 0.45)
		(drill 0.2)
		(layers "F.Cu" "B.Cu")
		(remove_unused_layers yes)
		(keep_end_layers yes)
		(zone_layer_connections "In1.Cu" "In4.Cu" "In6.Cu")
		(net 28)
	)
	(via
		(at 96.950001 52.085)
		(size 0.45)
		(drill 0.2)
		(layers "F.Cu" "B.Cu")
		(remove_unused_layers yes)
		(keep_end_layers yes)
		(zone_layer_connections "In1.Cu" "In4.Cu" "In6.Cu")
		(net 28)
	)
	(via
		(at 86.725 105.625)
		(size 0.45)
		(drill 0.2)
		(layers "F.Cu" "B.Cu")
		(remove_unused_layers yes)
		(keep_end_layers yes)
		(zone_layer_connections "In1.Cu" "In4.Cu" "In6.Cu")
		(net 28)
	)
	(via
		(at 68.89 106.88)
		(size 0.45)
		(drill 0.2)
		(layers "F.Cu" "B.Cu")
		(remove_unused_layers yes)
		(keep_end_layers yes)
		(zone_layer_connections "In1.Cu" "In4.Cu" "In6.Cu")
		(net 28)
	)
	(via
		(at 59.26 85.17)
		(size 0.45)
		(drill 0.1)
		(layers "F.Cu" "B.Cu")
		(remove_unused_layers yes)
		(keep_end_layers yes)
		(zone_layer_connections "In1.Cu" "In4.Cu" "In6.Cu")
		(net 28)
	)
	(via
		(at 88.725 98.705)
		(size 0.45)
		(drill 0.2)
		(layers "F.Cu" "B.Cu")
		(remove_unused_layers yes)
		(keep_end_layers yes)
		(zone_layer_connections "In1.Cu" "In4.Cu" "In6.Cu")
		(net 28)
	)
	(via
		(at 119.35 58.279998)
		(size 0.45)
		(drill 0.2)
		(layers "F.Cu" "B.Cu")
		(remove_unused_layers yes)
		(keep_end_layers yes)
		(zone_layer_connections "In1.Cu" "In4.Cu" "In6.Cu")
		(net 28)
	)
	(via
		(at 77.225 101.3)
		(size 0.45)
		(drill 0.2)
		(layers "F.Cu" "B.Cu")
		(remove_unused_layers yes)
		(keep_end_layers yes)
		(zone_layer_connections "In1.Cu" "In4.Cu" "In6.Cu")
		(net 28)
	)
	(via
		(at 84.725 103.895)
		(size 0.45)
		(drill 0.2)
		(layers "F.Cu" "B.Cu")
		(remove_unused_layers yes)
		(keep_end_layers yes)
		(zone_layer_connections "In1.Cu" "In4.Cu" "In6.Cu")
		(net 28)
	)
	(via
		(at 55.7 74.984)
		(size 0.45)
		(drill 0.2)
		(layers "F.Cu" "B.Cu")
		(remove_unused_layers yes)
		(keep_end_layers yes)
		(zone_layer_connections "In1.Cu" "In4.Cu" "In6.Cu")
		(net 28)
	)
	(via
		(at 119.35 136.28)
		(size 0.45)
		(drill 0.2)
		(layers "F.Cu" "B.Cu")
		(remove_unused_layers yes)
		(keep_end_layers yes)
		(zone_layer_connections "In1.Cu" "In3.Cu" "In4.Cu" "In6.Cu")
		(net 28)
	)
	(via
		(at 82.43 132.4)
		(size 0.45)
		(drill 0.2)
		(layers "F.Cu" "B.Cu")
		(remove_unused_layers yes)
		(keep_end_layers yes)
		(zone_layer_connections "In1.Cu" "In3.Cu" "In4.Cu" "In6.Cu")
		(net 28)
	)
	(via
		(at 50.65 130.5)
		(size 0.45)
		(drill 0.2)
		(layers "F.Cu" "B.Cu")
		(remove_unused_layers yes)
		(keep_end_layers yes)
		(zone_layer_connections "In1.Cu" "In3.Cu" "In4.Cu" "In6.Cu")
		(net 28)
	)
	(via
		(at 73.15 111.9)
		(size 0.45)
		(drill 0.2)
		(layers "F.Cu" "B.Cu")
		(remove_unused_layers yes)
		(keep_end_layers yes)
		(zone_layer_connections "In1.Cu" "In4.Cu" "In6.Cu")
		(net 28)
	)
	(via
		(at 75.479998 137.15)
		(size 0.45)
		(drill 0.2)
		(layers "F.Cu" "B.Cu")
		(remove_unused_layers yes)
		(keep_end_layers yes)
		(zone_layer_connections "In1.Cu" "In3.Cu" "In4.Cu" "In6.Cu")
		(net 28)
	)
	(via
		(at 86.225 90.92)
		(size 0.45)
		(drill 0.2)
		(layers "F.Cu" "B.Cu")
		(remove_unused_layers yes)
		(keep_end_layers yes)
		(zone_layer_connections "In1.Cu" "In4.Cu" "In6.Cu")
		(net 28)
	)
	(via
		(at 50.65 103.5)
		(size 0.45)
		(drill 0.2)
		(layers "F.Cu" "B.Cu")
		(remove_unused_layers yes)
		(keep_end_layers yes)
		(zone_layer_connections "In1.Cu" "In4.Cu" "In6.Cu")
		(net 28)
	)
	(via
		(at 89.725 98.705)
		(size 0.45)
		(drill 0.2)
		(layers "F.Cu" "B.Cu")
		(remove_unused_layers yes)
		(keep_end_layers yes)
		(zone_layer_connections "In1.Cu" "In4.Cu" "In6.Cu")
		(net 28)
	)
	(via
		(at 91.725 102.165)
		(size 0.45)
		(drill 0.2)
		(layers "F.Cu" "B.Cu")
		(remove_unused_layers yes)
		(keep_end_layers yes)
		(zone_layer_connections "In1.Cu" "In4.Cu" "In6.Cu")
		(net 28)
	)
	(via
		(at 98.63 90.89)
		(size 0.45)
		(drill 0.2)
		(layers "F.Cu" "B.Cu")
		(remove_unused_layers yes)
		(keep_end_layers yes)
		(zone_layer_connections "In1.Cu" "In4.Cu" "In5.Cu" "In6.Cu")
		(net 28)
	)
	(via
		(at 98.87 105.2)
		(size 0.45)
		(drill 0.2)
		(layers "F.Cu" "B.Cu")
		(remove_unused_layers yes)
		(keep_end_layers yes)
		(zone_layer_connections "In1.Cu" "In4.Cu" "In6.Cu")
		(net 28)
	)
	(via
		(at 50.65 85.5)
		(size 0.45)
		(drill 0.2)
		(layers "F.Cu" "B.Cu")
		(remove_unused_layers yes)
		(keep_end_layers yes)
		(zone_layer_connections "In1.Cu" "In4.Cu" "In6.Cu")
		(net 28)
	)
	(via
		(at 65.650001 118.500002)
		(size 0.45)
		(drill 0.2)
		(layers "F.Cu" "B.Cu")
		(remove_unused_layers yes)
		(keep_end_layers yes)
		(zone_layer_connections "In1.Cu" "In4.Cu" "In6.Cu")
		(net 28)
	)
	(via
		(at 55.6 124.05)
		(size 0.45)
		(drill 0.2)
		(layers "F.Cu" "B.Cu")
		(remove_unused_layers yes)
		(keep_end_layers yes)
		(zone_layer_connections "In1.Cu" "In3.Cu" "In4.Cu" "In6.Cu")
		(net 28)
	)
	(via
		(at 81.6 149.3)
		(size 0.45)
		(drill 0.2)
		(layers "F.Cu" "B.Cu")
		(remove_unused_layers yes)
		(keep_end_layers yes)
		(zone_layer_connections "In1.Cu" "In3.Cu" "In4.Cu" "In6.Cu")
		(net 28)
	)
	(via
		(at 105.5 133.3)
		(size 0.45)
		(drill 0.2)
		(layers "F.Cu" "B.Cu")
		(remove_unused_layers yes)
		(keep_end_layers yes)
		(zone_layer_connections "In1.Cu" "In3.Cu" "In4.Cu" "In6.Cu")
		(net 28)
	)
	(via
		(at 77.9 85.675)
		(size 0.45)
		(drill 0.2)
		(layers "F.Cu" "B.Cu")
		(remove_unused_layers yes)
		(keep_end_layers yes)
		(zone_layer_connections "In1.Cu" "In4.Cu" "In6.Cu")
		(net 28)
	)
	(via
		(at 101.35 124.280001)
		(size 0.45)
		(drill 0.2)
		(layers "F.Cu" "B.Cu")
		(remove_unused_layers yes)
		(keep_end_layers yes)
		(zone_layer_connections "In1.Cu" "In4.Cu" "In6.Cu")
		(net 28)
	)
	(via
		(at 54.575 110.225001)
		(size 0.45)
		(drill 0.1)
		(layers "F.Cu" "B.Cu")
		(remove_unused_layers yes)
		(keep_end_layers yes)
		(zone_layer_connections "In1.Cu" "In4.Cu" "In6.Cu")
		(net 28)
	)
	(via
		(at 93.48 144.86)
		(size 0.45)
		(drill 0.2)
		(layers "F.Cu" "B.Cu")
		(remove_unused_layers yes)
		(keep_end_layers yes)
		(zone_layer_connections "In1.Cu" "In3.Cu" "In4.Cu" "In6.Cu")
		(net 28)
	)
	(via
		(at 59.65 130.5)
		(size 0.45)
		(drill 0.2)
		(layers "F.Cu" "B.Cu")
		(remove_unused_layers yes)
		(keep_end_layers yes)
		(zone_layer_connections "In1.Cu" "In3.Cu" "In4.Cu" "In6.Cu")
		(net 28)
	)
	(via
		(at 100.61 84.94)
		(size 0.45)
		(drill 0.2)
		(layers "F.Cu" "B.Cu")
		(remove_unused_layers yes)
		(keep_end_layers yes)
		(zone_layer_connections "In1.Cu" "In4.Cu" "In6.Cu")
		(net 28)
	)
	(via
		(at 88.725 95.255)
		(size 0.45)
		(drill 0.2)
		(layers "F.Cu" "B.Cu")
		(remove_unused_layers yes)
		(keep_end_layers yes)
		(zone_layer_connections "In1.Cu" "In4.Cu" "In6.Cu")
		(net 28)
	)
	(via
		(at 71.15 110.9)
		(size 0.45)
		(drill 0.2)
		(layers "F.Cu" "B.Cu")
		(remove_unused_layers yes)
		(keep_end_layers yes)
		(zone_layer_connections "In1.Cu" "In4.Cu" "In6.Cu")
		(net 28)
	)
	(via
		(at 88.225 109.95)
		(size 0.45)
		(drill 0.2)
		(layers "F.Cu" "B.Cu")
		(remove_unused_layers yes)
		(keep_end_layers yes)
		(zone_layer_connections "In1.Cu" "In4.Cu" "In6.Cu")
		(net 28)
	)
	(via
		(at 54.95 50.65)
		(size 0.45)
		(drill 0.2)
		(layers "F.Cu" "B.Cu")
		(remove_unused_layers yes)
		(keep_end_layers yes)
		(zone_layer_connections "In1.Cu" "In4.Cu" "In6.Cu")
		(net 28)
	)
	(via
		(at 94.479999 143.15)
		(size 0.45)
		(drill 0.2)
		(layers "F.Cu" "B.Cu")
		(remove_unused_layers yes)
		(keep_end_layers yes)
		(zone_layer_connections "In1.Cu" "In3.Cu" "In4.Cu" "In6.Cu")
		(net 28)
	)
	(via
		(at 110.02 108.43)
		(size 0.45)
		(drill 0.2)
		(layers "F.Cu" "B.Cu")
		(remove_unused_layers yes)
		(keep_end_layers yes)
		(zone_layer_connections "In1.Cu" "In3.Cu" "In4.Cu" "In6.Cu")
		(net 28)
	)
	(via
		(at 71.15 111.9)
		(size 0.45)
		(drill 0.2)
		(layers "F.Cu" "B.Cu")
		(remove_unused_layers yes)
		(keep_end_layers yes)
		(zone_layer_connections "In1.Cu" "In4.Cu" "In6.Cu")
		(net 28)
	)
	(via
		(at 72.15 111.9)
		(size 0.45)
		(drill 0.2)
		(layers "F.Cu" "B.Cu")
		(remove_unused_layers yes)
		(keep_end_layers yes)
		(zone_layer_connections "In1.Cu" "In4.Cu" "In6.Cu")
		(net 28)
	)
	(via
		(at 59.97 84.4)
		(size 0.45)
		(drill 0.1)
		(layers "F.Cu" "B.Cu")
		(remove_unused_layers yes)
		(keep_end_layers yes)
		(zone_layer_connections "In1.Cu" "In4.Cu" "In6.Cu")
		(net 28)
	)
	(via
		(at 97.88 107.1)
		(size 0.45)
		(drill 0.2)
		(layers "F.Cu" "B.Cu")
		(remove_unused_layers yes)
		(keep_end_layers yes)
		(zone_layer_connections "In1.Cu" "In4.Cu" "In6.Cu")
		(net 28)
	)
	(via
		(at 74.725 105.635)
		(size 0.45)
		(drill 0.2)
		(layers "F.Cu" "B.Cu")
		(remove_unused_layers yes)
		(keep_end_layers yes)
		(zone_layer_connections "In1.Cu" "In4.Cu" "In6.Cu")
		(net 28)
	)
	(via
		(at 93.95 50.65)
		(size 0.45)
		(drill 0.2)
		(layers "F.Cu" "B.Cu")
		(remove_unused_layers yes)
		(keep_end_layers yes)
		(zone_layer_connections "In1.Cu" "In4.Cu" "In6.Cu")
		(net 28)
	)
	(via
		(at 76.725 91.785)
		(size 0.45)
		(drill 0.2)
		(layers "F.Cu" "B.Cu")
		(remove_unused_layers yes)
		(keep_end_layers yes)
		(zone_layer_connections "In1.Cu" "In4.Cu" "In6.Cu")
		(net 28)
	)
	(via
		(at 75.725 91.785)
		(size 0.45)
		(drill 0.2)
		(layers "F.Cu" "B.Cu")
		(remove_unused_layers yes)
		(keep_end_layers yes)
		(zone_layer_connections "In1.Cu" "In4.Cu" "In6.Cu")
		(net 28)
	)
	(via
		(at 68.15 52.9)
		(size 0.45)
		(drill 0.2)
		(layers "F.Cu" "B.Cu")
		(remove_unused_layers yes)
		(keep_end_layers yes)
		(zone_layer_connections "In1.Cu" "In4.Cu" "In6.Cu")
		(net 28)
	)
	(via
		(at 59.25 107.49)
		(size 0.45)
		(drill 0.1)
		(layers "F.Cu" "B.Cu")
		(remove_unused_layers yes)
		(keep_end_layers yes)
		(zone_layer_connections "In1.Cu" "In4.Cu" "In6.Cu")
		(net 28)
	)
	(via
		(at 89.725 96.975)
		(size 0.45)
		(drill 0.2)
		(layers "F.Cu" "B.Cu")
		(remove_unused_layers yes)
		(keep_end_layers yes)
		(zone_layer_connections "In1.Cu" "In4.Cu" "In6.Cu")
		(net 28)
	)
	(via
		(at 67.25 82.049998)
		(size 0.45)
		(drill 0.2)
		(layers "F.Cu" "B.Cu")
		(remove_unused_layers yes)
		(keep_end_layers yes)
		(zone_layer_connections "In1.Cu" "In4.Cu" "In6.Cu")
		(net 28)
	)
	(via
		(at 69.07 60.631)
		(size 0.45)
		(drill 0.2)
		(layers "F.Cu" "B.Cu")
		(remove_unused_layers yes)
		(keep_end_layers yes)
		(zone_layer_connections "In1.Cu" "In4.Cu" "In6.Cu")
		(net 28)
	)
	(via
		(at 101.79 64.005)
		(size 0.45)
		(drill 0.2)
		(layers "F.Cu" "B.Cu")
		(remove_unused_layers yes)
		(keep_end_layers yes)
		(zone_layer_connections "In1.Cu" "In2.Cu" "In4.Cu" "In6.Cu")
		(net 28)
	)
	(via
		(at 77.725 107.355)
		(size 0.45)
		(drill 0.2)
		(layers "F.Cu" "B.Cu")
		(remove_unused_layers yes)
		(keep_end_layers yes)
		(zone_layer_connections "In1.Cu" "In4.Cu" "In6.Cu")
		(net 28)
	)
	(via
		(at 99.175 101.975)
		(size 0.45)
		(drill 0.2)
		(layers "F.Cu" "B.Cu")
		(remove_unused_layers yes)
		(keep_end_layers yes)
		(zone_layer_connections "In1.Cu" "In4.Cu" "In6.Cu")
		(net 28)
	)
	(via
		(at 97.479998 140.15)
		(size 0.45)
		(drill 0.2)
		(layers "F.Cu" "B.Cu")
		(remove_unused_layers yes)
		(keep_end_layers yes)
		(zone_layer_connections "In1.Cu" "In3.Cu" "In4.Cu" "In6.Cu")
		(net 28)
	)
	(via
		(at 103.23 64.015)
		(size 0.45)
		(drill 0.2)
		(layers "F.Cu" "B.Cu")
		(remove_unused_layers yes)
		(keep_end_layers yes)
		(zone_layer_connections "In1.Cu" "In2.Cu" "In4.Cu" "In6.Cu")
		(net 28)
	)
	(via
		(at 59.65 118.5)
		(size 0.45)
		(drill 0.2)
		(layers "F.Cu" "B.Cu")
		(remove_unused_layers yes)
		(keep_end_layers yes)
		(zone_layer_connections "In1.Cu" "In3.Cu" "In4.Cu" "In6.Cu")
		(net 28)
	)
	(via
		(at 93.6 149.3)
		(size 0.45)
		(drill 0.2)
		(layers "F.Cu" "B.Cu")
		(remove_unused_layers yes)
		(keep_end_layers yes)
		(zone_layer_connections "In1.Cu" "In3.Cu" "In4.Cu" "In6.Cu")
		(net 28)
	)
	(via
		(at 82.225 90.92)
		(size 0.45)
		(drill 0.2)
		(layers "F.Cu" "B.Cu")
		(remove_unused_layers yes)
		(keep_end_layers yes)
		(zone_layer_connections "In1.Cu" "In4.Cu" "In6.Cu")
		(net 28)
	)
	(via
		(at 86.725 96.975)
		(size 0.45)
		(drill 0.2)
		(layers "F.Cu" "B.Cu")
		(remove_unused_layers yes)
		(keep_end_layers yes)
		(zone_layer_connections "In1.Cu" "In4.Cu" "In6.Cu")
		(net 28)
	)
	(via
		(at 84.725 109.085)
		(size 0.45)
		(drill 0.2)
		(layers "F.Cu" "B.Cu")
		(remove_unused_layers yes)
		(keep_end_layers yes)
		(zone_layer_connections "In1.Cu" "In4.Cu" "In6.Cu")
		(net 28)
	)
	(via
		(at 79.225 92.65)
		(size 0.45)
		(drill 0.2)
		(layers "F.Cu" "B.Cu")
		(remove_unused_layers yes)
		(keep_end_layers yes)
		(zone_layer_connections "In1.Cu" "In4.Cu" "In6.Cu")
		(net 28)
	)
	(via
		(at 54.575 111.225001)
		(size 0.45)
		(drill 0.1)
		(layers "F.Cu" "B.Cu")
		(remove_unused_layers yes)
		(keep_end_layers yes)
		(zone_layer_connections "In1.Cu" "In4.Cu" "In6.Cu")
		(net 28)
	)
	(via
		(at 112.55 88.6)
		(size 0.45)
		(drill 0.2)
		(layers "F.Cu" "B.Cu")
		(remove_unused_layers yes)
		(keep_end_layers yes)
		(zone_layer_connections "In1.Cu" "In4.Cu" "In6.Cu")
		(net 28)
	)
	(via
		(at 79.5375 57.0395)
		(size 0.45)
		(drill 0.2)
		(layers "F.Cu" "B.Cu")
		(remove_unused_layers yes)
		(keep_end_layers yes)
		(zone_layer_connections "In1.Cu" "In4.Cu" "In6.Cu")
		(net 28)
	)
	(via
		(at 93.09 57.300001)
		(size 0.45)
		(drill 0.2)
		(layers "F.Cu" "B.Cu")
		(remove_unused_layers yes)
		(keep_end_layers yes)
		(zone_layer_connections "In1.Cu" "In4.Cu" "In6.Cu")
		(net 28)
	)
	(via
		(at 99.75 54.835)
		(size 0.45)
		(drill 0.2)
		(layers "F.Cu" "B.Cu")
		(remove_unused_layers yes)
		(keep_end_layers yes)
		(zone_layer_connections "In1.Cu" "In2.Cu" "In4.Cu" "In6.Cu")
		(net 28)
	)
	(via
		(at 107.288 93.15)
		(size 0.45)
		(drill 0.2)
		(layers "F.Cu" "B.Cu")
		(remove_unused_layers yes)
		(keep_end_layers yes)
		(zone_layer_connections "In1.Cu" "In4.Cu" "In6.Cu")
		(net 28)
	)
	(via
		(at 98.5 101.325)
		(size 0.45)
		(drill 0.2)
		(layers "F.Cu" "B.Cu")
		(remove_unused_layers yes)
		(keep_end_layers yes)
		(zone_layer_connections "In1.Cu" "In4.Cu" "In6.Cu")
		(net 28)
	)
	(via
		(at 66.950002 73.499999)
		(size 0.45)
		(drill 0.2)
		(layers "F.Cu" "B.Cu")
		(remove_unused_layers yes)
		(keep_end_layers yes)
		(zone_layer_connections "In1.Cu" "In4.Cu" "In6.Cu")
		(net 28)
	)
	(via
		(at 80.225 101.3)
		(size 0.45)
		(drill 0.2)
		(layers "F.Cu" "B.Cu")
		(remove_unused_layers yes)
		(keep_end_layers yes)
		(zone_layer_connections "In1.Cu" "In4.Cu" "In6.Cu")
		(net 28)
	)
	(via
		(at 104.43 132.39)
		(size 0.45)
		(drill 0.2)
		(layers "F.Cu" "B.Cu")
		(remove_unused_layers yes)
		(keep_end_layers yes)
		(zone_layer_connections "In1.Cu" "In3.Cu" "In4.Cu" "In6.Cu")
		(net 28)
	)
	(via
		(at 96.6 149.3)
		(size 0.45)
		(drill 0.2)
		(layers "F.Cu" "B.Cu")
		(remove_unused_layers yes)
		(keep_end_layers yes)
		(zone_layer_connections "In1.Cu" "In3.Cu" "In4.Cu" "In6.Cu")
		(net 28)
	)
	(via
		(at 97.327501 64.155)
		(size 0.45)
		(drill 0.2)
		(layers "F.Cu" "B.Cu")
		(remove_unused_layers yes)
		(keep_end_layers yes)
		(zone_layer_connections "In1.Cu" "In2.Cu" "In4.Cu" "In6.Cu")
		(net 28)
	)
	(via
		(at 63.87 85.85)
		(size 0.45)
		(drill 0.1)
		(layers "F.Cu" "B.Cu")
		(remove_unused_layers yes)
		(keep_end_layers yes)
		(zone_layer_connections "In1.Cu" "In4.Cu" "In6.Cu")
		(net 28)
	)
	(via
		(at 119.35 70.279999)
		(size 0.45)
		(drill 0.2)
		(layers "F.Cu" "B.Cu")
		(remove_unused_layers yes)
		(keep_end_layers yes)
		(zone_layer_connections "In1.Cu" "In4.Cu" "In6.Cu")
		(net 28)
	)
	(via
		(at 100.82 103.3)
		(size 0.45)
		(drill 0.2)
		(layers "F.Cu" "B.Cu")
		(remove_unused_layers yes)
		(keep_end_layers yes)
		(zone_layer_connections "In1.Cu" "In4.Cu" "In6.Cu")
		(net 28)
	)
	(via
		(at 94.225 92.65)
		(size 0.45)
		(drill 0.2)
		(layers "F.Cu" "B.Cu")
		(remove_unused_layers yes)
		(keep_end_layers yes)
		(zone_layer_connections "In1.Cu" "In4.Cu" "In6.Cu")
		(net 28)
	)
	(via
		(at 60.949999 50.65)
		(size 0.45)
		(drill 0.2)
		(layers "F.Cu" "B.Cu")
		(remove_unused_layers yes)
		(keep_end_layers yes)
		(zone_layer_connections "In1.Cu" "In4.Cu" "In6.Cu")
		(net 28)
	)
	(via
		(at 71.874999 78.514996)
		(size 0.45)
		(drill 0.1)
		(layers "F.Cu" "B.Cu")
		(remove_unused_layers yes)
		(keep_end_layers yes)
		(zone_layer_connections "In1.Cu" "In4.Cu" "In6.Cu")
		(net 28)
	)
	(via
		(at 73.75 87.23)
		(size 0.45)
		(drill 0.1)
		(layers "F.Cu" "B.Cu")
		(remove_unused_layers yes)
		(keep_end_layers yes)
		(zone_layer_connections "In1.Cu" "In4.Cu" "In6.Cu")
		(net 28)
	)
	(via
		(at 60.19 88.449997)
		(size 0.45)
		(drill 0.1)
		(layers "F.Cu" "B.Cu")
		(remove_unused_layers yes)
		(keep_end_layers yes)
		(zone_layer_connections "In1.Cu" "In4.Cu" "In6.Cu")
		(net 28)
	)
	(via
		(at 83.225 92.65)
		(size 0.45)
		(drill 0.2)
		(layers "F.Cu" "B.Cu")
		(remove_unused_layers yes)
		(keep_end_layers yes)
		(zone_layer_connections "In1.Cu" "In4.Cu" "In6.Cu")
		(net 28)
	)
	(via
		(at 77.9 82.975)
		(size 0.45)
		(drill 0.2)
		(layers "F.Cu" "B.Cu")
		(remove_unused_layers yes)
		(keep_end_layers yes)
		(zone_layer_connections "In1.Cu" "In4.Cu" "In6.Cu")
		(net 28)
	)
	(via
		(at 65.52 131.4)
		(size 0.45)
		(drill 0.2)
		(layers "F.Cu" "B.Cu")
		(remove_unused_layers yes)
		(keep_end_layers yes)
		(zone_layer_connections "In1.Cu" "In3.Cu" "In4.Cu" "In6.Cu")
		(net 28)
	)
	(via
		(at 79.725 109.085)
		(size 0.45)
		(drill 0.2)
		(layers "F.Cu" "B.Cu")
		(remove_unused_layers yes)
		(keep_end_layers yes)
		(zone_layer_connections "In1.Cu" "In4.Cu" "In6.Cu")
		(net 28)
	)
	(via
		(at 71.64 56.521)
		(size 0.45)
		(drill 0.2)
		(layers "F.Cu" "B.Cu")
		(remove_unused_layers yes)
		(keep_end_layers yes)
		(zone_layer_connections "In1.Cu" "In4.Cu" "In6.Cu")
		(net 28)
	)
	(via
		(at 55.6 117)
		(size 0.45)
		(drill 0.2)
		(layers "F.Cu" "B.Cu")
		(remove_unused_layers yes)
		(keep_end_layers yes)
		(zone_layer_connections "In1.Cu" "In4.Cu" "In6.Cu")
		(net 28)
	)
	(via
		(at 70.15 115.85)
		(size 0.45)
		(drill 0.2)
		(layers "F.Cu" "B.Cu")
		(remove_unused_layers yes)
		(keep_end_layers yes)
		(zone_layer_connections "In1.Cu" "In4.Cu" "In6.Cu")
		(net 28)
	)
	(via
		(at 72.35 66.35)
		(size 0.45)
		(drill 0.2)
		(layers "F.Cu" "B.Cu")
		(remove_unused_layers yes)
		(keep_end_layers yes)
		(zone_layer_connections "In1.Cu" "In4.Cu" "In6.Cu")
		(net 28)
	)
	(via
		(at 76.225 94.38)
		(size 0.45)
		(drill 0.2)
		(layers "F.Cu" "B.Cu")
		(remove_unused_layers yes)
		(keep_end_layers yes)
		(zone_layer_connections "In1.Cu" "In4.Cu" "In6.Cu")
		(net 28)
	)
	(via
		(at 54.574999 95.825001)
		(size 0.45)
		(drill 0.1)
		(layers "F.Cu" "B.Cu")
		(remove_unused_layers yes)
		(keep_end_layers yes)
		(zone_layer_connections "In1.Cu" "In4.Cu" "In6.Cu")
		(net 28)
	)
	(via
		(at 59.65 115.500001)
		(size 0.45)
		(drill 0.2)
		(layers "F.Cu" "B.Cu")
		(remove_unused_layers yes)
		(keep_end_layers yes)
		(zone_layer_connections "In1.Cu" "In4.Cu" "In6.Cu")
		(net 28)
	)
	(via
		(at 61.5 61.5)
		(size 0.45)
		(drill 0.2)
		(layers "F.Cu" "B.Cu")
		(remove_unused_layers yes)
		(keep_end_layers yes)
		(zone_layer_connections "In1.Cu" "In4.Cu" "In6.Cu")
		(net 28)
	)
	(via
		(at 84.225 104.76)
		(size 0.45)
		(drill 0.2)
		(layers "F.Cu" "B.Cu")
		(remove_unused_layers yes)
		(keep_end_layers yes)
		(zone_layer_connections "In1.Cu" "In4.Cu" "In6.Cu")
		(net 28)
	)
	(via
		(at 77.9 87.025)
		(size 0.45)
		(drill 0.2)
		(layers "F.Cu" "B.Cu")
		(remove_unused_layers yes)
		(keep_end_layers yes)
		(zone_layer_connections "In1.Cu" "In4.Cu" "In6.Cu")
		(net 28)
	)
	(via
		(at 74.61 82.76)
		(size 0.45)
		(drill 0.1)
		(layers "F.Cu" "B.Cu")
		(remove_unused_layers yes)
		(keep_end_layers yes)
		(zone_layer_connections "In1.Cu" "In4.Cu" "In6.Cu")
		(net 28)
	)
	(via
		(at 104.25 54.835)
		(size 0.45)
		(drill 0.2)
		(layers "F.Cu" "B.Cu")
		(remove_unused_layers yes)
		(keep_end_layers yes)
		(zone_layer_connections "In1.Cu" "In2.Cu" "In4.Cu" "In6.Cu")
		(net 28)
	)
	(via
		(at 66.6 149.3)
		(size 0.45)
		(drill 0.2)
		(layers "F.Cu" "B.Cu")
		(remove_unused_layers yes)
		(keep_end_layers yes)
		(zone_layer_connections "In1.Cu" "In3.Cu" "In4.Cu" "In6.Cu")
		(net 28)
	)
	(via
		(at 91.225 108.22)
		(size 0.45)
		(drill 0.2)
		(layers "F.Cu" "B.Cu")
		(remove_unused_layers yes)
		(keep_end_layers yes)
		(zone_layer_connections "In1.Cu" "In4.Cu" "In6.Cu")
		(net 28)
	)
	(via
		(at 76.725 98.705)
		(size 0.45)
		(drill 0.2)
		(layers "F.Cu" "B.Cu")
		(remove_unused_layers yes)
		(keep_end_layers yes)
		(zone_layer_connections "In1.Cu" "In4.Cu" "In6.Cu")
		(net 28)
	)
	(via
		(at 75.2 83.35)
		(size 0.45)
		(drill 0.1)
		(layers "F.Cu" "B.Cu")
		(remove_unused_layers yes)
		(keep_end_layers yes)
		(zone_layer_connections "In1.Cu" "In4.Cu" "In6.Cu")
		(net 28)
	)
	(via
		(at 111.95 50.65)
		(size 0.45)
		(drill 0.2)
		(layers "F.Cu" "B.Cu")
		(remove_unused_layers yes)
		(keep_end_layers yes)
		(zone_layer_connections "In1.Cu" "In4.Cu" "In6.Cu")
		(net 28)
	)
	(via
		(at 95.48 144.86)
		(size 0.45)
		(drill 0.2)
		(layers "F.Cu" "B.Cu")
		(remove_unused_layers yes)
		(keep_end_layers yes)
		(zone_layer_connections "In1.Cu" "In3.Cu" "In4.Cu" "In6.Cu")
		(net 28)
	)
	(via
		(at 50.65 100.5)
		(size 0.45)
		(drill 0.2)
		(layers "F.Cu" "B.Cu")
		(remove_unused_layers yes)
		(keep_end_layers yes)
		(zone_layer_connections "In1.Cu" "In4.Cu" "In6.Cu")
		(net 28)
	)
	(via
		(at 74.33 78.039994)
		(size 0.45)
		(drill 0.1)
		(layers "F.Cu" "B.Cu")
		(remove_unused_layers yes)
		(keep_end_layers yes)
		(zone_layer_connections "In1.Cu" "In4.Cu" "In6.Cu")
		(net 28)
	)
	(via
		(at 85.225 90.92)
		(size 0.45)
		(drill 0.2)
		(layers "F.Cu" "B.Cu")
		(remove_unused_layers yes)
		(keep_end_layers yes)
		(zone_layer_connections "In1.Cu" "In4.Cu" "In6.Cu")
		(net 28)
	)
	(via
		(at 51.949999 50.65)
		(size 0.45)
		(drill 0.2)
		(layers "F.Cu" "B.Cu")
		(remove_unused_layers yes)
		(keep_end_layers yes)
		(zone_layer_connections "In1.Cu" "In4.Cu" "In6.Cu")
		(net 28)
	)
	(via
		(at 50.65 91.5)
		(size 0.45)
		(drill 0.2)
		(layers "F.Cu" "B.Cu")
		(remove_unused_layers yes)
		(keep_end_layers yes)
		(zone_layer_connections "In1.Cu" "In4.Cu" "In6.Cu")
		(net 28)
	)
	(via
		(at 81.225 90.92)
		(size 0.45)
		(drill 0.2)
		(layers "F.Cu" "B.Cu")
		(remove_unused_layers yes)
		(keep_end_layers yes)
		(zone_layer_connections "In1.Cu" "In4.Cu" "In6.Cu")
		(net 28)
	)
	(via
		(at 69.15 114.85)
		(size 0.45)
		(drill 0.2)
		(layers "F.Cu" "B.Cu")
		(remove_unused_layers yes)
		(keep_end_layers yes)
		(zone_layer_connections "In1.Cu" "In4.Cu" "In6.Cu")
		(net 28)
	)
	(via
		(at 63.89 108.86)
		(size 0.45)
		(drill 0.1)
		(layers "F.Cu" "B.Cu")
		(remove_unused_layers yes)
		(keep_end_layers yes)
		(zone_layer_connections "In1.Cu" "In4.Cu" "In6.Cu")
		(net 28)
	)
	(via
		(at 68.15 114.85)
		(size 0.45)
		(drill 0.2)
		(layers "F.Cu" "B.Cu")
		(remove_unused_layers yes)
		(keep_end_layers yes)
		(zone_layer_connections "In1.Cu" "In4.Cu" "In6.Cu")
		(net 28)
	)
	(via
		(at 75.349999 66.35)
		(size 0.45)
		(drill 0.2)
		(layers "F.Cu" "B.Cu")
		(remove_unused_layers yes)
		(keep_end_layers yes)
		(zone_layer_connections "In1.Cu" "In4.Cu" "In6.Cu")
		(net 28)
	)
	(via
		(at 53.65 58.5)
		(size 0.45)
		(drill 0.2)
		(layers "F.Cu" "B.Cu")
		(remove_unused_layers yes)
		(keep_end_layers yes)
		(zone_layer_connections "In1.Cu" "In4.Cu" "In6.Cu")
		(net 28)
	)
	(via
		(at 119.35 121.28)
		(size 0.45)
		(drill 0.2)
		(layers "F.Cu" "B.Cu")
		(remove_unused_layers yes)
		(keep_end_layers yes)
		(zone_layer_connections "In1.Cu" "In3.Cu" "In4.Cu" "In6.Cu")
		(net 28)
	)
	(via
		(at 51.575001 88.125)
		(size 0.45)
		(drill 0.1)
		(layers "F.Cu" "B.Cu")
		(remove_unused_layers yes)
		(keep_end_layers yes)
		(zone_layer_connections "In1.Cu" "In4.Cu" "In6.Cu")
		(net 28)
	)
	(via
		(at 85.725 102.165)
		(size 0.45)
		(drill 0.2)
		(layers "F.Cu" "B.Cu")
		(remove_unused_layers yes)
		(keep_end_layers yes)
		(zone_layer_connections "In1.Cu" "In4.Cu" "In6.Cu")
		(net 28)
	)
	(via
		(at 67.9 100.47)
		(size 0.45)
		(drill 0.2)
		(layers "F.Cu" "B.Cu")
		(remove_unused_layers yes)
		(keep_end_layers yes)
		(zone_layer_connections "In1.Cu" "In4.Cu" "In6.Cu")
		(net 28)
	)
	(via
		(at 102.56 84.97)
		(size 0.45)
		(drill 0.2)
		(layers "F.Cu" "B.Cu")
		(remove_unused_layers yes)
		(keep_end_layers yes)
		(zone_layer_connections "In1.Cu" "In4.Cu" "In6.Cu")
		(net 28)
	)
	(via
		(at 73.04 87.2)
		(size 0.45)
		(drill 0.1)
		(layers "F.Cu" "B.Cu")
		(remove_unused_layers yes)
		(keep_end_layers yes)
		(zone_layer_connections "In1.Cu" "In4.Cu" "In6.Cu")
		(net 28)
	)
	(via
		(at 56.599 79.1)
		(size 0.45)
		(drill 0.2)
		(layers "F.Cu" "B.Cu")
		(remove_unused_layers yes)
		(keep_end_layers yes)
		(zone_layer_connections "In1.Cu" "In4.Cu" "In6.Cu")
		(net 28)
	)
	(via
		(at 74.61 83.35)
		(size 0.45)
		(drill 0.1)
		(layers "F.Cu" "B.Cu")
		(remove_unused_layers yes)
		(keep_end_layers yes)
		(zone_layer_connections "In1.Cu" "In4.Cu" "In6.Cu")
		(net 28)
	)
	(via
		(at 76.725 103.895)
		(size 0.45)
		(drill 0.2)
		(layers "F.Cu" "B.Cu")
		(remove_unused_layers yes)
		(keep_end_layers yes)
		(zone_layer_connections "In1.Cu" "In4.Cu" "In6.Cu")
		(net 28)
	)
	(via
		(at 104.82 85.93)
		(size 0.45)
		(drill 0.2)
		(layers "F.Cu" "B.Cu")
		(remove_unused_layers yes)
		(keep_end_layers yes)
		(zone_layer_connections "In1.Cu" "In4.Cu" "In6.Cu")
		(net 28)
	)
	(via
		(at 83.725 103.895)
		(size 0.45)
		(drill 0.2)
		(layers "F.Cu" "B.Cu")
		(remove_unused_layers yes)
		(keep_end_layers yes)
		(zone_layer_connections "In1.Cu" "In4.Cu" "In6.Cu")
		(net 28)
	)
	(via
		(at 74.725 102.165)
		(size 0.45)
		(drill 0.2)
		(layers "F.Cu" "B.Cu")
		(remove_unused_layers yes)
		(keep_end_layers yes)
		(zone_layer_connections "In1.Cu" "In4.Cu" "In6.Cu")
		(net 28)
	)
	(via
		(at 90.6 149.3)
		(size 0.45)
		(drill 0.2)
		(layers "F.Cu" "B.Cu")
		(remove_unused_layers yes)
		(keep_end_layers yes)
		(zone_layer_connections "In1.Cu" "In3.Cu" "In4.Cu" "In6.Cu")
		(net 28)
	)
	(via
		(at 83.225 90.92)
		(size 0.45)
		(drill 0.2)
		(layers "F.Cu" "B.Cu")
		(remove_unused_layers yes)
		(keep_end_layers yes)
		(zone_layer_connections "In1.Cu" "In4.Cu" "In6.Cu")
		(net 28)
	)
	(via
		(at 109.15 103.099997)
		(size 0.45)
		(drill 0.2)
		(layers "F.Cu" "B.Cu")
		(remove_unused_layers yes)
		(keep_end_layers yes)
		(zone_layer_connections "In1.Cu" "In4.Cu" "In6.Cu")
		(net 28)
	)
	(via
		(at 70.874999 78.514996)
		(size 0.45)
		(drill 0.1)
		(layers "F.Cu" "B.Cu")
		(remove_unused_layers yes)
		(keep_end_layers yes)
		(zone_layer_connections "In1.Cu" "In4.Cu" "In6.Cu")
		(net 28)
	)
	(via
		(at 79.260999 57.771999)
		(size 0.45)
		(drill 0.2)
		(layers "F.Cu" "B.Cu")
		(remove_unused_layers yes)
		(keep_end_layers yes)
		(zone_layer_connections "In1.Cu" "In4.Cu" "In6.Cu")
		(net 28)
	)
	(via
		(at 116.35 121.28)
		(size 0.45)
		(drill 0.2)
		(layers "F.Cu" "B.Cu")
		(remove_unused_layers yes)
		(keep_end_layers yes)
		(zone_layer_connections "In1.Cu" "In3.Cu" "In4.Cu" "In6.Cu")
		(net 28)
	)
	(via
		(at 96.75 54.835)
		(size 0.45)
		(drill 0.2)
		(layers "F.Cu" "B.Cu")
		(remove_unused_layers yes)
		(keep_end_layers yes)
		(zone_layer_connections "In1.Cu" "In2.Cu" "In4.Cu" "In6.Cu")
		(net 28)
	)
	(via
		(at 53.575001 88.125)
		(size 0.45)
		(drill 0.1)
		(layers "F.Cu" "B.Cu")
		(remove_unused_layers yes)
		(keep_end_layers yes)
		(zone_layer_connections "In1.Cu" "In4.Cu" "In6.Cu")
		(net 28)
	)
	(via
		(at 55.7 82.284)
		(size 0.45)
		(drill 0.2)
		(layers "F.Cu" "B.Cu")
		(remove_unused_layers yes)
		(keep_end_layers yes)
		(zone_layer_connections "In1.Cu" "In4.Cu" "In6.Cu")
		(net 28)
	)
	(via
		(at 73.15 110.9)
		(size 0.45)
		(drill 0.2)
		(layers "F.Cu" "B.Cu")
		(remove_unused_layers yes)
		(keep_end_layers yes)
		(zone_layer_connections "In1.Cu" "In4.Cu" "In6.Cu")
		(net 28)
	)
	(via
		(at 57.099998 100.070002)
		(size 0.45)
		(drill 0.1)
		(layers "F.Cu" "B.Cu")
		(remove_unused_layers yes)
		(keep_end_layers yes)
		(zone_layer_connections "In1.Cu" "In4.Cu" "In6.Cu")
		(net 28)
	)
	(via
		(at 55.650001 87.799999)
		(size 0.45)
		(drill 0.1)
		(layers "F.Cu" "B.Cu")
		(remove_unused_layers yes)
		(keep_end_layers yes)
		(zone_layer_connections "In1.Cu" "In4.Cu" "In6.Cu")
		(net 28)
	)
	(via
		(at 90.725 102.165)
		(size 0.45)
		(drill 0.2)
		(layers "F.Cu" "B.Cu")
		(remove_unused_layers yes)
		(keep_end_layers yes)
		(zone_layer_connections "In1.Cu" "In4.Cu" "In6.Cu")
		(net 28)
	)
	(via
		(at 88.75 62.35)
		(size 0.45)
		(drill 0.2)
		(layers "F.Cu" "B.Cu")
		(remove_unused_layers yes)
		(keep_end_layers yes)
		(zone_layer_connections "In1.Cu" "In4.Cu" "In6.Cu")
		(net 28)
	)
	(via
		(at 99.85 99.975)
		(size 0.45)
		(drill 0.2)
		(layers "F.Cu" "B.Cu")
		(remove_unused_layers yes)
		(keep_end_layers yes)
		(zone_layer_connections "In1.Cu" "In4.Cu" "In6.Cu")
		(net 28)
	)
	(via
		(at 88.725 93.515)
		(size 0.45)
		(drill 0.2)
		(layers "F.Cu" "B.Cu")
		(remove_unused_layers yes)
		(keep_end_layers yes)
		(zone_layer_connections "In1.Cu" "In4.Cu" "In6.Cu")
		(net 28)
	)
	(via
		(at 74.329999 77.039994)
		(size 0.45)
		(drill 0.1)
		(layers "F.Cu" "B.Cu")
		(remove_unused_layers yes)
		(keep_end_layers yes)
		(zone_layer_connections "In1.Cu" "In4.Cu" "In6.Cu")
		(net 28)
	)
	(via
		(at 81.77 84.15)
		(size 0.45)
		(drill 0.2)
		(layers "F.Cu" "B.Cu")
		(remove_unused_layers yes)
		(keep_end_layers yes)
		(zone_layer_connections "In1.Cu" "In4.Cu" "In6.Cu")
		(net 28)
	)
	(via
		(at 68.65 127.500001)
		(size 0.45)
		(drill 0.2)
		(layers "F.Cu" "B.Cu")
		(remove_unused_layers yes)
		(keep_end_layers yes)
		(zone_layer_connections "In1.Cu" "In4.Cu" "In6.Cu")
		(net 28)
	)
	(via
		(at 85.725 100.435)
		(size 0.45)
		(drill 0.2)
		(layers "F.Cu" "B.Cu")
		(remove_unused_layers yes)
		(keep_end_layers yes)
		(zone_layer_connections "In1.Cu" "In4.Cu" "In6.Cu")
		(net 28)
	)
	(via
		(at 98.35 115.28)
		(size 0.45)
		(drill 0.2)
		(layers "F.Cu" "B.Cu")
		(remove_unused_layers yes)
		(keep_end_layers yes)
		(zone_layer_connections "In1.Cu" "In4.Cu" "In6.Cu")
		(net 28)
	)
	(via
		(at 70.15 111.9)
		(size 0.45)
		(drill 0.2)
		(layers "F.Cu" "B.Cu")
		(remove_unused_layers yes)
		(keep_end_layers yes)
		(zone_layer_connections "In1.Cu" "In4.Cu" "In6.Cu")
		(net 28)
	)
	(via
		(at 76.725 102.165)
		(size 0.45)
		(drill 0.2)
		(layers "F.Cu" "B.Cu")
		(remove_unused_layers yes)
		(keep_end_layers yes)
		(zone_layer_connections "In1.Cu" "In4.Cu" "In6.Cu")
		(net 28)
	)
	(via
		(at 94.225 90.92)
		(size 0.45)
		(drill 0.2)
		(layers "F.Cu" "B.Cu")
		(remove_unused_layers yes)
		(keep_end_layers yes)
		(zone_layer_connections "In1.Cu" "In4.Cu" "In6.Cu")
		(net 28)
	)
	(via
		(at 55.6 119.35)
		(size 0.45)
		(drill 0.2)
		(layers "F.Cu" "B.Cu")
		(remove_unused_layers yes)
		(keep_end_layers yes)
		(zone_layer_connections "In1.Cu" "In3.Cu" "In4.Cu" "In6.Cu")
		(net 28)
	)
	(via
		(at 75.479998 140.15)
		(size 0.45)
		(drill 0.2)
		(layers "F.Cu" "B.Cu")
		(remove_unused_layers yes)
		(keep_end_layers yes)
		(zone_layer_connections "In1.Cu" "In3.Cu" "In4.Cu" "In6.Cu")
		(net 28)
	)
	(via
		(at 90.25 59.05)
		(size 0.45)
		(drill 0.2)
		(layers "F.Cu" "B.Cu")
		(remove_unused_layers yes)
		(keep_end_layers yes)
		(zone_layer_connections "In1.Cu" "In4.Cu" "In6.Cu")
		(net 28)
	)
	(via
		(at 77.725 103.895)
		(size 0.45)
		(drill 0.2)
		(layers "F.Cu" "B.Cu")
		(remove_unused_layers yes)
		(keep_end_layers yes)
		(zone_layer_connections "In1.Cu" "In4.Cu" "In6.Cu")
		(net 28)
	)
	(via
		(at 86.225 103.03)
		(size 0.45)
		(drill 0.2)
		(layers "F.Cu" "B.Cu")
		(remove_unused_layers yes)
		(keep_end_layers yes)
		(zone_layer_connections "In1.Cu" "In4.Cu" "In6.Cu")
		(net 28)
	)
	(via
		(at 67.9 104.18)
		(size 0.45)
		(drill 0.2)
		(layers "F.Cu" "B.Cu")
		(remove_unused_layers yes)
		(keep_end_layers yes)
		(zone_layer_connections "In1.Cu" "In4.Cu" "In6.Cu")
		(net 28)
	)
	(via
		(at 67.25 87.050001)
		(size 0.45)
		(drill 0.2)
		(layers "F.Cu" "B.Cu")
		(remove_unused_layers yes)
		(keep_end_layers yes)
		(zone_layer_connections "In1.Cu" "In4.Cu" "In6.Cu")
		(net 28)
	)
	(via
		(at 71.1 99)
		(size 0.45)
		(drill 0.2)
		(layers "F.Cu" "B.Cu")
		(remove_unused_layers yes)
		(keep_end_layers yes)
		(zone_layer_connections "In1.Cu" "In4.Cu" "In6.Cu")
		(net 28)
	)
	(via
		(at 50.65 133.5)
		(size 0.45)
		(drill 0.2)
		(layers "F.Cu" "B.Cu")
		(remove_unused_layers yes)
		(keep_end_layers yes)
		(zone_layer_connections "In1.Cu" "In3.Cu" "In4.Cu" "In6.Cu")
		(net 28)
	)
	(via
		(at 102.6 149.3)
		(size 0.45)
		(drill 0.2)
		(layers "F.Cu" "B.Cu")
		(remove_unused_layers yes)
		(keep_end_layers yes)
		(zone_layer_connections "In1.Cu" "In3.Cu" "In4.Cu" "In6.Cu")
		(net 28)
	)
	(via
		(at 119.35 85.28)
		(size 0.45)
		(drill 0.2)
		(layers "F.Cu" "B.Cu")
		(remove_unused_layers yes)
		(keep_end_layers yes)
		(zone_layer_connections "In1.Cu" "In4.Cu" "In6.Cu")
		(net 28)
	)
	(via
		(at 90.949999 73.499999)
		(size 0.45)
		(drill 0.2)
		(layers "F.Cu" "B.Cu")
		(remove_unused_layers yes)
		(keep_end_layers yes)
		(zone_layer_connections "In1.Cu" "In4.Cu" "In6.Cu")
		(net 28)
	)
	(via
		(at 101.35 121.28)
		(size 0.45)
		(drill 0.2)
		(layers "F.Cu" "B.Cu")
		(remove_unused_layers yes)
		(keep_end_layers yes)
		(zone_layer_connections "In1.Cu" "In4.Cu" "In6.Cu")
		(net 28)
	)
	(via
		(at 68.65 118.500002)
		(size 0.45)
		(drill 0.2)
		(layers "F.Cu" "B.Cu")
		(remove_unused_layers yes)
		(keep_end_layers yes)
		(zone_layer_connections "In1.Cu" "In4.Cu" "In6.Cu")
		(net 28)
	)
	(via
		(at 76.725 90.055)
		(size 0.45)
		(drill 0.2)
		(layers "F.Cu" "B.Cu")
		(remove_unused_layers yes)
		(keep_end_layers yes)
		(zone_layer_connections "In1.Cu" "In4.Cu" "In6.Cu")
		(net 28)
	)
	(via
		(at 88.1 112.93)
		(size 0.45)
		(drill 0.2)
		(layers "F.Cu" "B.Cu")
		(remove_unused_layers yes)
		(keep_end_layers yes)
		(zone_layer_connections "In1.Cu" "In4.Cu" "In6.Cu")
		(net 28)
	)
	(via
		(at 111.49 89.34)
		(size 0.45)
		(drill 0.2)
		(layers "F.Cu" "B.Cu")
		(remove_unused_layers yes)
		(keep_end_layers yes)
		(zone_layer_connections "In1.Cu" "In4.Cu" "In6.Cu")
		(net 28)
	)
	(via
		(at 74.2 55.3)
		(size 0.45)
		(drill 0.2)
		(layers "F.Cu" "B.Cu")
		(remove_unused_layers yes)
		(keep_end_layers yes)
		(zone_layer_connections "In1.Cu" "In4.Cu" "In6.Cu")
		(net 28)
	)
	(via
		(at 114.15 94.099999)
		(size 0.45)
		(drill 0.2)
		(layers "F.Cu" "B.Cu")
		(remove_unused_layers yes)
		(keep_end_layers yes)
		(zone_layer_connections "In1.Cu" "In4.Cu" "In6.Cu")
		(net 28)
	)
	(via
		(at 102.57 88.03)
		(size 0.45)
		(drill 0.2)
		(layers "F.Cu" "B.Cu")
		(remove_unused_layers yes)
		(keep_end_layers yes)
		(zone_layer_connections "In1.Cu" "In4.Cu" "In5.Cu" "In6.Cu")
		(net 28)
	)
	(via
		(at 88.75 65.35)
		(size 0.45)
		(drill 0.2)
		(layers "F.Cu" "B.Cu")
		(remove_unused_layers yes)
		(keep_end_layers yes)
		(zone_layer_connections "In1.Cu" "In4.Cu" "In6.Cu")
		(net 28)
	)
	(via
		(at 78.725 90.055)
		(size 0.45)
		(drill 0.2)
		(layers "F.Cu" "B.Cu")
		(remove_unused_layers yes)
		(keep_end_layers yes)
		(zone_layer_connections "In1.Cu" "In4.Cu" "In6.Cu")
		(net 28)
	)
	(via
		(at 75.725 103.895)
		(size 0.45)
		(drill 0.2)
		(layers "F.Cu" "B.Cu")
		(remove_unused_layers yes)
		(keep_end_layers yes)
		(zone_layer_connections "In1.Cu" "In4.Cu" "In6.Cu")
		(net 28)
	)
	(via
		(at 104.75 58.355002)
		(size 0.45)
		(drill 0.2)
		(layers "F.Cu" "B.Cu")
		(remove_unused_layers yes)
		(keep_end_layers yes)
		(zone_layer_connections "In1.Cu" "In2.Cu" "In4.Cu" "In6.Cu")
		(net 28)
	)
	(via
		(at 81.2 52.552)
		(size 0.45)
		(drill 0.2)
		(layers "F.Cu" "B.Cu")
		(remove_unused_layers yes)
		(keep_end_layers yes)
		(zone_layer_connections "In1.Cu" "In4.Cu" "In6.Cu")
		(net 28)
	)
	(via
		(at 78.950001 79.499999)
		(size 0.45)
		(drill 0.2)
		(layers "F.Cu" "B.Cu")
		(remove_unused_layers yes)
		(keep_end_layers yes)
		(zone_layer_connections "In1.Cu" "In4.Cu" "In6.Cu")
		(net 28)
	)
	(via
		(at 53.574999 94.825001)
		(size 0.45)
		(drill 0.1)
		(layers "F.Cu" "B.Cu")
		(remove_unused_layers yes)
		(keep_end_layers yes)
		(zone_layer_connections "In1.Cu" "In4.Cu" "In6.Cu")
		(net 28)
	)
	(via
		(at 99.462338 72.073211)
		(size 0.45)
		(drill 0.2)
		(layers "F.Cu" "B.Cu")
		(remove_unused_layers yes)
		(keep_end_layers yes)
		(zone_layer_connections "In1.Cu" "In4.Cu" "In6.Cu")
		(net 28)
	)
	(via
		(at 60.190001 111.549998)
		(size 0.45)
		(drill 0.1)
		(layers "F.Cu" "B.Cu")
		(remove_unused_layers yes)
		(keep_end_layers yes)
		(zone_layer_connections "In1.Cu" "In4.Cu" "In6.Cu")
		(net 28)
	)
	(via
		(at 53.65 130.5)
		(size 0.45)
		(drill 0.2)
		(layers "F.Cu" "B.Cu")
		(remove_unused_layers yes)
		(keep_end_layers yes)
		(zone_layer_connections "In1.Cu" "In3.Cu" "In4.Cu" "In6.Cu")
		(net 28)
	)
	(via
		(at 54.099997 84.669999)
		(size 0.45)
		(drill 0.1)
		(layers "F.Cu" "B.Cu")
		(remove_unused_layers yes)
		(keep_end_layers yes)
		(zone_layer_connections "In1.Cu" "In4.Cu" "In6.Cu")
		(net 28)
	)
	(via
		(at 68.65 124.500002)
		(size 0.45)
		(drill 0.2)
		(layers "F.Cu" "B.Cu")
		(remove_unused_layers yes)
		(keep_end_layers yes)
		(zone_layer_connections "In1.Cu" "In4.Cu" "In6.Cu")
		(net 28)
	)
	(via
		(at 65.52 132.39)
		(size 0.45)
		(drill 0.2)
		(layers "F.Cu" "B.Cu")
		(remove_unused_layers yes)
		(keep_end_layers yes)
		(zone_layer_connections "In1.Cu" "In3.Cu" "In4.Cu" "In6.Cu")
		(net 28)
	)
	(via
		(at 110.49 89.34)
		(size 0.45)
		(drill 0.2)
		(layers "F.Cu" "B.Cu")
		(remove_unused_layers yes)
		(keep_end_layers yes)
		(zone_layer_connections "In1.Cu" "In4.Cu" "In6.Cu")
		(net 28)
	)
	(via
		(at 88.725 96.975)
		(size 0.45)
		(drill 0.2)
		(layers "F.Cu" "B.Cu")
		(remove_unused_layers yes)
		(keep_end_layers yes)
		(zone_layer_connections "In1.Cu" "In4.Cu" "In6.Cu")
		(net 28)
	)
	(via
		(at 119.35 115.280001)
		(size 0.45)
		(drill 0.2)
		(layers "F.Cu" "B.Cu")
		(remove_unused_layers yes)
		(keep_end_layers yes)
		(zone_layer_connections "In1.Cu" "In3.Cu" "In4.Cu" "In6.Cu")
		(net 28)
	)
	(via
		(at 107.8 58.885)
		(size 0.45)
		(drill 0.2)
		(layers "F.Cu" "B.Cu")
		(remove_unused_layers yes)
		(keep_end_layers yes)
		(zone_layer_connections "In1.Cu" "In4.Cu" "In6.Cu")
		(net 28)
	)
	(via
		(at 50.65 70.499999)
		(size 0.45)
		(drill 0.2)
		(layers "F.Cu" "B.Cu")
		(remove_unused_layers yes)
		(keep_end_layers yes)
		(zone_layer_connections "In1.Cu" "In4.Cu" "In6.Cu")
		(net 28)
	)
	(via
		(at 50.65 76.500001)
		(size 0.45)
		(drill 0.2)
		(layers "F.Cu" "B.Cu")
		(remove_unused_layers yes)
		(keep_end_layers yes)
		(zone_layer_connections "In1.Cu" "In4.Cu" "In6.Cu")
		(net 28)
	)
	(via
		(at 82.725 105.625)
		(size 0.45)
		(drill 0.2)
		(layers "F.Cu" "B.Cu")
		(remove_unused_layers yes)
		(keep_end_layers yes)
		(zone_layer_connections "In1.Cu" "In4.Cu" "In6.Cu")
		(net 28)
	)
	(via
		(at 89.225 92.6)
		(size 0.45)
		(drill 0.2)
		(layers "F.Cu" "B.Cu")
		(remove_unused_layers yes)
		(keep_end_layers yes)
		(zone_layer_connections "In1.Cu" "In4.Cu" "In6.Cu")
		(net 28)
	)
	(via
		(at 107.8 66.449999)
		(size 0.45)
		(drill 0.2)
		(layers "F.Cu" "B.Cu")
		(remove_unused_layers yes)
		(keep_end_layers yes)
		(zone_layer_connections "In1.Cu" "In4.Cu" "In6.Cu")
		(net 28)
	)
	(via
		(at 110.35 124.280001)
		(size 0.45)
		(drill 0.2)
		(layers "F.Cu" "B.Cu")
		(remove_unused_layers yes)
		(keep_end_layers yes)
		(zone_layer_connections "In1.Cu" "In3.Cu" "In4.Cu" "In6.Cu")
		(net 28)
	)
	(via
		(at 99.196645 61.961653)
		(size 0.45)
		(drill 0.2)
		(layers "F.Cu" "B.Cu")
		(remove_unused_layers yes)
		(keep_end_layers yes)
		(zone_layer_connections "In1.Cu" "In2.Cu" "In4.Cu" "In6.Cu")
		(net 28)
	)
	(via
		(at 54.575 102.525002)
		(size 0.45)
		(drill 0.1)
		(layers "F.Cu" "B.Cu")
		(remove_unused_layers yes)
		(keep_end_layers yes)
		(zone_layer_connections "In1.Cu" "In4.Cu" "In6.Cu")
		(net 28)
	)
	(via
		(at 69.05 88)
		(size 0.45)
		(drill 0.2)
		(layers "F.Cu" "B.Cu")
		(remove_unused_layers yes)
		(keep_end_layers yes)
		(zone_layer_connections "In1.Cu" "In4.Cu" "In6.Cu")
		(net 28)
	)
	(via
		(at 50.65 121.500001)
		(size 0.45)
		(drill 0.2)
		(layers "F.Cu" "B.Cu")
		(remove_unused_layers yes)
		(keep_end_layers yes)
		(zone_layer_connections "In1.Cu" "In3.Cu" "In4.Cu" "In6.Cu")
		(net 28)
	)
	(via
		(at 86.725 102.165)
		(size 0.45)
		(drill 0.2)
		(layers "F.Cu" "B.Cu")
		(remove_unused_layers yes)
		(keep_end_layers yes)
		(zone_layer_connections "In1.Cu" "In4.Cu" "In6.Cu")
		(net 28)
	)
	(via
		(at 56.97 81.015)
		(size 0.45)
		(drill 0.2)
		(layers "F.Cu" "B.Cu")
		(remove_unused_layers yes)
		(keep_end_layers yes)
		(zone_layer_connections "In1.Cu" "In4.Cu" "In6.Cu")
		(net 28)
	)
	(via
		(at 64.600999 56.521)
		(size 0.45)
		(drill 0.2)
		(layers "F.Cu" "B.Cu")
		(remove_unused_layers yes)
		(keep_end_layers yes)
		(zone_layer_connections "In1.Cu" "In4.Cu" "In6.Cu")
		(net 28)
	)
	(via
		(at 51.575 103.525002)
		(size 0.45)
		(drill 0.1)
		(layers "F.Cu" "B.Cu")
		(remove_unused_layers yes)
		(keep_end_layers yes)
		(zone_layer_connections "In1.Cu" "In4.Cu" "In6.Cu")
		(net 28)
	)
	(via
		(at 51.575001 87.125)
		(size 0.45)
		(drill 0.1)
		(layers "F.Cu" "B.Cu")
		(remove_unused_layers yes)
		(keep_end_layers yes)
		(zone_layer_connections "In1.Cu" "In4.Cu" "In6.Cu")
		(net 28)
	)
	(via
		(at 74.2 52.3)
		(size 0.45)
		(drill 0.2)
		(layers "F.Cu" "B.Cu")
		(remove_unused_layers yes)
		(keep_end_layers yes)
		(zone_layer_connections "In1.Cu" "In4.Cu" "In6.Cu")
		(net 28)
	)
	(via
		(at 89.725 109.085)
		(size 0.45)
		(drill 0.2)
		(layers "F.Cu" "B.Cu")
		(remove_unused_layers yes)
		(keep_end_layers yes)
		(zone_layer_connections "In1.Cu" "In4.Cu" "In6.Cu")
		(net 28)
	)
	(via
		(at 111.6 149.3)
		(size 0.45)
		(drill 0.2)
		(layers "F.Cu" "B.Cu")
		(remove_unused_layers yes)
		(keep_end_layers yes)
		(zone_layer_connections "In1.Cu" "In3.Cu" "In4.Cu" "In6.Cu")
		(net 28)
	)
	(via
		(at 119.35 112.28)
		(size 0.45)
		(drill 0.2)
		(layers "F.Cu" "B.Cu")
		(remove_unused_layers yes)
		(keep_end_layers yes)
		(zone_layer_connections "In1.Cu" "In3.Cu" "In4.Cu" "In6.Cu")
		(net 28)
	)
	(via
		(at 87.225 108.22)
		(size 0.45)
		(drill 0.2)
		(layers "F.Cu" "B.Cu")
		(remove_unused_layers yes)
		(keep_end_layers yes)
		(zone_layer_connections "In1.Cu" "In4.Cu" "In6.Cu")
		(net 28)
	)
	(via
		(at 59.94 100.58)
		(size 0.45)
		(drill 0.1)
		(layers "F.Cu" "B.Cu")
		(remove_unused_layers yes)
		(keep_end_layers yes)
		(zone_layer_connections "In1.Cu" "In4.Cu" "In6.Cu")
		(net 28)
	)
	(via
		(at 104.76 61.405)
		(size 0.45)
		(drill 0.2)
		(layers "F.Cu" "B.Cu")
		(remove_unused_layers yes)
		(keep_end_layers yes)
		(zone_layer_connections "In1.Cu" "In2.Cu" "In4.Cu" "In6.Cu")
		(net 28)
	)
	(via
		(at 91.225 92.6)
		(size 0.45)
		(drill 0.2)
		(layers "F.Cu" "B.Cu")
		(remove_unused_layers yes)
		(keep_end_layers yes)
		(zone_layer_connections "In1.Cu" "In4.Cu" "In6.Cu")
		(net 28)
	)
	(via
		(at 75.225 92.65)
		(size 0.45)
		(drill 0.2)
		(layers "F.Cu" "B.Cu")
		(remove_unused_layers yes)
		(keep_end_layers yes)
		(zone_layer_connections "In1.Cu" "In4.Cu" "In6.Cu")
		(net 28)
	)
	(via
		(at 82.725 107.355)
		(size 0.45)
		(drill 0.2)
		(layers "F.Cu" "B.Cu")
		(remove_unused_layers yes)
		(keep_end_layers yes)
		(zone_layer_connections "In1.Cu" "In4.Cu" "In6.Cu")
		(net 28)
	)
	(via
		(at 89.225 108.22)
		(size 0.45)
		(drill 0.2)
		(layers "F.Cu" "B.Cu")
		(remove_unused_layers yes)
		(keep_end_layers yes)
		(zone_layer_connections "In1.Cu" "In4.Cu" "In6.Cu")
		(net 28)
	)
	(segment
		(start 55.598 121.702)
		(end 55.6 121.7)
		(width 0.15)
		(layer "B.Cu")
		(net 28)
	)
	(segment
		(start 90.55 98.7)
		(end 90.6 98.65)
		(width 0.2)
		(layer "B.Cu")
		(net 28)
	)
	(segment
		(start 93.28 113.610001)
		(end 93.81 113.610001)
		(width 0.3)
		(layer "B.Cu")
		(net 28)
	)
	(segment
		(start 100.62 88.254)
		(end 100.62 87.37)
		(width 0.2)
		(layer "B.Cu")
		(net 28)
	)
	(segment
		(start 75.55 105.8)
		(end 75.55 106.48)
		(width 0.125)
		(layer "B.Cu")
		(net 28)
	)
	(segment
		(start 89.245 103.05)
		(end 89.225 103.03)
		(width 0.15)
		(layer "B.Cu")
		(net 28)
	)
	(segment
		(start 100.62 91.124)
		(end 101.394 91.124)
		(width 0.2)
		(layer "B.Cu")
		(net 28)
	)
	(segment
		(start 95.225 93.52)
		(end 94.73 93.52)
		(width 0.5)
		(layer "B.Cu")
		(net 28)
	)
	(segment
		(start 73.1 99.65)
		(end 72.45 99)
		(width 0.15)
		(layer "B.Cu")
		(net 28)
	)
	(segment
		(start 55.598 117.552)
		(end 55.598 117.002)
		(width 0.15)
		(layer "B.Cu")
		(net 28)
	)
	(segment
		(start 97.48 96.98)
		(end 98.5 98)
		(width 0.15)
		(layer "B.Cu")
		(net 28)
	)
	(segment
		(start 96.747999 56.27066)
		(end 96.747999 55.49866)
		(width 0.3)
		(layer "B.Cu")
		(net 28)
	)
	(segment
		(start 105.475 90.253)
		(end 105.475 90.965)
		(width 0.2)
		(layer "B.Cu")
		(net 28)
	)
	(segment
		(start 90.6 98.65)
		(end 90.6 98.385)
		(width 0.2)
		(layer "B.Cu")
		(net 28)
	)
	(segment
		(start 105.475 90.965)
		(end 105.19 91.25)
		(width 0.2)
		(layer "B.Cu")
		(net 28)
	)
	(segment
		(start 68.246 93.453146)
		(end 67.496855 93.453146)
		(width 0.3)
		(layer "B.Cu")
		(net 28)
	)
	(segment
		(start 92.73 93.52)
		(end 92.725 93.515)
		(width 0.5)
		(layer "B.Cu")
		(net 28)
	)
	(segment
		(start 102.75 55.5)
		(end 102.75 54.835)
		(width 0.3)
		(layer "B.Cu")
		(net 28)
	)
	(segment
		(start 93.225 93.52)
		(end 93.72 93.52)
		(width 0.5)
		(layer "B.Cu")
		(net 28)
	)
	(segment
		(start 96.95 96.98)
		(end 97.48 96.98)
		(width 0.15)
		(layer "B.Cu")
		(net 28)
	)
	(segment
		(start 75.725 105.625)
		(end 75.55 105.8)
		(width 0.125)
		(layer "B.Cu")
		(net 28)
	)
	(segment
		(start 78.55 97.88)
		(end 79.55 97.88)
		(width 0.3)
		(layer "B.Cu")
		(net 28)
	)
	(segment
		(start 72.45 99)
		(end 72.8 98.65)
		(width 0.15)
		(layer "B.Cu")
		(net 28)
	)
	(segment
		(start 67.496855 93.453146)
		(end 67.4 93.550001)
		(width 0.3)
		(layer "B.Cu")
		(net 28)
	)
	(segment
		(start 90.725 108.28)
		(end 90.785 108.22)
		(width 0.5)
		(layer "B.Cu")
		(net 28)
	)
	(segment
		(start 94.73 93.52)
		(end 94.725 93.515)
		(width 0.5)
		(layer "B.Cu")
		(net 28)
	)
	(segment
		(start 101.394 91.124)
		(end 101.42 91.15)
		(width 0.2)
		(layer "B.Cu")
		(net 28)
	)
	(segment
		(start 90.785 108.22)
		(end 91.225 108.22)
		(width 0.5)
		(layer "B.Cu")
		(net 28)
	)
	(segment
		(start 98.5 98)
		(end 98.5 98.625)
		(width 0.15)
		(layer "B.Cu")
		(net 28)
	)
	(segment
		(start 55.598 122.252)
		(end 55.598 121.702)
		(width 0.15)
		(layer "B.Cu")
		(net 28)
	)
	(segment
		(start 90.6 98.385)
		(end 91.165 97.82)
		(width 0.2)
		(layer "B.Cu")
		(net 28)
	)
	(segment
		(start 93.72 93.52)
		(end 93.725 93.515)
		(width 0.15)
		(layer "B.Cu")
		(net 28)
	)
	(segment
		(start 107.285 95.92)
		(end 107.285 95.39)
		(width 0.3)
		(layer "B.Cu")
		(net 28)
	)
	(segment
		(start 72.8 98.65)
		(end 73.52 98.65)
		(width 0.15)
		(layer "B.Cu")
		(net 28)
	)
	(segment
		(start 80.445 101.52)
		(end 80.225 101.3)
		(width 0.125)
		(layer "B.Cu")
		(net 28)
	)
	(segment
		(start 99.75 56.272)
		(end 99.75 55.5)
		(width 0.3)
		(layer "B.Cu")
		(net 28)
	)
	(segment
		(start 78.55 97.88)
		(end 78.265 97.88)
		(width 0.3)
		(layer "B.Cu")
		(net 28)
	)
	(segment
		(start 55.598 117.002)
		(end 55.6 117)
		(width 0.15)
		(layer "B.Cu")
		(net 28)
	)
	(segment
		(start 99.75 55.5)
		(end 99.75 54.835)
		(width 0.3)
		(layer "B.Cu")
		(net 28)
	)
	(segment
		(start 90.665 108.22)
		(end 90.725 108.28)
		(width 0.5)
		(layer "B.Cu")
		(net 28)
	)
	(segment
		(start 55.598 119.352)
		(end 55.6 119.35)
		(width 0.15)
		(layer "B.Cu")
		(net 28)
	)
	(segment
		(start 105.475 90.253)
		(end 106.583 90.253)
		(width 0.2)
		(layer "B.Cu")
		(net 28)
	)
	(segment
		(start 89.245 103.45)
		(end 89.245 103.05)
		(width 0.15)
		(layer "B.Cu")
		(net 28)
	)
	(segment
		(start 100.62 87.37)
		(end 100.63 87.36)
		(width 0.2)
		(layer "B.Cu")
		(net 28)
	)
	(segment
		(start 76.32 102.8)
		(end 76.32 102.57)
		(width 0.3)
		(layer "B.Cu")
		(net 28)
	)
	(segment
		(start 84.225 97.35)
		(end 84.645 96.93)
		(width 0.15)
		(layer "B.Cu")
		(net 28)
	)
	(segment
		(start 90.225 108.22)
		(end 90.665 108.22)
		(width 0.5)
		(layer "B.Cu")
		(net 28)
	)
	(segment
		(start 55.598 119.902)
		(end 55.598 119.352)
		(width 0.15)
		(layer "B.Cu")
		(net 28)
	)
	(segment
		(start 96.747999 55.49866)
		(end 96.747999 54.83366)
		(width 0.3)
		(layer "B.Cu")
		(net 28)
	)
	(segment
		(start 104.82 86.654)
		(end 104.82 85.93)
		(width 0.2)
		(layer "B.Cu")
		(net 28)
	)
	(segment
		(start 84.225 97.82)
		(end 84.225 97.35)
		(width 0.15)
		(layer "B.Cu")
		(net 28)
	)
	(segment
		(start 90.45 98.7)
		(end 90.55 98.7)
		(width 0.2)
		(layer "B.Cu")
		(net 28)
	)
	(segment
		(start 91.165 97.82)
		(end 91.2 97.82)
		(width 0.2)
		(layer "B.Cu")
		(net 28)
	)
	(segment
		(start 73.52 99.65)
		(end 73.1 99.65)
		(width 0.15)
		(layer "B.Cu")
		(net 28)
	)
	(segment
		(start 55.598 124.602)
		(end 55.598 124.052)
		(width 0.15)
		(layer "B.Cu")
		(net 28)
	)
	(segment
		(start 90.4 98.705)
		(end 90.445 98.705)
		(width 0.2)
		(layer "B.Cu")
		(net 28)
	)
	(segment
		(start 76.32 102.57)
		(end 76.725 102.165)
		(width 0.3)
		(layer "B.Cu")
		(net 28)
	)
	(segment
		(start 55.598 124.052)
		(end 55.6 124.05)
		(width 0.15)
		(layer "B.Cu")
		(net 28)
	)
	(segment
		(start 90.445 98.705)
		(end 90.45 98.7)
		(width 0.2)
		(layer "B.Cu")
		(net 28)
	)
	(segment
		(start 78.265 97.88)
		(end 78.225 97.84)
		(width 0.3)
		(layer "B.Cu")
		(net 28)
	)
	(segment
		(start 93.225 93.52)
		(end 92.73 93.52)
		(width 0.5)
		(layer "B.Cu")
		(net 28)
	)
	(segment
		(start 84.645 96.93)
		(end 85.225 96.93)
		(width 0.15)
		(layer "B.Cu")
		(net 28)
	)
	(segment
		(start 102.75 56.272)
		(end 102.75 55.5)
		(width 0.3)
		(layer "B.Cu")
		(net 28)
	)
	(segment
		(start 106.583 90.253)
		(end 106.59 90.26)
		(width 0.2)
		(layer "B.Cu")
		(net 28)
	)
	(segment
		(start 83.3 101.52)
		(end 80.445 101.52)
		(width 0.125)
		(layer "B.Cu")
		(net 28)
	)
	(segment
		(start 96.096841 107.694024)
		(end 96.016841 107.694024)
		(width 0.16)
		(layer "F.Cu")
		(net 29)
	)
	(segment
		(start 95.415 108.41)
		(end 95.225 108.22)
		(width 0.16)
		(layer "F.Cu")
		(net 29)
	)
	(segment
		(start 95.616841 108.41)
		(end 95.452318 108.41)
		(width 0.16)
		(layer "F.Cu")
		(net 29)
	)
	(segment
		(start 96.584999 108.41)
		(end 96.416841 108.41)
		(width 0.16)
		(layer "F.Cu")
		(net 29)
	)
	(segment
		(start 95.452318 108.41)
		(end 95.415 108.41)
		(width 0.16)
		(layer "F.Cu")
		(net 29)
	)
	(segment
		(start 96.919999 108.1)
		(end 96.894999 108.1)
		(width 0.16)
		(layer "F.Cu")
		(net 29)
	)
	(segment
		(start 95.696841 108.41)
		(end 95.616841 108.41)
		(width 0.16)
		(layer "F.Cu")
		(net 29)
	)
	(segment
		(start 95.856841 107.854024)
		(end 95.856841 108.25)
		(width 0.16)
		(layer "F.Cu")
		(net 29)
	)
	(segment
		(start 96.256841 108.25)
		(end 96.256841 107.854024)
		(width 0.16)
		(layer "F.Cu")
		(net 29)
	)
	(segment
		(start 96.894999 108.1)
		(end 96.584999 108.41)
		(width 0.16)
		(layer "F.Cu")
		(net 29)
	)
	(arc
		(start 96.256841 107.854024)
		(mid 96.209978 107.740887)
		(end 96.096841 107.694024)
		(width 0.16)
		(layer "F.Cu")
		(net 29)
	)
	(arc
		(start 96.416841 108.41)
		(mid 96.303704 108.363137)
		(end 96.256841 108.25)
		(width 0.16)
		(layer "F.Cu")
		(net 29)
	)
	(arc
		(start 96.016841 107.694024)
		(mid 95.903704 107.740887)
		(end 95.856841 107.854024)
		(width 0.16)
		(layer "F.Cu")
		(net 29)
	)
	(arc
		(start 95.856841 108.25)
		(mid 95.809978 108.363137)
		(end 95.696841 108.41)
		(width 0.16)
		(layer "F.Cu")
		(net 29)
	)
	(segment
		(start 97.904999 108.1)
		(end 97.879999 108.1)
		(width 0.16)
		(layer "F.Cu")
		(net 30)
	)
	(segment
		(start 98.869999 108.1)
		(end 98.844999 108.1)
		(width 0.16)
		(layer "F.Cu")
		(net 30)
	)
	(segment
		(start 98.844999 108.1)
		(end 98.534999 108.41)
		(width 0.16)
		(layer "F.Cu")
		(net 30)
	)
	(segment
		(start 98.869999 108.1)
		(end 98.869999 107.099999)
		(width 0.16)
		(layer "F.Cu")
		(net 30)
	)
	(segment
		(start 98.214999 108.41)
		(end 97.904999 108.1)
		(width 0.16)
		(layer "F.Cu")
		(net 30)
	)
	(segment
		(start 98.534999 108.41)
		(end 98.214999 108.41)
		(width 0.16)
		(layer "F.Cu")
		(net 30)
	)
	(segment
		(start 96.894999 109.1)
		(end 96.584999 108.79)
		(width 0.16)
		(layer "F.Cu")
		(net 31)
	)
	(segment
		(start 96.919999 109.1)
		(end 96.894999 109.1)
		(width 0.16)
		(layer "F.Cu")
		(net 31)
	)
	(segment
		(start 96.584999 108.79)
		(end 95.114763 108.79)
		(width 0.16)
		(layer "F.Cu")
		(net 31)
	)
	(segment
		(start 95.114763 108.79)
		(end 94.544763 108.22)
		(width 0.16)
		(layer "F.Cu")
		(net 31)
	)
	(segment
		(start 94.544763 108.22)
		(end 94.225 108.22)
		(width 0.16)
		(layer "F.Cu")
		(net 31)
	)
	(segment
		(start 93.724205 88.530911)
		(end 93.724205 88.410911)
		(width 0.202)
		(layer "F.Cu")
		(net 32)
	)
	(segment
		(start 93.725 90.055)
		(end 93.724205 90.054205)
		(width 0.202)
		(layer "F.Cu")
		(net 32)
	)
	(segment
		(start 93.964205 89.370911)
		(end 94.146013 89.370911)
		(width 0.202)
		(layer "F.Cu")
		(net 32)
	)
	(segment
		(start 93.724205 88.105244)
		(end 93.724205 85.554222)
		(width 0.202)
		(layer "F.Cu")
		(net 32)
	)
	(segment
		(start 93.724205 88.410911)
		(end 93.724205 88.105244)
		(width 0.202)
		(layer "F.Cu")
		(net 32)
	)
	(segment
		(start 94.309992 84.140008)
		(end 103.491379 74.958621)
		(width 0.202)
		(layer "F.Cu")
		(net 32)
	)
	(segment
		(start 94.386013 89.130911)
		(end 94.386013 89.010911)
		(width 0.202)
		(layer "F.Cu")
		(net 32)
	)
	(segment
		(start 104.498001 63.283655)
		(end 104.498001 63.258655)
		(width 0.202)
		(layer "F.Cu")
		(net 32)
	)
	(segment
		(start 94.146013 88.770911)
		(end 93.964205 88.770911)
		(width 0.202)
		(layer "F.Cu")
		(net 32)
	)
	(segment
		(start 93.724205 90.054205)
		(end 93.724205 89.610911)
		(width 0.202)
		(layer "F.Cu")
		(net 32)
	)
	(segment
		(start 104.192501 73.265962)
		(end 104.192501 63.589155)
		(width 0.202)
		(layer "F.Cu")
		(net 32)
	)
	(segment
		(start 104.192501 63.589155)
		(end 104.498001 63.283655)
		(width 0.202)
		(layer "F.Cu")
		(net 32)
	)
	(arc
		(start 93.724205 89.610911)
		(mid 93.794499 89.441205)
		(end 93.964205 89.370911)
		(width 0.202)
		(layer "F.Cu")
		(net 32)
	)
	(arc
		(start 94.386013 89.010911)
		(mid 94.315719 88.841205)
		(end 94.146013 88.770911)
		(width 0.202)
		(layer "F.Cu")
		(net 32)
	)
	(arc
		(start 94.146013 89.370911)
		(mid 94.315719 89.300617)
		(end 94.386013 89.130911)
		(width 0.202)
		(layer "F.Cu")
		(net 32)
	)
	(arc
		(start 103.491379 74.958621)
		(mid 104.010285 74.182022)
		(end 104.192501 73.265962)
		(width 0.202)
		(layer "F.Cu")
		(net 32)
	)
	(arc
		(start 93.964205 88.770911)
		(mid 93.794499 88.700617)
		(end 93.724205 88.530911)
		(width 0.202)
		(layer "F.Cu")
		(net 32)
	)
	(arc
		(start 93.724205 85.554222)
		(mid 93.876446 84.788855)
		(end 94.309992 84.140008)
		(width 0.202)
		(layer "F.Cu")
		(net 32)
	)
	(segment
		(start 93.225 90.25)
		(end 93.225 89.81)
		(width 0.125)
		(layer "F.Cu")
		(net 33)
	)
	(segment
		(start 93.225 89.81)
		(end 93.225 89.675)
		(width 0.202)
		(layer "F.Cu")
		(net 33)
	)
	(segment
		(start 93.225 90.92)
		(end 93.225 90.25)
		(width 0.202)
		(layer "F.Cu")
		(net 33)
	)
	(segment
		(start 103.803501 63.589155)
		(end 103.498001 63.283655)
		(width 0.202)
		(layer "F.Cu")
		(net 33)
	)
	(segment
		(start 94.029725 83.870143)
		(end 103.217715 74.682153)
		(width 0.202)
		(layer "F.Cu")
		(net 33)
	)
	(segment
		(start 103.803501 73.26794)
		(end 103.803501 63.589155)
		(width 0.202)
		(layer "F.Cu")
		(net 33)
	)
	(segment
		(start 93.335205 89.564795)
		(end 93.335205 85.546862)
		(width 0.202)
		(layer "F.Cu")
		(net 33)
	)
	(segment
		(start 93.225 89.675)
		(end 93.335205 89.564795)
		(width 0.202)
		(layer "F.Cu")
		(net 33)
	)
	(segment
		(start 103.498001 63.283655)
		(end 103.498001 63.258655)
		(width 0.202)
		(layer "F.Cu")
		(net 33)
	)
	(arc
		(start 103.217715 74.682153)
		(mid 103.65126 74.033307)
		(end 103.803501 73.26794)
		(width 0.202)
		(layer "F.Cu")
		(net 33)
	)
	(arc
		(start 93.335205 85.546862)
		(mid 93.515705 84.639428)
		(end 94.029725 83.870143)
		(width 0.202)
		(layer "F.Cu")
		(net 33)
	)
	(segment
		(start 101.8055 55.144501)
		(end 101.8055 54.50346)
		(width 0.202)
		(layer "F.Cu")
		(net 34)
	)
	(segment
		(start 101.75 55.200001)
		(end 101.8055 55.144501)
		(width 0.202)
		(layer "F.Cu")
		(net 34)
	)
	(segment
		(start 101.8055 54.50346)
		(end 101.6815 54.37946)
		(width 0.202)
		(layer "F.Cu")
		(net 34)
	)
	(segment
		(start 101.75 55.500001)
		(end 101.75 55.200001)
		(width 0.202)
		(layer "F.Cu")
		(net 34)
	)
	(via
		(at 89.725 91.785)
		(size 0.45)
		(drill 0.2)
		(layers "F.Cu" "B.Cu")
		(remove_unused_layers yes)
		(keep_end_layers yes)
		(zone_layer_connections)
		(net 34)
	)
	(via
		(at 101.6815 54.37946)
		(size 0.45)
		(drill 0.2)
		(layers "F.Cu" "B.Cu")
		(remove_unused_layers yes)
		(keep_end_layers yes)
		(zone_layer_connections)
		(net 34)
	)
	(segment
		(start 90.5155 89.922327)
		(end 90.5155 85.577561)
		(width 0.202)
		(layer "B.Cu")
		(net 34)
	)
	(segment
		(start 101.805499 56.513816)
		(end 101.805499 56.47616)
		(width 0.202)
		(layer "B.Cu")
		(net 34)
	)
	(segment
		(start 90.291848 90.353086)
		(end 90.369053 90.275881)
		(width 0.202)
		(layer "B.Cu")
		(net 34)
	)
	(segment
		(start 96.4 77.871573)
		(end 96.4 64.533913)
		(width 0.202)
		(layer "B.Cu")
		(net 34)
	)
	(segment
		(start 100.8055 58.450916)
		(end 100.8055 58.272224)
		(width 0.202)
		(layer "B.Cu")
		(net 34)
	)
	(segment
		(start 101.8055 54.50346)
		(end 101.8055 55.443158)
		(width 0.202)
		(layer "B.Cu")
		(net 34)
	)
	(segment
		(start 101.805499 56.47616)
		(end 101.749999 56.42066)
		(width 0.202)
		(layer "B.Cu")
		(net 34)
	)
	(segment
		(start 101.749999 55.498659)
		(end 101.749999 56.27066)
		(width 0.202)
		(layer "B.Cu")
		(net 34)
	)
	(segment
		(start 101.8055 55.443158)
		(end 101.749999 55.498659)
		(width 0.202)
		(layer "B.Cu")
		(net 34)
	)
	(segment
		(start 91.2177 83.8823)
		(end 95.814213 79.285787)
		(width 0.202)
		(layer "B.Cu")
		(net 34)
	)
	(segment
		(start 89.725 91.785)
		(end 89.884053 91.625947)
		(width 0.202)
		(layer "B.Cu")
		(net 34)
	)
	(segment
		(start 97.106338 62.828662)
		(end 100.325669 59.609331)
		(width 0.202)
		(layer "B.Cu")
		(net 34)
	)
	(segment
		(start 101.749999 56.42066)
		(end 101.749999 56.27066)
		(width 0.202)
		(layer "B.Cu")
		(net 34)
	)
	(segment
		(start 101.224619 57.260381)
		(end 101.688341 56.796659)
		(width 0.202)
		(layer "B.Cu")
		(net 34)
	)
	(segment
		(start 101.6815 54.37946)
		(end 101.8055 54.50346)
		(width 0.202)
		(layer "B.Cu")
		(net 34)
	)
	(segment
		(start 90.0305 91.272393)
		(end 90.0305 90.984036)
		(width 0.202)
		(layer "B.Cu")
		(net 34)
	)
	(arc
		(start 95.814213 79.285787)
		(mid 96.247759 78.63694)
		(end 96.4 77.871573)
		(width 0.202)
		(layer "B.Cu")
		(net 34)
	)
	(arc
		(start 101.688341 56.796659)
		(mid 101.775051 56.66689)
		(end 101.805499 56.513816)
		(width 0.202)
		(layer "B.Cu")
		(net 34)
	)
	(arc
		(start 90.369053 90.275881)
		(mid 90.47744 90.113669)
		(end 90.5155 89.922327)
		(width 0.202)
		(layer "B.Cu")
		(net 34)
	)
	(arc
		(start 90.5155 85.577561)
		(mid 90.697996 84.660092)
		(end 91.2177 83.8823)
		(width 0.202)
		(layer "B.Cu")
		(net 34)
	)
	(arc
		(start 100.325669 59.609331)
		(mid 100.680796 59.077846)
		(end 100.8055 58.450916)
		(width 0.202)
		(layer "B.Cu")
		(net 34)
	)
	(arc
		(start 100.8055 58.272224)
		(mid 100.914426 57.724619)
		(end 101.224619 57.260381)
		(width 0.202)
		(layer "B.Cu")
		(net 34)
	)
	(arc
		(start 96.4 64.533913)
		(mid 96.583571 63.611038)
		(end 97.106338 62.828662)
		(width 0.202)
		(layer "B.Cu")
		(net 34)
	)
	(arc
		(start 90.0305 90.984036)
		(mid 90.098422 90.642568)
		(end 90.291848 90.353086)
		(width 0.202)
		(layer "B.Cu")
		(net 34)
	)
	(arc
		(start 89.884053 91.625947)
		(mid 89.99244 91.463735)
		(end 90.0305 91.272393)
		(width 0.202)
		(layer "B.Cu")
		(net 34)
	)
	(segment
		(start 91.4195 89.7495)
		(end 91.4195 85.059059)
		(width 0.202)
		(layer "F.Cu")
		(net 35)
	)
	(segment
		(start 92.005286 83.644846)
		(end 101.995745 73.654387)
		(width 0.202)
		(layer "F.Cu")
		(net 35)
	)
	(segment
		(start 102.694505 71.967431)
		(end 102.694505 66.070495)
		(width 0.202)
		(layer "F.Cu")
		(net 35)
	)
	(segment
		(start 102.694505 66.070495)
		(end 103 65.765)
		(width 0.202)
		(layer "F.Cu")
		(net 35)
	)
	(segment
		(start 91.725 90.055)
		(end 91.4195 89.7495)
		(width 0.202)
		(layer "F.Cu")
		(net 35)
	)
	(arc
		(start 101.995745 73.654387)
		(mid 102.512903 72.880405)
		(end 102.694505 71.967431)
		(width 0.202)
		(layer "F.Cu")
		(net 35)
	)
	(arc
		(start 91.4195 85.059059)
		(mid 91.571741 84.293692)
		(end 92.005286 83.644846)
		(width 0.202)
		(layer "F.Cu")
		(net 35)
	)
	(segment
		(start 103.3055 55.144501)
		(end 103.3055 54.50346)
		(width 0.202)
		(layer "F.Cu")
		(net 36)
	)
	(segment
		(start 103.3055 54.50346)
		(end 103.1815 54.37946)
		(width 0.202)
		(layer "F.Cu")
		(net 36)
	)
	(segment
		(start 103.25 55.200001)
		(end 103.3055 55.144501)
		(width 0.202)
		(layer "F.Cu")
		(net 36)
	)
	(segment
		(start 103.25 55.500001)
		(end 103.25 55.200001)
		(width 0.202)
		(layer "F.Cu")
		(net 36)
	)
	(via
		(at 103.1815 54.37946)
		(size 0.45)
		(drill 0.2)
		(layers "F.Cu" "B.Cu")
		(remove_unused_layers yes)
		(keep_end_layers yes)
		(zone_layer_connections)
		(net 36)
	)
	(via
		(at 92.225 92.65)
		(size 0.45)
		(drill 0.2)
		(layers "F.Cu" "B.Cu")
		(remove_unused_layers yes)
		(keep_end_layers yes)
		(zone_layer_connections)
		(net 36)
	)
	(segment
		(start 103.3055 54.50346)
		(end 103.3055 55.443158)
		(width 0.202)
		(layer "B.Cu")
		(net 36)
	)
	(segment
		(start 92.5305 92.137393)
		(end 92.5305 91.895079)
		(width 0.202)
		(layer "B.Cu")
		(net 36)
	)
	(segment
		(start 94.11278 83.78722)
		(end 97.614213 80.285787)
		(width 0.202)
		(layer "B.Cu")
		(net 36)
	)
	(segment
		(start 103.303499 57.004721)
		(end 103.303499 56.47616)
		(width 0.202)
		(layer "B.Cu")
		(net 36)
	)
	(segment
		(start 102.708061 58.014373)
		(end 103.010606 57.711828)
		(width 0.202)
		(layer "B.Cu")
		(net 36)
	)
	(segment
		(start 103.3055 55.443158)
		(end 103.249999 55.498659)
		(width 0.202)
		(layer "B.Cu")
		(net 36)
	)
	(segment
		(start 98.899252 64.460682)
		(end 101.719713 61.640221)
		(width 0.202)
		(layer "B.Cu")
		(net 36)
	)
	(segment
		(start 103.247999 56.42066)
		(end 103.247999 56.27066)
		(width 0.202)
		(layer "B.Cu")
		(net 36)
	)
	(segment
		(start 102.3055 60.226007)
		(end 102.3055 58.986242)
		(width 0.202)
		(layer "B.Cu")
		(net 36)
	)
	(segment
		(start 103.303499 56.47616)
		(end 103.247999 56.42066)
		(width 0.202)
		(layer "B.Cu")
		(net 36)
	)
	(segment
		(start 103.249999 55.498659)
		(end 103.249999 56.27066)
		(width 0.202)
		(layer "B.Cu")
		(net 36)
	)
	(segment
		(start 92.225 92.65)
		(end 92.384053 92.490947)
		(width 0.202)
		(layer "B.Cu")
		(net 36)
	)
	(segment
		(start 103.1815 54.37946)
		(end 103.3055 54.50346)
		(width 0.202)
		(layer "B.Cu")
		(net 36)
	)
	(segment
		(start 92.939333 90.908068)
		(end 93.122607 90.724794)
		(width 0.202)
		(layer "B.Cu")
		(net 36)
	)
	(segment
		(start 93.4155 90.017687)
		(end 93.4155 85.470603)
		(width 0.202)
		(layer "B.Cu")
		(net 36)
	)
	(segment
		(start 98.2 78.871573)
		(end 98.2 66.148826)
		(width 0.202)
		(layer "B.Cu")
		(net 36)
	)
	(arc
		(start 97.614213 80.285787)
		(mid 98.047759 79.63694)
		(end 98.2 78.871573)
		(width 0.202)
		(layer "B.Cu")
		(net 36)
	)
	(arc
		(start 93.4155 85.470603)
		(mid 93.596717 84.559563)
		(end 94.11278 83.78722)
		(width 0.202)
		(layer "B.Cu")
		(net 36)
	)
	(arc
		(start 98.2 66.148826)
		(mid 98.38173 65.235209)
		(end 98.899252 64.460682)
		(width 0.202)
		(layer "B.Cu")
		(net 36)
	)
	(arc
		(start 92.5305 91.895079)
		(mid 92.636752 91.360912)
		(end 92.939333 90.908068)
		(width 0.202)
		(layer "B.Cu")
		(net 36)
	)
	(arc
		(start 102.3055 58.986242)
		(mid 102.410122 58.46027)
		(end 102.708061 58.014373)
		(width 0.202)
		(layer "B.Cu")
		(net 36)
	)
	(arc
		(start 103.010606 57.711828)
		(mid 103.227379 57.387404)
		(end 103.303499 57.004721)
		(width 0.202)
		(layer "B.Cu")
		(net 36)
	)
	(arc
		(start 93.122607 90.724794)
		(mid 93.33938 90.40037)
		(end 93.4155 90.017687)
		(width 0.202)
		(layer "B.Cu")
		(net 36)
	)
	(arc
		(start 92.384053 92.490947)
		(mid 92.49244 92.328735)
		(end 92.5305 92.137393)
		(width 0.202)
		(layer "B.Cu")
		(net 36)
	)
	(arc
		(start 101.719713 61.640221)
		(mid 102.153259 60.991374)
		(end 102.3055 60.226007)
		(width 0.202)
		(layer "B.Cu")
		(net 36)
	)
	(segment
		(start 102.1945 55.144501)
		(end 102.1945 54.50346)
		(width 0.202)
		(layer "F.Cu")
		(net 37)
	)
	(segment
		(start 102.1945 54.50346)
		(end 102.3185 54.37946)
		(width 0.202)
		(layer "F.Cu")
		(net 37)
	)
	(segment
		(start 102.25 55.200001)
		(end 102.1945 55.144501)
		(width 0.202)
		(layer "F.Cu")
		(net 37)
	)
	(segment
		(start 102.25 55.500001)
		(end 102.25 55.200001)
		(width 0.202)
		(layer "F.Cu")
		(net 37)
	)
	(via
		(at 102.3185 54.37946)
		(size 0.45)
		(drill 0.2)
		(layers "F.Cu" "B.Cu")
		(remove_unused_layers yes)
		(keep_end_layers yes)
		(zone_layer_connections)
		(net 37)
	)
	(via
		(at 90.725 91.785)
		(size 0.45)
		(drill 0.2)
		(layers "F.Cu" "B.Cu")
		(remove_unused_layers yes)
		(keep_end_layers yes)
		(zone_layer_connections)
		(net 37)
	)
	(segment
		(start 90.4195 91.272393)
		(end 90.4195 90.982673)
		(width 0.202)
		(layer "B.Cu")
		(net 37)
	)
	(segment
		(start 101.1945 58.462205)
		(end 101.1945 58.254846)
		(width 0.202)
		(layer "B.Cu")
		(net 37)
	)
	(segment
		(start 102.249999 55.49866)
		(end 102.249999 56.27066)
		(width 0.202)
		(layer "B.Cu")
		(net 37)
	)
	(segment
		(start 102.194499 56.47616)
		(end 102.249999 56.42066)
		(width 0.202)
		(layer "B.Cu")
		(net 37)
	)
	(segment
		(start 102.249999 56.42066)
		(end 102.249999 56.27066)
		(width 0.202)
		(layer "B.Cu")
		(net 37)
	)
	(segment
		(start 96.789 77.867429)
		(end 96.789 64.524559)
		(width 0.202)
		(layer "B.Cu")
		(net 37)
	)
	(segment
		(start 91.490286 84.159846)
		(end 96.086346 79.563786)
		(width 0.202)
		(layer "B.Cu")
		(net 37)
	)
	(segment
		(start 90.9045 89.909614)
		(end 90.9045 85.574059)
		(width 0.202)
		(layer "B.Cu")
		(net 37)
	)
	(segment
		(start 90.565946 90.62912)
		(end 90.635136 90.559929)
		(width 0.202)
		(layer "B.Cu")
		(net 37)
	)
	(segment
		(start 102.3185 54.37946)
		(end 102.1945 54.50346)
		(width 0.202)
		(layer "B.Cu")
		(net 37)
	)
	(segment
		(start 102.194501 56.516105)
		(end 102.194499 56.47616)
		(width 0.202)
		(layer "B.Cu")
		(net 37)
	)
	(segment
		(start 101.487393 57.547739)
		(end 101.965051 57.070081)
		(width 0.202)
		(layer "B.Cu")
		(net 37)
	)
	(segment
		(start 102.1945 54.50346)
		(end 102.1945 55.443161)
		(width 0.202)
		(layer "B.Cu")
		(net 37)
	)
	(segment
		(start 97.374786 63.110346)
		(end 100.608713 59.876419)
		(width 0.202)
		(layer "B.Cu")
		(net 37)
	)
	(segment
		(start 102.1945 55.443161)
		(end 102.249999 55.49866)
		(width 0.202)
		(layer "B.Cu")
		(net 37)
	)
	(segment
		(start 90.725 91.785)
		(end 90.565947 91.625947)
		(width 0.202)
		(layer "B.Cu")
		(net 37)
	)
	(arc
		(start 90.565947 91.625947)
		(mid 90.45756 91.463735)
		(end 90.4195 91.272393)
		(width 0.202)
		(layer "B.Cu")
		(net 37)
	)
	(arc
		(start 101.965051 57.070081)
		(mid 102.134876 56.815915)
		(end 102.194501 56.516105)
		(width 0.202)
		(layer "B.Cu")
		(net 37)
	)
	(arc
		(start 90.4195 90.982673)
		(mid 90.45756 90.791332)
		(end 90.565946 90.62912)
		(width 0.202)
		(layer "B.Cu")
		(net 37)
	)
	(arc
		(start 90.9045 85.574059)
		(mid 91.056741 84.808692)
		(end 91.490286 84.159846)
		(width 0.202)
		(layer "B.Cu")
		(net 37)
	)
	(arc
		(start 96.789 64.524559)
		(mid 96.941241 63.759192)
		(end 97.374786 63.110346)
		(width 0.202)
		(layer "B.Cu")
		(net 37)
	)
	(arc
		(start 101.1945 58.254846)
		(mid 101.27062 57.872163)
		(end 101.487393 57.547739)
		(width 0.202)
		(layer "B.Cu")
		(net 37)
	)
	(arc
		(start 100.608713 59.876419)
		(mid 101.042259 59.227572)
		(end 101.1945 58.462205)
		(width 0.202)
		(layer "B.Cu")
		(net 37)
	)
	(arc
		(start 90.635136 90.559929)
		(mid 90.834495 90.261561)
		(end 90.9045 89.909614)
		(width 0.202)
		(layer "B.Cu")
		(net 37)
	)
	(arc
		(start 96.086346 79.563786)
		(mid 96.606386 78.785491)
		(end 96.789 77.867429)
		(width 0.202)
		(layer "B.Cu")
		(net 37)
	)
	(segment
		(start 102.305505 66.070505)
		(end 102 65.765)
		(width 0.202)
		(layer "F.Cu")
		(net 38)
	)
	(segment
		(start 90.725 90.055)
		(end 91.0305 89.7495)
		(width 0.202)
		(layer "F.Cu")
		(net 38)
	)
	(segment
		(start 91.0305 89.7495)
		(end 91.0305 85.0628)
		(width 0.202)
		(layer "F.Cu")
		(net 38)
	)
	(segment
		(start 102.305505 71.966068)
		(end 102.305505 66.070505)
		(width 0.202)
		(layer "F.Cu")
		(net 38)
	)
	(segment
		(start 91.732869 83.367131)
		(end 101.719718 73.380282)
		(width 0.202)
		(layer "F.Cu")
		(net 38)
	)
	(arc
		(start 101.719718 73.380282)
		(mid 102.153264 72.731435)
		(end 102.305505 71.966068)
		(width 0.202)
		(layer "F.Cu")
		(net 38)
	)
	(arc
		(start 91.0305 85.0628)
		(mid 91.21304 84.145111)
		(end 91.732869 83.367131)
		(width 0.202)
		(layer "F.Cu")
		(net 38)
	)
	(segment
		(start 103.6945 55.144501)
		(end 103.6945 54.50346)
		(width 0.202)
		(layer "F.Cu")
		(net 39)
	)
	(segment
		(start 103.75 55.200001)
		(end 103.6945 55.144501)
		(width 0.202)
		(layer "F.Cu")
		(net 39)
	)
	(segment
		(start 103.75 55.500001)
		(end 103.75 55.200001)
		(width 0.202)
		(layer "F.Cu")
		(net 39)
	)
	(segment
		(start 103.6945 54.50346)
		(end 103.8185 54.37946)
		(width 0.202)
		(layer "F.Cu")
		(net 39)
	)
	(via
		(at 103.8185 54.37946)
		(size 0.45)
		(drill 0.2)
		(layers "F.Cu" "B.Cu")
		(remove_unused_layers yes)
		(keep_end_layers yes)
		(zone_layer_connections)
		(net 39)
	)
	(via
		(at 93.225 92.65)
		(size 0.45)
		(drill 0.2)
		(layers "F.Cu" "B.Cu")
		(remove_unused_layers yes)
		(keep_end_layers yes)
		(zone_layer_connections)
		(net 39)
	)
	(segment
		(start 103.747999 56.42066)
		(end 103.747999 56.27066)
		(width 0.202)
		(layer "B.Cu")
		(net 39)
	)
	(segment
		(start 98.589 78.878366)
		(end 98.589 66.149493)
		(width 0.202)
		(layer "B.Cu")
		(net 39)
	)
	(segment
		(start 102.987393 58.285173)
		(end 103.290544 57.982022)
		(width 0.202)
		(layer "B.Cu")
		(net 39)
	)
	(segment
		(start 93.8045 90.000083)
		(end 93.8045 85.474059)
		(width 0.202)
		(layer "B.Cu")
		(net 39)
	)
	(segment
		(start 93.225 92.65)
		(end 93.065947 92.490947)
		(width 0.202)
		(layer "B.Cu")
		(net 39)
	)
	(segment
		(start 103.692499 56.47616)
		(end 103.747999 56.42066)
		(width 0.202)
		(layer "B.Cu")
		(net 39)
	)
	(segment
		(start 103.6945 55.443161)
		(end 103.749999 55.49866)
		(width 0.202)
		(layer "B.Cu")
		(net 39)
	)
	(segment
		(start 103.6945 54.50346)
		(end 103.6945 55.443161)
		(width 0.202)
		(layer "B.Cu")
		(net 39)
	)
	(segment
		(start 94.390286 84.059846)
		(end 97.89408 80.556052)
		(width 0.202)
		(layer "B.Cu")
		(net 39)
	)
	(segment
		(start 102.6945 60.21235)
		(end 102.6945 58.99228)
		(width 0.202)
		(layer "B.Cu")
		(net 39)
	)
	(segment
		(start 92.9195 92.137393)
		(end 92.9195 91.892247)
		(width 0.202)
		(layer "B.Cu")
		(net 39)
	)
	(segment
		(start 103.8185 54.37946)
		(end 103.6945 54.50346)
		(width 0.202)
		(layer "B.Cu")
		(net 39)
	)
	(segment
		(start 93.212393 91.18514)
		(end 93.385221 91.012312)
		(width 0.202)
		(layer "B.Cu")
		(net 39)
	)
	(segment
		(start 103.749999 55.49866)
		(end 103.749999 56.27066)
		(width 0.202)
		(layer "B.Cu")
		(net 39)
	)
	(segment
		(start 103.692499 57.011615)
		(end 103.692499 56.47616)
		(width 0.202)
		(layer "B.Cu")
		(net 39)
	)
	(segment
		(start 99.174786 64.73528)
		(end 101.985118 61.924948)
		(width 0.202)
		(layer "B.Cu")
		(net 39)
	)
	(arc
		(start 103.290544 57.982022)
		(mid 103.588035 57.536795)
		(end 103.692499 57.011615)
		(width 0.202)
		(layer "B.Cu")
		(net 39)
	)
	(arc
		(start 93.385221 91.012312)
		(mid 93.695533 90.547897)
		(end 93.8045 90.000083)
		(width 0.202)
		(layer "B.Cu")
		(net 39)
	)
	(arc
		(start 93.8045 85.474059)
		(mid 93.956741 84.708692)
		(end 94.390286 84.059846)
		(width 0.202)
		(layer "B.Cu")
		(net 39)
	)
	(arc
		(start 93.065947 92.490947)
		(mid 92.95756 92.328735)
		(end 92.9195 92.137393)
		(width 0.202)
		(layer "B.Cu")
		(net 39)
	)
	(arc
		(start 101.985118 61.924948)
		(mid 102.510137 61.139201)
		(end 102.6945 60.21235)
		(width 0.202)
		(layer "B.Cu")
		(net 39)
	)
	(arc
		(start 102.6945 58.99228)
		(mid 102.77062 58.609596)
		(end 102.987393 58.285173)
		(width 0.202)
		(layer "B.Cu")
		(net 39)
	)
	(arc
		(start 97.89408 80.556052)
		(mid 98.408396 79.786323)
		(end 98.589 78.878366)
		(width 0.202)
		(layer "B.Cu")
		(net 39)
	)
	(arc
		(start 98.589 66.149493)
		(mid 98.741241 65.384126)
		(end 99.174786 64.73528)
		(width 0.202)
		(layer "B.Cu")
		(net 39)
	)
	(arc
		(start 92.9195 91.892247)
		(mid 92.99562 91.509563)
		(end 93.212393 91.18514)
		(width 0.202)
		(layer "B.Cu")
		(net 39)
	)
	(segment
		(start 98.498001 63.283655)
		(end 98.498001 63.258655)
		(width 0.202)
		(layer "F.Cu")
		(net 40)
	)
	(segment
		(start 98.192501 63.589155)
		(end 98.498001 63.283655)
		(width 0.202)
		(layer "F.Cu")
		(net 40)
	)
	(segment
		(start 88.4195 89.7495)
		(end 88.4195 85.209059)
		(width 0.202)
		(layer "F.Cu")
		(net 40)
	)
	(segment
		(start 88.725 90.055)
		(end 88.4195 89.7495)
		(width 0.202)
		(layer "F.Cu")
		(net 40)
	)
	(segment
		(start 98.192501 73.616271)
		(end 98.192501 63.589155)
		(width 0.202)
		(layer "F.Cu")
		(net 40)
	)
	(segment
		(start 89.005286 83.794846)
		(end 97.491504 75.308628)
		(width 0.202)
		(layer "F.Cu")
		(net 40)
	)
	(arc
		(start 97.491504 75.308628)
		(mid 98.010318 74.532168)
		(end 98.192501 73.616271)
		(width 0.202)
		(layer "F.Cu")
		(net 40)
	)
	(arc
		(start 88.4195 85.209059)
		(mid 88.571741 84.443692)
		(end 89.005286 83.794846)
		(width 0.202)
		(layer "F.Cu")
		(net 40)
	)
	(segment
		(start 88.0305 89.7495)
		(end 88.0305 85.199169)
		(width 0.202)
		(layer "F.Cu")
		(net 41)
	)
	(segment
		(start 97.803501 63.589155)
		(end 97.498001 63.283655)
		(width 0.202)
		(layer "F.Cu")
		(net 41)
	)
	(segment
		(start 87.725 90.055)
		(end 88.0305 89.7495)
		(width 0.202)
		(layer "F.Cu")
		(net 41)
	)
	(segment
		(start 97.803501 73.618072)
		(end 97.803501 63.589155)
		(width 0.202)
		(layer "F.Cu")
		(net 41)
	)
	(segment
		(start 88.723231 83.526769)
		(end 97.217714 75.032286)
		(width 0.202)
		(layer "F.Cu")
		(net 41)
	)
	(arc
		(start 97.217714 75.032286)
		(mid 97.65126 74.383439)
		(end 97.803501 73.618072)
		(width 0.202)
		(layer "F.Cu")
		(net 41)
	)
	(arc
		(start 88.0305 85.199169)
		(mid 88.210535 84.294073)
		(end 88.723231 83.526769)
		(width 0.202)
		(layer "F.Cu")
		(net 41)
	)
	(segment
		(start 99.9455 89.884)
		(end 100.42898 89.884)
		(width 0.202)
		(layer "F.Cu")
		(net 42)
	)
	(segment
		(start 99.6945 59.544499)
		(end 99.75 59.599999)
		(width 0.202)
		(layer "F.Cu")
		(net 42)
	)
	(segment
		(start 99.75 59.599999)
		(end 99.75 60.372)
		(width 0.202)
		(layer "F.Cu")
		(net 42)
	)
	(segment
		(start 99.75 57.990001)
		(end 99.6945 58.045501)
		(width 0.202)
		(layer "F.Cu")
		(net 42)
	)
	(segment
		(start 99.75 57.690001)
		(end 99.75 57.990001)
		(width 0.202)
		(layer "F.Cu")
		(net 42)
	)
	(segment
		(start 101.7845 88.52848)
		(end 101.7845 85.054)
		(width 0.202)
		(layer "F.Cu")
		(net 42)
	)
	(segment
		(start 99.665 90.1645)
		(end 99.9455 89.884)
		(width 0.202)
		(layer "F.Cu")
		(net 42)
	)
	(segment
		(start 99.64 90.1645)
		(end 99.665 90.1645)
		(width 0.202)
		(layer "F.Cu")
		(net 42)
	)
	(segment
		(start 100.4945 72.25)
		(end 100.4945 62.643927)
		(width 0.202)
		(layer "F.Cu")
		(net 42)
	)
	(segment
		(start 100.6185 72.374)
		(end 100.4945 72.25)
		(width 0.202)
		(layer "F.Cu")
		(net 42)
	)
	(segment
		(start 99.696499 60.842219)
		(end 99.696499 60.425501)
		(width 0.202)
		(layer "F.Cu")
		(net 42)
	)
	(segment
		(start 101.7845 85.054)
		(end 101.9085 84.93)
		(width 0.202)
		(layer "F.Cu")
		(net 42)
	)
	(segment
		(start 99.6945 58.045501)
		(end 99.6945 59.544499)
		(width 0.202)
		(layer "F.Cu")
		(net 42)
	)
	(segment
		(start 101.269023 89.536043)
		(end 101.436543 89.368523)
		(width 0.202)
		(layer "F.Cu")
		(net 42)
	)
	(segment
		(start 99.696499 60.425501)
		(end 99.752 60.37)
		(width 0.202)
		(layer "F.Cu")
		(net 42)
	)
	(segment
		(start 100.077666 61.6376)
		(end 99.989392 61.549326)
		(width 0.202)
		(layer "F.Cu")
		(net 42)
	)
	(via
		(at 101.9085 84.93)
		(size 0.45)
		(drill 0.2)
		(layers "F.Cu" "B.Cu")
		(remove_unused_layers yes)
		(keep_end_layers yes)
		(zone_layer_connections)
		(net 42)
	)
	(via
		(at 100.6185 72.374)
		(size 0.45)
		(drill 0.2)
		(layers "F.Cu" "B.Cu")
		(remove_unused_layers yes)
		(keep_end_layers yes)
		(zone_layer_connections)
		(net 42)
	)
	(arc
		(start 101.269023 89.536043)
		(mid 100.883608 89.793569)
		(end 100.42898 89.884)
		(width 0.202)
		(layer "F.Cu")
		(net 42)
	)
	(arc
		(start 99.989392 61.549326)
		(mid 99.772619 61.224902)
		(end 99.696499 60.842219)
		(width 0.202)
		(layer "F.Cu")
		(net 42)
	)
	(arc
		(start 101.436543 89.368523)
		(mid 101.694069 88.983108)
		(end 101.7845 88.52848)
		(width 0.202)
		(layer "F.Cu")
		(net 42)
	)
	(arc
		(start 100.4945 62.643927)
		(mid 100.386168 62.099307)
		(end 100.077666 61.6376)
		(width 0.202)
		(layer "F.Cu")
		(net 42)
	)
	(segment
		(start 101.9085 84.93)
		(end 101.7845 84.806)
		(width 0.202)
		(layer "B.Cu")
		(net 42)
	)
	(segment
		(start 100.4945 72.498)
		(end 100.6185 72.374)
		(width 0.202)
		(layer "B.Cu")
		(net 42)
	)
	(segment
		(start 101.7845 84.806)
		(end 101.7845 82.72152)
		(width 0.202)
		(layer "B.Cu")
		(net 42)
	)
	(segment
		(start 100.4945 80.52522)
		(end 100.4945 72.498)
		(width 0.202)
		(layer "B.Cu")
		(net 42)
	)
	(segment
		(start 101.436543 81.881477)
		(end 100.787393 81.232327)
		(width 0.202)
		(layer "B.Cu")
		(net 42)
	)
	(arc
		(start 101.436543 81.881477)
		(mid 101.694069 82.266892)
		(end 101.7845 82.72152)
		(width 0.202)
		(layer "B.Cu")
		(net 42)
	)
	(arc
		(start 100.4945 80.52522)
		(mid 100.57062 80.907903)
		(end 100.787393 81.232327)
		(width 0.202)
		(layer "B.Cu")
		(net 42)
	)
	(segment
		(start 85.4195 89.7495)
		(end 85.4195 85.409059)
		(width 0.202)
		(layer "F.Cu")
		(net 44)
	)
	(segment
		(start 86.005286 83.994846)
		(end 95.998453 74.001679)
		(width 0.202)
		(layer "F.Cu")
		(net 44)
	)
	(segment
		(start 96.694505 66.070495)
		(end 97 65.765)
		(width 0.202)
		(layer "F.Cu")
		(net 44)
	)
	(segment
		(start 85.725 90.055)
		(end 85.4195 89.7495)
		(width 0.202)
		(layer "F.Cu")
		(net 44)
	)
	(segment
		(start 96.694505 72.32126)
		(end 96.694505 66.070495)
		(width 0.202)
		(layer "F.Cu")
		(net 44)
	)
	(arc
		(start 85.4195 85.409059)
		(mid 85.571741 84.643692)
		(end 86.005286 83.994846)
		(width 0.202)
		(layer "F.Cu")
		(net 44)
	)
	(arc
		(start 95.998453 74.001679)
		(mid 96.513607 73.230696)
		(end 96.694505 72.32126)
		(width 0.202)
		(layer "F.Cu")
		(net 44)
	)
	(segment
		(start 101.124096 86.303102)
		(end 101.1555 86.303102)
		(width 0.202)
		(layer "F.Cu")
		(net 45)
	)
	(segment
		(start 101.102607 89.152327)
		(end 101.052827 89.202107)
		(width 0.202)
		(layer "F.Cu")
		(net 45)
	)
	(segment
		(start 99.25 59.6)
		(end 99.25 60.372)
		(width 0.202)
		(layer "F.Cu")
		(net 45)
	)
	(segment
		(start 101.3955 86.663102)
		(end 101.3955 87.08275)
		(width 0.202)
		(layer "F.Cu")
		(net 45)
	)
	(segment
		(start 99.307499 60.829487)
		(end 99.307499 60.4255)
		(width 0.202)
		(layer "F.Cu")
		(net 45)
	)
	(segment
		(start 99.812607 61.922673)
		(end 99.723332 61.833398)
		(width 0.202)
		(layer "F.Cu")
		(net 45)
	)
	(segment
		(start 99.307499 60.4255)
		(end 99.252 60.370001)
		(width 0.202)
		(layer "F.Cu")
		(net 45)
	)
	(segment
		(start 99.665 89.2145)
		(end 99.64 89.2145)
		(width 0.202)
		(layer "F.Cu")
		(net 45)
	)
	(segment
		(start 101.3955 86.543102)
		(end 101.3955 86.663102)
		(width 0.202)
		(layer "F.Cu")
		(net 45)
	)
	(segment
		(start 101.3955 87.08275)
		(end 101.3955 88.44522)
		(width 0.202)
		(layer "F.Cu")
		(net 45)
	)
	(segment
		(start 100.1055 72.25)
		(end 100.1055 62.62978)
		(width 0.202)
		(layer "F.Cu")
		(net 45)
	)
	(segment
		(start 100.884096 85.943102)
		(end 100.884096 86.063102)
		(width 0.202)
		(layer "F.Cu")
		(net 45)
	)
	(segment
		(start 101.3955 85.054)
		(end 101.3955 85.463102)
		(width 0.202)
		(layer "F.Cu")
		(net 45)
	)
	(segment
		(start 101.1555 85.703102)
		(end 101.124096 85.703102)
		(width 0.202)
		(layer "F.Cu")
		(net 45)
	)
	(segment
		(start 99.25 57.990001)
		(end 99.25 57.690001)
		(width 0.202)
		(layer "F.Cu")
		(net 45)
	)
	(segment
		(start 99.3055 58.045501)
		(end 99.25 57.990001)
		(width 0.202)
		(layer "F.Cu")
		(net 45)
	)
	(segment
		(start 99.9455 89.495)
		(end 99.665 89.2145)
		(width 0.202)
		(layer "F.Cu")
		(net 45)
	)
	(segment
		(start 99.25 59.6)
		(end 99.3055 59.5445)
		(width 0.202)
		(layer "F.Cu")
		(net 45)
	)
	(segment
		(start 99.3055 59.5445)
		(end 99.3055 58.045501)
		(width 0.202)
		(layer "F.Cu")
		(net 45)
	)
	(segment
		(start 100.34572 89.495)
		(end 99.9455 89.495)
		(width 0.202)
		(layer "F.Cu")
		(net 45)
	)
	(segment
		(start 101.2715 84.93)
		(end 101.3955 85.054)
		(width 0.202)
		(layer "F.Cu")
		(net 45)
	)
	(segment
		(start 99.9815 72.374)
		(end 100.1055 72.25)
		(width 0.202)
		(layer "F.Cu")
		(net 45)
	)
	(via
		(at 99.9815 72.374)
		(size 0.45)
		(drill 0.2)
		(layers "F.Cu" "B.Cu")
		(remove_unused_layers yes)
		(keep_end_layers yes)
		(zone_layer_connections)
		(net 45)
	)
	(via
		(at 101.2715 84.93)
		(size 0.45)
		(drill 0.2)
		(layers "F.Cu" "B.Cu")
		(remove_unused_layers yes)
		(keep_end_layers yes)
		(zone_layer_connections)
		(net 45)
	)
	(arc
		(start 99.723332 61.833398)
		(mid 99.41557 61.3728)
		(end 99.307499 60.829487)
		(width 0.202)
		(layer "F.Cu")
		(net 45)
	)
	(arc
		(start 100.1055 62.62978)
		(mid 100.02938 62.247096)
		(end 99.812607 61.922673)
		(width 0.202)
		(layer "F.Cu")
		(net 45)
	)
	(arc
		(start 101.1555 86.303102)
		(mid 101.325206 86.373396)
		(end 101.3955 86.543102)
		(width 0.202)
		(layer "F.Cu")
		(net 45)
	)
	(arc
		(start 101.3955 88.44522)
		(mid 101.31938 88.827903)
		(end 101.102607 89.152327)
		(width 0.202)
		(layer "F.Cu")
		(net 45)
	)
	(arc
		(start 101.052827 89.202107)
		(mid 100.728403 89.41888)
		(end 100.34572 89.495)
		(width 0.202)
		(layer "F.Cu")
		(net 45)
	)
	(arc
		(start 101.3955 85.463102)
		(mid 101.325206 85.632808)
		(end 101.1555 85.703102)
		(width 0.202)
		(layer "F.Cu")
		(net 45)
	)
	(arc
		(start 101.124096 85.703102)
		(mid 100.95439 85.773396)
		(end 100.884096 85.943102)
		(width 0.202)
		(layer "F.Cu")
		(net 45)
	)
	(arc
		(start 100.884096 86.063102)
		(mid 100.95439 86.232808)
		(end 101.124096 86.303102)
		(width 0.202)
		(layer "F.Cu")
		(net 45)
	)
	(segment
		(start 101.102607 82.097673)
		(end 100.453457 81.448523)
		(width 0.202)
		(layer "B.Cu")
		(net 45)
	)
	(segment
		(start 100.1055 80.60848)
		(end 100.1055 72.498)
		(width 0.202)
		(layer "B.Cu")
		(net 45)
	)
	(segment
		(start 101.3955 84.806)
		(end 101.3955 82.80478)
		(width 0.202)
		(layer "B.Cu")
		(net 45)
	)
	(segment
		(start 101.2715 84.93)
		(end 101.3955 84.806)
		(width 0.202)
		(layer "B.Cu")
		(net 45)
	)
	(segment
		(start 100.1055 72.498)
		(end 99.9815 72.374)
		(width 0.202)
		(layer "B.Cu")
		(net 45)
	)
	(arc
		(start 100.453457 81.448523)
		(mid 100.195931 81.063108)
		(end 100.1055 80.60848)
		(width 0.202)
		(layer "B.Cu")
		(net 45)
	)
	(arc
		(start 101.102607 82.097673)
		(mid 101.31938 82.422096)
		(end 101.3955 82.80478)
		(width 0.202)
		(layer "B.Cu")
		(net 45)
	)
	(segment
		(start 85.0305 89.7495)
		(end 85.0305 85.401339)
		(width 0.202)
		(layer "F.Cu")
		(net 46)
	)
	(segment
		(start 84.725 90.055)
		(end 85.0305 89.7495)
		(width 0.202)
		(layer "F.Cu")
		(net 46)
	)
	(segment
		(start 96.305505 72.316068)
		(end 96.305505 66.070505)
		(width 0.202)
		(layer "F.Cu")
		(net 46)
	)
	(segment
		(start 85.724765 83.725235)
		(end 95.719718 73.730282)
		(width 0.202)
		(layer "F.Cu")
		(net 46)
	)
	(segment
		(start 96.305505 66.070505)
		(end 96 65.765)
		(width 0.202)
		(layer "F.Cu")
		(net 46)
	)
	(arc
		(start 95.719718 73.730282)
		(mid 96.153264 73.081435)
		(end 96.305505 72.316068)
		(width 0.202)
		(layer "F.Cu")
		(net 46)
	)
	(arc
		(start 85.0305 85.401339)
		(mid 85.210934 84.494238)
		(end 85.724765 83.725235)
		(width 0.202)
		(layer "F.Cu")
		(net 46)
	)
	(via
		(at 76.225 96.11)
		(size 0.45)
		(drill 0.2)
		(layers "F.Cu" "B.Cu")
		(remove_unused_layers yes)
		(keep_end_layers yes)
		(zone_layer_connections)
		(net 47)
	)
	(segment
		(start 74.48 97.65)
		(end 74.48 98.65)
		(width 0.15)
		(layer "B.Cu")
		(net 47)
	)
	(segment
		(start 74.48 96.65)
		(end 75.35 96.65)
		(width 0.15)
		(layer "B.Cu")
		(net 47)
	)
	(segment
		(start 75.89 96.11)
		(end 76.225 96.11)
		(width 0.15)
		(layer "B.Cu")
		(net 47)
	)
	(segment
		(start 74.48 96.65)
		(end 74.48 97.65)
		(width 0.15)
		(layer "B.Cu")
		(net 47)
	)
	(segment
		(start 74.48 99.65)
		(end 74.48 98.65)
		(width 0.15)
		(layer "B.Cu")
		(net 47)
	)
	(segment
		(start 75.35 96.65)
		(end 75.89 96.11)
		(width 0.15)
		(layer "B.Cu")
		(net 47)
	)
	(via
		(at 76.725 109.085)
		(size 0.45)
		(drill 0.2)
		(layers "F.Cu" "B.Cu")
		(remove_unused_layers yes)
		(keep_end_layers yes)
		(zone_layer_connections)
		(net 48)
	)
	(segment
		(start 71.112598 132.39)
		(end 72.763553 130.739045)
		(width 0.16)
		(layer "B.Cu")
		(net 48)
	)
	(segment
		(start 70.93 132.39)
		(end 71.112598 132.39)
		(width 0.16)
		(layer "B.Cu")
		(net 48)
	)
	(segment
		(start 73.320816 119.960482)
		(end 76.432107 116.849191)
		(width 0.16)
		(layer "B.Cu")
		(net 48)
	)
	(segment
		(start 76.725 116.142084)
		(end 76.725 109.085)
		(width 0.16)
		(layer "B.Cu")
		(net 48)
	)
	(segment
		(start 72.91 120.952279)
		(end 72.91 130.385491)
		(width 0.16)
		(layer "B.Cu")
		(net 48)
	)
	(arc
		(start 76.725 116.142084)
		(mid 76.64888 116.524767)
		(end 76.432107 116.849191)
		(width 0.16)
		(layer "B.Cu")
		(net 48)
	)
	(arc
		(start 72.763553 130.739045)
		(mid 72.87194 130.576833)
		(end 72.91 130.385491)
		(width 0.16)
		(layer "B.Cu")
		(net 48)
	)
	(arc
		(start 73.320816 119.960482)
		(mid 73.016768 120.415522)
		(end 72.91 120.952279)
		(width 0.16)
		(layer "B.Cu")
		(net 48)
	)
	(via
		(at 76.225 109.95)
		(size 0.45)
		(drill 0.2)
		(layers "F.Cu" "B.Cu")
		(remove_unused_layers yes)
		(keep_end_layers yes)
		(zone_layer_connections)
		(net 49)
	)
	(segment
		(start 75.320573 116.24592)
		(end 75.225736 116.151083)
		(width 0.16)
		(layer "B.Cu")
		(net 49)
	)
	(segment
		(start 74.801471 116.235934)
		(end 74.8 116.237404)
		(width 0.16)
		(layer "B.Cu")
		(net 49)
	)
	(segment
		(start 76.225 109.958032)
		(end 76.105001 110.078031)
		(width 0.16)
		(layer "B.Cu")
		(net 49)
	)
	(segment
		(start 74.8 116.237404)
		(end 71.407893 119.629511)
		(width 0.16)
		(layer "B.Cu")
		(net 49)
	)
	(segment
		(start 75.744837 116.161066)
		(end 75.659985 116.245919)
		(width 0.16)
		(layer "B.Cu")
		(net 49)
	)
	(segment
		(start 71.261447 129.171447)
		(end 71.94 129.85)
		(width 0.16)
		(layer "B.Cu")
		(net 49)
	)
	(segment
		(start 75.65 115.726816)
		(end 75.744838 115.821654)
		(width 0.16)
		(layer "B.Cu")
		(net 49)
	)
	(segment
		(start 76.105001 110.078031)
		(end 76.105001 114.361658)
		(width 0.16)
		(layer "B.Cu")
		(net 49)
	)
	(segment
		(start 75.701423 115.335981)
		(end 75.65 115.387404)
		(width 0.16)
		(layer "B.Cu")
		(net 49)
	)
	(segment
		(start 74.886326 116.151082)
		(end 74.801471 116.235934)
		(width 0.16)
		(layer "B.Cu")
		(net 49)
	)
	(segment
		(start 71.115 120.336618)
		(end 71.115 128.817893)
		(width 0.16)
		(layer "B.Cu")
		(net 49)
	)
	(arc
		(start 71.407893 119.629511)
		(mid 71.19112 119.953935)
		(end 71.115 120.336618)
		(width 0.16)
		(layer "B.Cu")
		(net 49)
	)
	(arc
		(start 75.744838 115.821654)
		(mid 75.815133 115.991359)
		(end 75.744837 116.161066)
		(width 0.16)
		(layer "B.Cu")
		(net 49)
	)
	(arc
		(start 71.115 128.817893)
		(mid 71.15306 129.009235)
		(end 71.261447 129.171447)
		(width 0.16)
		(layer "B.Cu")
		(net 49)
	)
	(arc
		(start 75.659985 116.245919)
		(mid 75.490279 116.316214)
		(end 75.320573 116.24592)
		(width 0.16)
		(layer "B.Cu")
		(net 49)
	)
	(arc
		(start 76.105001 114.361658)
		(mid 76.000115 114.888958)
		(end 75.701423 115.335981)
		(width 0.16)
		(layer "B.Cu")
		(net 49)
	)
	(arc
		(start 75.65 115.387404)
		(mid 75.579704 115.557111)
		(end 75.65 115.726816)
		(width 0.16)
		(layer "B.Cu")
		(net 49)
	)
	(arc
		(start 75.225736 116.151083)
		(mid 75.05603 116.080789)
		(end 74.886326 116.151082)
		(width 0.16)
		(layer "B.Cu")
		(net 49)
	)
	(via
		(at 78.225 109.95)
		(size 0.45)
		(drill 0.2)
		(layers "F.Cu" "B.Cu")
		(remove_unused_layers yes)
		(keep_end_layers yes)
		(zone_layer_connections)
		(net 50)
	)
	(segment
		(start 77.7 118.987404)
		(end 77.597896 119.089508)
		(width 0.16)
		(layer "B.Cu")
		(net 50)
	)
	(segment
		(start 75.186447 130.739045)
		(end 76.837402 132.39)
		(width 0.16)
		(layer "B.Cu")
		(net 50)
	)
	(segment
		(start 78.225 109.958032)
		(end 78.105001 110.078031)
		(width 0.16)
		(layer "B.Cu")
		(net 50)
	)
	(segment
		(start 76.837402 132.39)
		(end 77.02 132.39)
		(width 0.16)
		(layer "B.Cu")
		(net 50)
	)
	(segment
		(start 76.7 119.987404)
		(end 75.332893 121.354511)
		(width 0.16)
		(layer "B.Cu")
		(net 50)
	)
	(segment
		(start 75.04 122.061618)
		(end 75.04 130.385491)
		(width 0.16)
		(layer "B.Cu")
		(net 50)
	)
	(segment
		(start 76.83422 119.853185)
		(end 76.7 119.987404)
		(width 0.16)
		(layer "B.Cu")
		(net 50)
	)
	(segment
		(start 76.931031 119.756376)
		(end 76.83422 119.853185)
		(width 0.16)
		(layer "B.Cu")
		(net 50)
	)
	(segment
		(start 78.105001 110.078031)
		(end 78.105001 118.009664)
		(width 0.16)
		(layer "B.Cu")
		(net 50)
	)
	(segment
		(start 77.597896 119.659562)
		(end 77.501083 119.756376)
		(width 0.16)
		(layer "B.Cu")
		(net 50)
	)
	(arc
		(start 77.597896 119.089508)
		(mid 77.538864 119.232023)
		(end 77.597895 119.374536)
		(width 0.16)
		(layer "B.Cu")
		(net 50)
	)
	(arc
		(start 77.597895 119.374536)
		(mid 77.656928 119.517048)
		(end 77.597896 119.659562)
		(width 0.16)
		(layer "B.Cu")
		(net 50)
	)
	(arc
		(start 77.501083 119.756376)
		(mid 77.35857 119.815407)
		(end 77.216057 119.756376)
		(width 0.16)
		(layer "B.Cu")
		(net 50)
	)
	(arc
		(start 75.332893 121.354511)
		(mid 75.11612 121.678935)
		(end 75.04 122.061618)
		(width 0.16)
		(layer "B.Cu")
		(net 50)
	)
	(arc
		(start 78.105001 118.009664)
		(mid 77.999748 118.538805)
		(end 77.7 118.987404)
		(width 0.16)
		(layer "B.Cu")
		(net 50)
	)
	(arc
		(start 75.04 130.385491)
		(mid 75.07806 130.576833)
		(end 75.186447 130.739045)
		(width 0.16)
		(layer "B.Cu")
		(net 50)
	)
	(arc
		(start 77.216057 119.756376)
		(mid 77.073544 119.697345)
		(end 76.931031 119.756376)
		(width 0.16)
		(layer "B.Cu")
		(net 50)
	)
	(via
		(at 77.225 109.95)
		(size 0.45)
		(drill 0.2)
		(layers "F.Cu" "B.Cu")
		(remove_unused_layers yes)
		(keep_end_layers yes)
		(zone_layer_connections)
		(net 51)
	)
	(segment
		(start 73.29 120.942916)
		(end 73.29 130.372785)
		(width 0.16)
		(layer "B.Cu")
		(net 51)
	)
	(segment
		(start 72.461855 131.891855)
		(end 72.96 132.39)
		(width 0.16)
		(layer "B.Cu")
		(net 51)
	)
	(segment
		(start 72.397075 131.752443)
		(end 72.414518 131.735)
		(width 0.16)
		(layer "B.Cu")
		(net 51)
	)
	(segment
		(start 76.783848 118.081374)
		(end 76.698995 118.166228)
		(width 0.16)
		(layer "B.Cu")
		(net 51)
	)
	(segment
		(start 76.359583 118.166228)
		(end 76.175736 117.982381)
		(width 0.16)
		(layer "B.Cu")
		(net 51)
	)
	(segment
		(start 77.105001 110.069999)
		(end 77.105001 116.157431)
		(width 0.16)
		(layer "B.Cu")
		(net 51)
	)
	(segment
		(start 76.6 117.558114)
		(end 76.783848 117.741962)
		(width 0.16)
		(layer "B.Cu")
		(net 51)
	)
	(segment
		(start 75.29185 118.526851)
		(end 74.968702 118.85)
		(width 0.16)
		(layer "B.Cu")
		(net 51)
	)
	(segment
		(start 75.836324 117.982381)
		(end 75.751471 118.067232)
		(width 0.16)
		(layer "B.Cu")
		(net 51)
	)
	(segment
		(start 74.968702 118.85)
		(end 73.582893 120.235809)
		(width 0.16)
		(layer "B.Cu")
		(net 51)
	)
	(segment
		(start 75.751471 118.067232)
		(end 75.29185 118.526851)
		(width 0.16)
		(layer "B.Cu")
		(net 51)
	)
	(segment
		(start 72.414518 131.735)
		(end 72.397075 131.717557)
		(width 0.16)
		(layer "B.Cu")
		(net 51)
	)
	(segment
		(start 73.023269 131.016731)
		(end 72.461855 131.578145)
		(width 0.16)
		(layer "B.Cu")
		(net 51)
	)
	(segment
		(start 72.413313 131.820078)
		(end 72.424512 131.808878)
		(width 0.16)
		(layer "B.Cu")
		(net 51)
	)
	(segment
		(start 77.225 109.95)
		(end 77.105001 110.069999)
		(width 0.16)
		(layer "B.Cu")
		(net 51)
	)
	(segment
		(start 72.424512 131.808878)
		(end 72.402533 131.786899)
		(width 0.16)
		(layer "B.Cu")
		(net 51)
	)
	(segment
		(start 76.711659 117.107043)
		(end 76.6 117.218702)
		(width 0.16)
		(layer "B.Cu")
		(net 51)
	)
	(arc
		(start 73.29 130.372785)
		(mid 73.220679 130.721286)
		(end 73.023269 131.016731)
		(width 0.16)
		(layer "B.Cu")
		(net 51)
	)
	(arc
		(start 72.461855 131.578145)
		(mid 72.396884 131.735)
		(end 72.461855 131.891855)
		(width 0.16)
		(layer "B.Cu")
		(net 51)
	)
	(arc
		(start 76.175736 117.982381)
		(mid 76.006031 117.912085)
		(end 75.836324 117.982381)
		(width 0.16)
		(layer "B.Cu")
		(net 51)
	)
	(arc
		(start 77.105001 116.157431)
		(mid 77.002775 116.671357)
		(end 76.711659 117.107043)
		(width 0.16)
		(layer "B.Cu")
		(net 51)
	)
	(arc
		(start 76.783848 117.741962)
		(mid 76.854142 117.911669)
		(end 76.783848 118.081374)
		(width 0.16)
		(layer "B.Cu")
		(net 51)
	)
	(arc
		(start 76.698995 118.166228)
		(mid 76.52929 118.236522)
		(end 76.359583 118.166228)
		(width 0.16)
		(layer "B.Cu")
		(net 51)
	)
	(arc
		(start 76.6 117.218702)
		(mid 76.529704 117.388409)
		(end 76.6 117.558114)
		(width 0.16)
		(layer "B.Cu")
		(net 51)
	)
	(arc
		(start 73.582893 120.235809)
		(mid 73.36612 120.560233)
		(end 73.29 120.942916)
		(width 0.16)
		(layer "B.Cu")
		(net 51)
	)
	(segment
		(start 76.48 145.82)
		(end 78.48 145.82)
		(width 0.2)
		(layer "B.Cu")
		(net 52)
	)
	(segment
		(start 75.479998 145.82)
		(end 76.48 145.82)
		(width 0.2)
		(layer "B.Cu")
		(net 52)
	)
	(segment
		(start 78.48 145.82)
		(end 81.5 142.8)
		(width 0.2)
		(layer "B.Cu")
		(net 52)
	)
	(segment
		(start 74.480001 146.690001)
		(end 75.67 147.88)
		(width 0.2)
		(layer "B.Cu")
		(net 53)
	)
	(segment
		(start 74.480001 145.82)
		(end 74.480001 146.690001)
		(width 0.2)
		(layer "B.Cu")
		(net 53)
	)
	(segment
		(start 74.480001 145.82)
		(end 73.480002 145.82)
		(width 0.2)
		(layer "B.Cu")
		(net 53)
	)
	(segment
		(start 73.480002 145.82)
		(end 73.48 145.819998)
		(width 0.2)
		(layer "B.Cu")
		(net 53)
	)
	(segment
		(start 75.67 147.88)
		(end 81.5 147.88)
		(width 0.2)
		(layer "B.Cu")
		(net 53)
	)
	(segment
		(start 69.04 145.82)
		(end 71.48 145.82)
		(width 0.2)
		(layer "B.Cu")
		(net 54)
	)
	(segment
		(start 68.56 145.34)
		(end 66.46 145.34)
		(width 0.2)
		(layer "B.Cu")
		(net 54)
	)
	(segment
		(start 69.04 145.82)
		(end 68.56 145.34)
		(width 0.2)
		(layer "B.Cu")
		(net 54)
	)
	(segment
		(start 72.48 145.82)
		(end 71.48 145.82)
		(width 0.2)
		(layer "B.Cu")
		(net 54)
	)
	(via
		(at 79.225 109.95)
		(size 0.45)
		(drill 0.2)
		(layers "F.Cu" "B.Cu")
		(remove_unused_layers yes)
		(keep_end_layers yes)
		(zone_layer_connections)
		(net 55)
	)
	(segment
		(start 78.698508 120.788896)
		(end 77.507893 121.979511)
		(width 0.16)
		(layer "B.Cu")
		(net 55)
	)
	(segment
		(start 79.105001 112.36775)
		(end 79.105001 112.53)
		(width 0.16)
		(layer "B.Cu")
		(net 55)
	)
	(segment
		(start 77.215 122.686618)
		(end 77.215 128.817893)
		(width 0.16)
		(layer "B.Cu")
		(net 55)
	)
	(segment
		(start 77.361447 129.171447)
		(end 78.04 129.85)
		(width 0.16)
		(layer "B.Cu")
		(net 55)
	)
	(segment
		(start 79.462751 111.84775)
		(end 79.462751 112.01)
		(width 0.16)
		(layer "B.Cu")
		(net 55)
	)
	(segment
		(start 79.225 109.958032)
		(end 79.105001 110.078031)
		(width 0.16)
		(layer "B.Cu")
		(net 55)
	)
	(segment
		(start 79.105001 110.078031)
		(end 79.105001 110.45)
		(width 0.16)
		(layer "B.Cu")
		(net 55)
	)
	(segment
		(start 79.105001 112.53)
		(end 79.105001 113.4)
		(width 0.16)
		(layer "B.Cu")
		(net 55)
	)
	(segment
		(start 79.105001 111.327648)
		(end 79.105001 111.49)
		(width 0.16)
		(layer "B.Cu")
		(net 55)
	)
	(segment
		(start 79.462649 110.807648)
		(end 79.462649 110.97)
		(width 0.16)
		(layer "B.Cu")
		(net 55)
	)
	(segment
		(start 79.105001 113.4)
		(end 79.105001 119.807535)
		(width 0.16)
		(layer "B.Cu")
		(net 55)
	)
	(arc
		(start 79.462751 112.01)
		(mid 79.41036 112.136484)
		(end 79.283876 112.188875)
		(width 0.16)
		(layer "B.Cu")
		(net 55)
	)
	(arc
		(start 79.283825 110.628824)
		(mid 79.410273 110.6812)
		(end 79.462649 110.807648)
		(width 0.16)
		(layer "B.Cu")
		(net 55)
	)
	(arc
		(start 79.105001 110.45)
		(mid 79.157377 110.576448)
		(end 79.283825 110.628824)
		(width 0.16)
		(layer "B.Cu")
		(net 55)
	)
	(arc
		(start 79.462649 110.97)
		(mid 79.410273 111.096448)
		(end 79.283825 111.148824)
		(width 0.16)
		(layer "B.Cu")
		(net 55)
	)
	(arc
		(start 79.283876 111.668875)
		(mid 79.41036 111.721266)
		(end 79.462751 111.84775)
		(width 0.16)
		(layer "B.Cu")
		(net 55)
	)
	(arc
		(start 77.507893 121.979511)
		(mid 77.29112 122.303934)
		(end 77.215 122.686618)
		(width 0.16)
		(layer "B.Cu")
		(net 55)
	)
	(arc
		(start 79.283825 111.148824)
		(mid 79.157377 111.2012)
		(end 79.105001 111.327648)
		(width 0.16)
		(layer "B.Cu")
		(net 55)
	)
	(arc
		(start 79.105001 119.807535)
		(mid 78.999357 120.338644)
		(end 78.698508 120.788896)
		(width 0.16)
		(layer "B.Cu")
		(net 55)
	)
	(arc
		(start 77.215 128.817893)
		(mid 77.25306 129.009235)
		(end 77.361447 129.171447)
		(width 0.16)
		(layer "B.Cu")
		(net 55)
	)
	(arc
		(start 79.283876 112.188875)
		(mid 79.157392 112.241266)
		(end 79.105001 112.36775)
		(width 0.16)
		(layer "B.Cu")
		(net 55)
	)
	(arc
		(start 79.105001 111.49)
		(mid 79.157392 111.616484)
		(end 79.283876 111.668875)
		(width 0.16)
		(layer "B.Cu")
		(net 55)
	)
	(via
		(at 75.725 109.085)
		(size 0.45)
		(drill 0.2)
		(layers "F.Cu" "B.Cu")
		(remove_unused_layers yes)
		(keep_end_layers yes)
		(zone_layer_connections)
		(net 56)
	)
	(segment
		(start 75.725 109.093032)
		(end 75.725 114.360786)
		(width 0.16)
		(layer "B.Cu")
		(net 56)
	)
	(segment
		(start 70.588553 129.171447)
		(end 69.91 129.85)
		(width 0.16)
		(layer "B.Cu")
		(net 56)
	)
	(segment
		(start 75.432107 115.067893)
		(end 71.132241 119.367759)
		(width 0.16)
		(layer "B.Cu")
		(net 56)
	)
	(segment
		(start 70.735 120.326784)
		(end 70.735 128.817893)
		(width 0.16)
		(layer "B.Cu")
		(net 56)
	)
	(arc
		(start 71.132241 119.367759)
		(mid 70.838239 119.807763)
		(end 70.735 120.326784)
		(width 0.16)
		(layer "B.Cu")
		(net 56)
	)
	(arc
		(start 75.432107 115.067893)
		(mid 75.64888 114.74347)
		(end 75.725 114.360786)
		(width 0.16)
		(layer "B.Cu")
		(net 56)
	)
	(arc
		(start 70.735 128.817893)
		(mid 70.69694 129.009235)
		(end 70.588553 129.171447)
		(width 0.16)
		(layer "B.Cu")
		(net 56)
	)
	(via
		(at 78.725 109.085)
		(size 0.45)
		(drill 0.2)
		(layers "F.Cu" "B.Cu")
		(remove_unused_layers yes)
		(keep_end_layers yes)
		(zone_layer_connections)
		(net 57)
	)
	(segment
		(start 76.688553 129.171447)
		(end 76.01 129.85)
		(width 0.16)
		(layer "B.Cu")
		(net 57)
	)
	(segment
		(start 78.725 109.093032)
		(end 78.725 119.810786)
		(width 0.16)
		(layer "B.Cu")
		(net 57)
	)
	(segment
		(start 76.835 122.676993)
		(end 76.835 128.817893)
		(width 0.16)
		(layer "B.Cu")
		(net 57)
	)
	(segment
		(start 78.432107 120.517893)
		(end 77.232388 121.717612)
		(width 0.16)
		(layer "B.Cu")
		(net 57)
	)
	(arc
		(start 76.835 122.676993)
		(mid 76.938278 122.15778)
		(end 77.232388 121.717612)
		(width 0.16)
		(layer "B.Cu")
		(net 57)
	)
	(arc
		(start 76.835 128.817893)
		(mid 76.79694 129.009235)
		(end 76.688553 129.171447)
		(width 0.16)
		(layer "B.Cu")
		(net 57)
	)
	(arc
		(start 78.725 119.810786)
		(mid 78.64888 120.193469)
		(end 78.432107 120.517893)
		(width 0.16)
		(layer "B.Cu")
		(net 57)
	)
	(via
		(at 77.725 109.085)
		(size 0.45)
		(drill 0.2)
		(layers "F.Cu" "B.Cu")
		(remove_unused_layers yes)
		(keep_end_layers yes)
		(zone_layer_connections)
		(net 58)
	)
	(segment
		(start 77.432107 118.717893)
		(end 75.052947 121.097053)
		(width 0.16)
		(layer "B.Cu")
		(net 58)
	)
	(segment
		(start 75.488145 131.891855)
		(end 74.99 132.39)
		(width 0.16)
		(layer "B.Cu")
		(net 58)
	)
	(segment
		(start 77.725 109.093032)
		(end 77.725 118.010786)
		(width 0.16)
		(layer "B.Cu")
		(net 58)
	)
	(segment
		(start 74.66 122.045711)
		(end 74.66 130.396325)
		(width 0.16)
		(layer "B.Cu")
		(net 58)
	)
	(segment
		(start 74.910086 131.000086)
		(end 75.488145 131.578145)
		(width 0.16)
		(layer "B.Cu")
		(net 58)
	)
	(arc
		(start 75.488145 131.578145)
		(mid 75.553116 131.735)
		(end 75.488145 131.891855)
		(width 0.16)
		(layer "B.Cu")
		(net 58)
	)
	(arc
		(start 75.052947 121.097053)
		(mid 74.762124 121.532301)
		(end 74.66 122.045711)
		(width 0.16)
		(layer "B.Cu")
		(net 58)
	)
	(arc
		(start 77.432107 118.717893)
		(mid 77.64888 118.39347)
		(end 77.725 118.010786)
		(width 0.16)
		(layer "B.Cu")
		(net 58)
	)
	(arc
		(start 74.66 130.396325)
		(mid 74.724995 130.723078)
		(end 74.910086 131.000086)
		(width 0.16)
		(layer "B.Cu")
		(net 58)
	)
	(via
		(at 83.725 109.085)
		(size 0.45)
		(drill 0.2)
		(layers "F.Cu" "B.Cu")
		(remove_unused_layers yes)
		(keep_end_layers yes)
		(zone_layer_connections)
		(net 59)
	)
	(segment
		(start 84.135158 112.30386)
		(end 98.542107 126.710809)
		(width 0.16)
		(layer "B.Cu")
		(net 59)
	)
	(segment
		(start 98.688553 129.171447)
		(end 98.01 129.85)
		(width 0.16)
		(layer "B.Cu")
		(net 59)
	)
	(segment
		(start 83.725 109.093032)
		(end 83.725 111.313652)
		(width 0.16)
		(layer "B.Cu")
		(net 59)
	)
	(segment
		(start 98.835 127.417916)
		(end 98.835 128.817893)
		(width 0.16)
		(layer "B.Cu")
		(net 59)
	)
	(arc
		(start 98.688553 129.171447)
		(mid 98.79694 129.009235)
		(end 98.835 128.817893)
		(width 0.16)
		(layer "B.Cu")
		(net 59)
	)
	(arc
		(start 83.725 111.313652)
		(mid 83.831597 111.849549)
		(end 84.135158 112.30386)
		(width 0.16)
		(layer "B.Cu")
		(net 59)
	)
	(arc
		(start 98.542107 126.710809)
		(mid 98.75888 127.035232)
		(end 98.835 127.417916)
		(width 0.16)
		(layer "B.Cu")
		(net 59)
	)
	(via
		(at 83.225 109.95)
		(size 0.45)
		(drill 0.2)
		(layers "F.Cu" "B.Cu")
		(remove_unused_layers yes)
		(keep_end_layers yes)
		(zone_layer_connections)
		(net 60)
	)
	(segment
		(start 83.397894 113.379192)
		(end 83.528231 113.509529)
		(width 0.16)
		(layer "B.Cu")
		(net 60)
	)
	(segment
		(start 84.050074 114.031372)
		(end 84.108058 114.089356)
		(width 0.16)
		(layer "B.Cu")
		(net 60)
	)
	(segment
		(start 84.018483 113.48314)
		(end 84.076465 113.541122)
		(width 0.16)
		(layer "B.Cu")
		(net 60)
	)
	(segment
		(start 98.837402 132.39)
		(end 99.02 132.39)
		(width 0.16)
		(layer "B.Cu")
		(net 60)
	)
	(segment
		(start 83.225 109.958032)
		(end 83.105001 110.078031)
		(width 0.16)
		(layer "B.Cu")
		(net 60)
	)
	(segment
		(start 83.105001 110.078031)
		(end 83.105001 112.672085)
		(width 0.16)
		(layer "B.Cu")
		(net 60)
	)
	(segment
		(start 97.04 127.598596)
		(end 97.04 130.385491)
		(width 0.16)
		(layer "B.Cu")
		(net 60)
	)
	(segment
		(start 84.108058 114.089356)
		(end 84.871631 114.852929)
		(width 0.16)
		(layer "B.Cu")
		(net 60)
	)
	(segment
		(start 83.760163 113.50953)
		(end 83.786551 113.483139)
		(width 0.16)
		(layer "B.Cu")
		(net 60)
	)
	(segment
		(start 84.871631 114.852929)
		(end 96.631789 126.613087)
		(width 0.16)
		(layer "B.Cu")
		(net 60)
	)
	(segment
		(start 97.186447 130.739045)
		(end 98.837402 132.39)
		(width 0.16)
		(layer "B.Cu")
		(net 60)
	)
	(segment
		(start 84.076464 113.773052)
		(end 84.050075 113.799442)
		(width 0.16)
		(layer "B.Cu")
		(net 60)
	)
	(arc
		(start 84.076465 113.541122)
		(mid 84.124499 113.657088)
		(end 84.076464 113.773052)
		(width 0.16)
		(layer "B.Cu")
		(net 60)
	)
	(arc
		(start 83.105001 112.672085)
		(mid 83.181121 113.054769)
		(end 83.397894 113.379192)
		(width 0.16)
		(layer "B.Cu")
		(net 60)
	)
	(arc
		(start 83.786551 113.483139)
		(mid 83.902517 113.435106)
		(end 84.018483 113.48314)
		(width 0.16)
		(layer "B.Cu")
		(net 60)
	)
	(arc
		(start 96.631789 126.613087)
		(mid 96.93391 127.065242)
		(end 97.04 127.598596)
		(width 0.16)
		(layer "B.Cu")
		(net 60)
	)
	(arc
		(start 84.050075 113.799442)
		(mid 84.00204 113.915406)
		(end 84.050074 114.031372)
		(width 0.16)
		(layer "B.Cu")
		(net 60)
	)
	(arc
		(start 97.04 130.385491)
		(mid 97.07806 130.576833)
		(end 97.186447 130.739045)
		(width 0.16)
		(layer "B.Cu")
		(net 60)
	)
	(arc
		(start 83.528231 113.509529)
		(mid 83.644197 113.557563)
		(end 83.760163 113.50953)
		(width 0.16)
		(layer "B.Cu")
		(net 60)
	)
	(segment
		(start 97.479998 145.82)
		(end 98.48 145.82)
		(width 0.2)
		(layer "B.Cu")
		(net 61)
	)
	(segment
		(start 98.48 145.82)
		(end 100.48 145.82)
		(width 0.2)
		(layer "B.Cu")
		(net 61)
	)
	(segment
		(start 100.48 145.82)
		(end 103.5 142.8)
		(width 0.2)
		(layer "B.Cu")
		(net 61)
	)
	(via
		(at 82.725 109.085)
		(size 0.45)
		(drill 0.2)
		(layers "F.Cu" "B.Cu")
		(remove_unused_layers yes)
		(keep_end_layers yes)
		(zone_layer_connections)
		(net 62)
	)
	(segment
		(start 82.725 109.093032)
		(end 82.725 112.672843)
		(width 0.16)
		(layer "B.Cu")
		(net 62)
	)
	(segment
		(start 97.488145 131.891855)
		(end 96.99 132.39)
		(width 0.16)
		(layer "B.Cu")
		(net 62)
	)
	(segment
		(start 96.90975 130.99975)
		(end 97.488145 131.578145)
		(width 0.16)
		(layer "B.Cu")
		(net 62)
	)
	(segment
		(start 83.128658 113.64736)
		(end 96.367107 126.885809)
		(width 0.16)
		(layer "B.Cu")
		(net 62)
	)
	(segment
		(start 96.66 127.592916)
		(end 96.66 130.3968)
		(width 0.16)
		(layer "B.Cu")
		(net 62)
	)
	(arc
		(start 97.488145 131.578145)
		(mid 97.553116 131.735)
		(end 97.488145 131.891855)
		(width 0.16)
		(layer "B.Cu")
		(net 62)
	)
	(arc
		(start 96.66 130.3968)
		(mid 96.724908 130.723114)
		(end 96.90975 130.99975)
		(width 0.16)
		(layer "B.Cu")
		(net 62)
	)
	(arc
		(start 96.367107 126.885809)
		(mid 96.58388 127.210232)
		(end 96.66 127.592916)
		(width 0.16)
		(layer "B.Cu")
		(net 62)
	)
	(arc
		(start 83.128658 113.64736)
		(mid 82.829907 113.200248)
		(end 82.725 112.672843)
		(width 0.16)
		(layer "B.Cu")
		(net 62)
	)
	(via
		(at 82.225 109.95)
		(size 0.45)
		(drill 0.2)
		(layers "F.Cu" "B.Cu")
		(remove_unused_layers yes)
		(keep_end_layers yes)
		(zone_layer_connections)
		(net 63)
	)
	(segment
		(start 95.29 127.855883)
		(end 95.29 130.394498)
		(width 0.16)
		(layer "B.Cu")
		(net 63)
	)
	(segment
		(start 95.038622 131.001378)
		(end 94.461855 131.578145)
		(width 0.16)
		(layer "B.Cu")
		(net 63)
	)
	(segment
		(start 82.731932 114.481299)
		(end 82.737878 114.47535)
		(width 0.16)
		(layer "B.Cu")
		(net 63)
	)
	(segment
		(start 82.397894 114.379192)
		(end 82.5 114.481298)
		(width 0.16)
		(layer "B.Cu")
		(net 63)
	)
	(segment
		(start 84.129428 115.635041)
		(end 84.18741 115.693023)
		(width 0.16)
		(layer "B.Cu")
		(net 63)
	)
	(segment
		(start 83.027791 114.765263)
		(end 83.021844 114.771211)
		(width 0.16)
		(layer "B.Cu")
		(net 63)
	)
	(segment
		(start 83.891586 115.640953)
		(end 83.897496 115.63504)
		(width 0.16)
		(layer "B.Cu")
		(net 63)
	)
	(segment
		(start 83.311759 115.061126)
		(end 83.317705 115.055177)
		(width 0.16)
		(layer "B.Cu")
		(net 63)
	)
	(segment
		(start 83.549637 115.055178)
		(end 83.607619 115.11316)
		(width 0.16)
		(layer "B.Cu")
		(net 63)
	)
	(segment
		(start 84.239481 116.220779)
		(end 85.35 117.331298)
		(width 0.16)
		(layer "B.Cu")
		(net 63)
	)
	(segment
		(start 82.105001 110.078031)
		(end 82.105001 113.672085)
		(width 0.16)
		(layer "B.Cu")
		(net 63)
	)
	(segment
		(start 82.96981 114.475351)
		(end 83.027792 114.533333)
		(width 0.16)
		(layer "B.Cu")
		(net 63)
	)
	(segment
		(start 83.021843 115.003141)
		(end 83.079827 115.061125)
		(width 0.16)
		(layer "B.Cu")
		(net 63)
	)
	(segment
		(start 84.181497 116.162795)
		(end 84.239481 116.220779)
		(width 0.16)
		(layer "B.Cu")
		(net 63)
	)
	(segment
		(start 82.225 109.958032)
		(end 82.105001 110.078031)
		(width 0.16)
		(layer "B.Cu")
		(net 63)
	)
	(segment
		(start 84.187409 115.924953)
		(end 84.181498 115.930865)
		(width 0.16)
		(layer "B.Cu")
		(net 63)
	)
	(segment
		(start 85.35 117.331298)
		(end 94.876636 126.857934)
		(width 0.16)
		(layer "B.Cu")
		(net 63)
	)
	(segment
		(start 83.607618 115.34509)
		(end 83.601671 115.351038)
		(width 0.16)
		(layer "B.Cu")
		(net 63)
	)
	(segment
		(start 94.461855 131.891855)
		(end 94.96 132.39)
		(width 0.16)
		(layer "B.Cu")
		(net 63)
	)
	(segment
		(start 83.60167 115.582968)
		(end 83.659654 115.640952)
		(width 0.16)
		(layer "B.Cu")
		(net 63)
	)
	(arc
		(start 83.897496 115.63504)
		(mid 84.013462 115.587007)
		(end 84.129428 115.635041)
		(width 0.16)
		(layer "B.Cu")
		(net 63)
	)
	(arc
		(start 82.105001 113.672085)
		(mid 82.181121 114.054768)
		(end 82.397894 114.379192)
		(width 0.16)
		(layer "B.Cu")
		(net 63)
	)
	(arc
		(start 83.317705 115.055177)
		(mid 83.433671 115.007144)
		(end 83.549637 115.055178)
		(width 0.16)
		(layer "B.Cu")
		(net 63)
	)
	(arc
		(start 84.18741 115.693023)
		(mid 84.235444 115.808989)
		(end 84.187409 115.924953)
		(width 0.16)
		(layer "B.Cu")
		(net 63)
	)
	(arc
		(start 84.181498 115.930865)
		(mid 84.133463 116.046829)
		(end 84.181497 116.162795)
		(width 0.16)
		(layer "B.Cu")
		(net 63)
	)
	(arc
		(start 94.876636 126.857934)
		(mid 95.18257 127.315797)
		(end 95.29 127.855883)
		(width 0.16)
		(layer "B.Cu")
		(net 63)
	)
	(arc
		(start 83.027792 114.533333)
		(mid 83.075826 114.649299)
		(end 83.027791 114.765263)
		(width 0.16)
		(layer "B.Cu")
		(net 63)
	)
	(arc
		(start 83.601671 115.351038)
		(mid 83.553636 115.467002)
		(end 83.60167 115.582968)
		(width 0.16)
		(layer "B.Cu")
		(net 63)
	)
	(arc
		(start 83.079827 115.061125)
		(mid 83.195793 115.109159)
		(end 83.311759 115.061126)
		(width 0.16)
		(layer "B.Cu")
		(net 63)
	)
	(arc
		(start 83.021844 114.771211)
		(mid 82.973809 114.887175)
		(end 83.021843 115.003141)
		(width 0.16)
		(layer "B.Cu")
		(net 63)
	)
	(arc
		(start 83.659654 115.640952)
		(mid 83.77562 115.688986)
		(end 83.891586 115.640953)
		(width 0.16)
		(layer "B.Cu")
		(net 63)
	)
	(arc
		(start 82.737878 114.47535)
		(mid 82.853844 114.427317)
		(end 82.96981 114.475351)
		(width 0.16)
		(layer "B.Cu")
		(net 63)
	)
	(arc
		(start 83.607619 115.11316)
		(mid 83.655653 115.229126)
		(end 83.607618 115.34509)
		(width 0.16)
		(layer "B.Cu")
		(net 63)
	)
	(arc
		(start 94.461855 131.578145)
		(mid 94.396884 131.735)
		(end 94.461855 131.891855)
		(width 0.16)
		(layer "B.Cu")
		(net 63)
	)
	(arc
		(start 82.5 114.481298)
		(mid 82.615966 114.529332)
		(end 82.731932 114.481299)
		(width 0.16)
		(layer "B.Cu")
		(net 63)
	)
	(arc
		(start 95.29 130.394498)
		(mid 95.224669 130.722939)
		(end 95.038622 131.001378)
		(width 0.16)
		(layer "B.Cu")
		(net 63)
	)
	(segment
		(start 103.5 147.88)
		(end 97.67 147.88)
		(width 0.2)
		(layer "B.Cu")
		(net 64)
	)
	(segment
		(start 96.48 145.82)
		(end 95.480002 145.82)
		(width 0.2)
		(layer "B.Cu")
		(net 64)
	)
	(segment
		(start 96.48 146.69)
		(end 96.48 145.82)
		(width 0.2)
		(layer "B.Cu")
		(net 64)
	)
	(segment
		(start 95.480002 145.82)
		(end 95.48 145.819998)
		(width 0.2)
		(layer "B.Cu")
		(net 64)
	)
	(segment
		(start 97.67 147.88)
		(end 96.48 146.69)
		(width 0.2)
		(layer "B.Cu")
		(net 64)
	)
	(via
		(at 81.725 109.085)
		(size 0.45)
		(drill 0.2)
		(layers "F.Cu" "B.Cu")
		(remove_unused_layers yes)
		(keep_end_layers yes)
		(zone_layer_connections)
		(net 65)
	)
	(segment
		(start 81.725 109.093032)
		(end 81.725 113.67274)
		(width 0.16)
		(layer "B.Cu")
		(net 65)
	)
	(segment
		(start 82.128731 114.647433)
		(end 94.617107 127.135809)
		(width 0.16)
		(layer "B.Cu")
		(net 65)
	)
	(segment
		(start 93.112598 132.39)
		(end 92.93 132.39)
		(width 0.16)
		(layer "B.Cu")
		(net 65)
	)
	(segment
		(start 94.91 127.842916)
		(end 94.91 130.385491)
		(width 0.16)
		(layer "B.Cu")
		(net 65)
	)
	(segment
		(start 94.763553 130.739045)
		(end 93.112598 132.39)
		(width 0.16)
		(layer "B.Cu")
		(net 65)
	)
	(arc
		(start 94.763553 130.739045)
		(mid 94.87194 130.576833)
		(end 94.91 130.385491)
		(width 0.16)
		(layer "B.Cu")
		(net 65)
	)
	(arc
		(start 81.725 113.67274)
		(mid 81.829926 114.20024)
		(end 82.128731 114.647433)
		(width 0.16)
		(layer "B.Cu")
		(net 65)
	)
	(arc
		(start 94.617107 127.135809)
		(mid 94.83388 127.460232)
		(end 94.91 127.842916)
		(width 0.16)
		(layer "B.Cu")
		(net 65)
	)
	(segment
		(start 88.46 145.34)
		(end 90.56 145.34)
		(width 0.2)
		(layer "B.Cu")
		(net 66)
	)
	(segment
		(start 90.56 145.34)
		(end 91.04 145.82)
		(width 0.2)
		(layer "B.Cu")
		(net 66)
	)
	(segment
		(start 91.04 145.82)
		(end 93.48 145.82)
		(width 0.2)
		(layer "B.Cu")
		(net 66)
	)
	(segment
		(start 94.48 145.82)
		(end 93.48 145.82)
		(width 0.2)
		(layer "B.Cu")
		(net 66)
	)
	(via
		(at 80.725 109.085)
		(size 0.45)
		(drill 0.2)
		(layers "F.Cu" "B.Cu")
		(remove_unused_layers yes)
		(keep_end_layers yes)
		(zone_layer_connections)
		(net 67)
	)
	(segment
		(start 80.725 115.486816)
		(end 80.725 109.093032)
		(width 0.16)
		(layer "B.Cu")
		(net 67)
	)
	(segment
		(start 92.735 128.817893)
		(end 92.735 128.467916)
		(width 0.16)
		(layer "B.Cu")
		(net 67)
	)
	(segment
		(start 91.91 129.85)
		(end 92.588554 129.171446)
		(width 0.16)
		(layer "B.Cu")
		(net 67)
	)
	(segment
		(start 92.442107 127.760809)
		(end 81.118778 116.43748)
		(width 0.16)
		(layer "B.Cu")
		(net 67)
	)
	(arc
		(start 81.118778 116.43748)
		(mid 80.82734 116.001312)
		(end 80.725 115.486816)
		(width 0.16)
		(layer "B.Cu")
		(net 67)
	)
	(arc
		(start 92.735 128.817893)
		(mid 92.69694 129.009234)
		(end 92.588554 129.171446)
		(width 0.16)
		(layer "B.Cu")
		(net 67)
	)
	(arc
		(start 92.442107 127.760809)
		(mid 92.65888 128.085232)
		(end 92.735 128.467916)
		(width 0.16)
		(layer "B.Cu")
		(net 67)
	)
	(via
		(at 81.225 109.95)
		(size 0.45)
		(drill 0.2)
		(layers "F.Cu" "B.Cu")
		(remove_unused_layers yes)
		(keep_end_layers yes)
		(zone_layer_connections)
		(net 68)
	)
	(segment
		(start 81.105001 110.078031)
		(end 81.105001 115.472085)
		(width 0.16)
		(layer "B.Cu")
		(net 68)
	)
	(segment
		(start 93.261446 129.171446)
		(end 93.94 129.85)
		(width 0.16)
		(layer "B.Cu")
		(net 68)
	)
	(segment
		(start 81.225 109.958032)
		(end 81.105001 110.078031)
		(width 0.16)
		(layer "B.Cu")
		(net 68)
	)
	(segment
		(start 82.182377 116.963676)
		(end 82.26723 117.048528)
		(width 0.16)
		(layer "B.Cu")
		(net 68)
	)
	(segment
		(start 84.173704 118.955002)
		(end 92.730477 127.511775)
		(width 0.16)
		(layer "B.Cu")
		(net 68)
	)
	(segment
		(start 81.397894 116.179192)
		(end 81.418702 116.2)
		(width 0.16)
		(layer "B.Cu")
		(net 68)
	)
	(segment
		(start 82.26723 117.048528)
		(end 84.173704 118.955002)
		(width 0.16)
		(layer "B.Cu")
		(net 68)
	)
	(segment
		(start 82.276408 116.530232)
		(end 82.182377 116.624264)
		(width 0.16)
		(layer "B.Cu")
		(net 68)
	)
	(segment
		(start 82.191556 116.105968)
		(end 82.276408 116.19082)
		(width 0.16)
		(layer "B.Cu")
		(net 68)
	)
	(segment
		(start 81.758114 116.200001)
		(end 81.852144 116.105968)
		(width 0.16)
		(layer "B.Cu")
		(net 68)
	)
	(segment
		(start 93.115 128.440096)
		(end 93.115 128.817893)
		(width 0.16)
		(layer "B.Cu")
		(net 68)
	)
	(arc
		(start 81.852144 116.105968)
		(mid 82.021851 116.035674)
		(end 82.191556 116.105968)
		(width 0.16)
		(layer "B.Cu")
		(net 68)
	)
	(arc
		(start 93.115 128.817893)
		(mid 93.15306 129.009234)
		(end 93.261446 129.171446)
		(width 0.16)
		(layer "B.Cu")
		(net 68)
	)
	(arc
		(start 82.182377 116.624264)
		(mid 82.112081 116.793969)
		(end 82.182377 116.963676)
		(width 0.16)
		(layer "B.Cu")
		(net 68)
	)
	(arc
		(start 92.730477 127.511775)
		(mid 93.015066 127.937692)
		(end 93.115 128.440096)
		(width 0.16)
		(layer "B.Cu")
		(net 68)
	)
	(arc
		(start 81.418702 116.2)
		(mid 81.588408 116.270294)
		(end 81.758114 116.200001)
		(width 0.16)
		(layer "B.Cu")
		(net 68)
	)
	(arc
		(start 82.276408 116.19082)
		(mid 82.346704 116.360527)
		(end 82.276408 116.530232)
		(width 0.16)
		(layer "B.Cu")
		(net 68)
	)
	(arc
		(start 81.105001 115.472085)
		(mid 81.181121 115.854768)
		(end 81.397894 116.179192)
		(width 0.16)
		(layer "B.Cu")
		(net 68)
	)
	(via
		(at 84.225 109.95)
		(size 0.45)
		(drill 0.2)
		(layers "F.Cu" "B.Cu")
		(remove_unused_layers yes)
		(keep_end_layers yes)
		(zone_layer_connections)
		(net 69)
	)
	(segment
		(start 84.724172 112.05)
		(end 84.837277 111.936896)
		(width 0.16)
		(layer "B.Cu")
		(net 69)
	)
	(segment
		(start 84.105001 110.078031)
		(end 84.105001 111.322085)
		(width 0.16)
		(layer "B.Cu")
		(net 69)
	)
	(segment
		(start 85.182377 112.813675)
		(end 85.418702 113.05)
		(width 0.16)
		(layer "B.Cu")
		(net 69)
	)
	(segment
		(start 85.142747 111.936896)
		(end 85.219114 112.013263)
		(width 0.16)
		(layer "B.Cu")
		(net 69)
	)
	(segment
		(start 84.397894 112.029192)
		(end 84.418702 112.05)
		(width 0.16)
		(layer "B.Cu")
		(net 69)
	)
	(segment
		(start 99.215 127.405474)
		(end 99.215 128.817893)
		(width 0.16)
		(layer "B.Cu")
		(net 69)
	)
	(segment
		(start 85.418702 113.05)
		(end 98.819603 126.450901)
		(width 0.16)
		(layer "B.Cu")
		(net 69)
	)
	(segment
		(start 99.361447 129.171447)
		(end 100.04 129.85)
		(width 0.16)
		(layer "B.Cu")
		(net 69)
	)
	(segment
		(start 84.225 109.958032)
		(end 84.105001 110.078031)
		(width 0.16)
		(layer "B.Cu")
		(net 69)
	)
	(segment
		(start 85.219114 112.318733)
		(end 85.106008 112.431836)
		(width 0.16)
		(layer "B.Cu")
		(net 69)
	)
	(segment
		(start 85.106008 112.737306)
		(end 85.182377 112.813675)
		(width 0.16)
		(layer "B.Cu")
		(net 69)
	)
	(arc
		(start 98.819603 126.450901)
		(mid 99.11224 126.888863)
		(end 99.215 127.405474)
		(width 0.16)
		(layer "B.Cu")
		(net 69)
	)
	(arc
		(start 84.418702 112.05)
		(mid 84.571437 112.113265)
		(end 84.724172 112.05)
		(width 0.16)
		(layer "B.Cu")
		(net 69)
	)
	(arc
		(start 85.106008 112.431836)
		(mid 85.042743 112.584571)
		(end 85.106008 112.737306)
		(width 0.16)
		(layer "B.Cu")
		(net 69)
	)
	(arc
		(start 99.215 128.817893)
		(mid 99.25306 129.009235)
		(end 99.361447 129.171447)
		(width 0.16)
		(layer "B.Cu")
		(net 69)
	)
	(arc
		(start 85.219114 112.013263)
		(mid 85.282379 112.165998)
		(end 85.219114 112.318733)
		(width 0.16)
		(layer "B.Cu")
		(net 69)
	)
	(arc
		(start 84.837277 111.936896)
		(mid 84.990012 111.873631)
		(end 85.142747 111.936896)
		(width 0.16)
		(layer "B.Cu")
		(net 69)
	)
	(arc
		(start 84.105001 111.322085)
		(mid 84.181121 111.704768)
		(end 84.397894 112.029192)
		(width 0.16)
		(layer "B.Cu")
		(net 69)
	)
	(segment
		(start 62.26 61.57)
		(end 62.71 62.02)
		(width 0.15)
		(layer "F.Cu")
		(net 70)
	)
	(segment
		(start 62.71 62.02)
		(end 63.313 62.02)
		(width 0.15)
		(layer "F.Cu")
		(net 70)
	)
	(segment
		(start 62.26 53.347)
		(end 62.26 61.57)
		(width 0.15)
		(layer "F.Cu")
		(net 70)
	)
	(segment
		(start 70.785 87.285)
		(end 70.785 86.252146)
		(width 0.15)
		(layer "B.Cu")
		(net 71)
	)
	(segment
		(start 71.92 88.42)
		(end 70.785 87.285)
		(width 0.15)
		(layer "B.Cu")
		(net 71)
	)
	(segment
		(start 73.75 88.42)
		(end 71.92 88.42)
		(width 0.15)
		(layer "B.Cu")
		(net 71)
	)
	(segment
		(start 69.517 92.983)
		(end 69.517 93.453146)
		(width 0.15)
		(layer "B.Cu")
		(net 72)
	)
	(segment
		(start 71.22 91.28)
		(end 69.517 92.983)
		(width 0.15)
		(layer "B.Cu")
		(net 72)
	)
	(segment
		(start 73.75 91.28)
		(end 71.22 91.28)
		(width 0.15)
		(layer "B.Cu")
		(net 72)
	)
	(segment
		(start 98.869999 109.1)
		(end 98.869999 110.1)
		(width 0.16)
		(layer "F.Cu")
		(net 73)
	)
	(segment
		(start 97.904999 109.1)
		(end 97.879999 109.1)
		(width 0.16)
		(layer "F.Cu")
		(net 73)
	)
	(segment
		(start 98.844999 109.1)
		(end 98.534999 108.79)
		(width 0.16)
		(layer "F.Cu")
		(net 73)
	)
	(segment
		(start 98.869999 109.1)
		(end 98.844999 109.1)
		(width 0.16)
		(layer "F.Cu")
		(net 73)
	)
	(segment
		(start 98.534999 108.79)
		(end 98.214999 108.79)
		(width 0.16)
		(layer "F.Cu")
		(net 73)
	)
	(segment
		(start 98.214999 108.79)
		(end 97.904999 109.1)
		(width 0.16)
		(layer "F.Cu")
		(net 73)
	)
	(segment
		(start 108.08 112.5)
		(end 108.08 113.57)
		(width 0.15)
		(layer "F.Cu")
		(net 74)
	)
	(segment
		(start 108.08 113.57)
		(end 106.79 114.86)
		(width 0.15)
		(layer "F.Cu")
		(net 74)
	)
	(segment
		(start 103.22 113.569999)
		(end 103.550001 113.9)
		(width 0.5)
		(layer "F.Cu")
		(net 74)
	)
	(segment
		(start 103.600001 114.725001)
		(end 103.600001 113.9)
		(width 0.15)
		(layer "F.Cu")
		(net 74)
	)
	(segment
		(start 103.735 114.86)
		(end 103.600001 114.725001)
		(width 0.15)
		(layer "F.Cu")
		(net 74)
	)
	(segment
		(start 103.550001 113.9)
		(end 103.600001 113.9)
		(width 0.5)
		(layer "F.Cu")
		(net 74)
	)
	(segment
		(start 103.4 110.505)
		(end 103.22 110.685)
		(width 0.5)
		(layer "F.Cu")
		(net 74)
	)
	(segment
		(start 106.79 114.86)
		(end 103.735 114.86)
		(width 0.15)
		(layer "F.Cu")
		(net 74)
	)
	(segment
		(start 103.22 110.685)
		(end 103.22 113.569999)
		(width 0.5)
		(layer "F.Cu")
		(net 74)
	)
	(segment
		(start 77.55 58.9)
		(end 76.7 58.05)
		(width 0.15)
		(layer "F.Cu")
		(net 75)
	)
	(segment
		(start 79.48 58.9)
		(end 77.55 58.9)
		(width 0.15)
		(layer "F.Cu")
		(net 75)
	)
	(segment
		(start 76.7 57.602)
		(end 76.7 53.35)
		(width 0.15)
		(layer "F.Cu")
		(net 75)
	)
	(segment
		(start 76.7 58.05)
		(end 76.7 57.602)
		(width 0.15)
		(layer "F.Cu")
		(net 75)
	)
	(segment
		(start 71.02 107.37)
		(end 71.92 107.37)
		(width 0.2)
		(layer "F.Cu")
		(net 76)
	)
	(segment
		(start 70 107.94)
		(end 70 107.0005)
		(width 0.2)
		(layer "F.Cu")
		(net 76)
	)
	(segment
		(start 70 107.94)
		(end 70 107.93)
		(width 0.2)
		(layer "F.Cu")
		(net 76)
	)
	(segment
		(start 70.48 107.91)
		(end 71.02 107.37)
		(width 0.2)
		(layer "F.Cu")
		(net 76)
	)
	(segment
		(start 70 107.0005)
		(end 69.8945 106.895)
		(width 0.2)
		(layer "F.Cu")
		(net 76)
	)
	(segment
		(start 70 107.93)
		(end 70.02 107.91)
		(width 0.2)
		(layer "F.Cu")
		(net 76)
	)
	(segment
		(start 70.02 107.91)
		(end 70.48 107.91)
		(width 0.2)
		(layer "F.Cu")
		(net 76)
	)
	(segment
		(start 71.92 107.37)
		(end 71.94 107.35)
		(width 0.2)
		(layer "F.Cu")
		(net 76)
	)
	(segment
		(start 68.8945 105.545)
		(end 68.8945 105.69)
		(width 0.2)
		(layer "F.Cu")
		(net 77)
	)
	(segment
		(start 71.92 106.37)
		(end 71.94 106.35)
		(width 0.2)
		(layer "F.Cu")
		(net 77)
	)
	(segment
		(start 68.8945 105.69)
		(end 69.4145 106.21)
		(width 0.2)
		(layer "F.Cu")
		(net 77)
	)
	(segment
		(start 69.4145 106.21)
		(end 70.3555 106.21)
		(width 0.2)
		(layer "F.Cu")
		(net 77)
	)
	(segment
		(start 70.3555 106.21)
		(end 70.5355 106.39)
		(width 0.2)
		(layer "F.Cu")
		(net 77)
	)
	(segment
		(start 70.96 106.37)
		(end 71.92 106.37)
		(width 0.2)
		(layer "F.Cu")
		(net 77)
	)
	(segment
		(start 70.5355 106.39)
		(end 70.9445 106.39)
		(width 0.2)
		(layer "F.Cu")
		(net 77)
	)
	(segment
		(start 80.83 84.15)
		(end 82.079 85.399)
		(width 0.15)
		(layer "F.Cu")
		(net 78)
	)
	(segment
		(start 82.73 82.15)
		(end 82.730001 83.15)
		(width 0.5)
		(layer "F.Cu")
		(net 78)
	)
	(segment
		(start 82.73 85.32)
		(end 82.651 85.399)
		(width 0.5)
		(layer "F.Cu")
		(net 78)
	)
	(segment
		(start 82.730001 83.15)
		(end 82.73 84.15)
		(width 0.5)
		(layer "F.Cu")
		(net 78)
	)
	(segment
		(start 82.079 85.399)
		(end 82.651 85.399)
		(width 0.15)
		(layer "F.Cu")
		(net 78)
	)
	(segment
		(start 82.73 84.15)
		(end 82.73 85.32)
		(width 0.5)
		(layer "F.Cu")
		(net 78)
	)
	(segment
		(start 53.48 77.52)
		(end 52.3 78.7)
		(width 0.15)
		(layer "F.Cu")
		(net 79)
	)
	(segment
		(start 53.5 77.52)
		(end 53.48 77.52)
		(width 0.15)
		(layer "F.Cu")
		(net 79)
	)
	(segment
		(start 97.6945 55.144501)
		(end 97.6945 54.50346)
		(width 0.202)
		(layer "F.Cu")
		(net 80)
	)
	(segment
		(start 97.75 55.200001)
		(end 97.6945 55.144501)
		(width 0.202)
		(layer "F.Cu")
		(net 80)
	)
	(segment
		(start 97.75 55.500001)
		(end 97.75 55.200001)
		(width 0.202)
		(layer "F.Cu")
		(net 80)
	)
	(segment
		(start 97.6945 54.50346)
		(end 97.8185 54.37946)
		(width 0.202)
		(layer "F.Cu")
		(net 80)
	)
	(via
		(at 97.8185 54.37946)
		(size 0.45)
		(drill 0.2)
		(layers "F.Cu" "B.Cu")
		(remove_unused_layers yes)
		(keep_end_layers yes)
		(zone_layer_connections)
		(net 80)
	)
	(via
		(at 87.725 91.785)
		(size 0.45)
		(drill 0.2)
		(layers "F.Cu" "B.Cu")
		(remove_unused_layers yes)
		(keep_end_layers yes)
		(zone_layer_connections)
		(net 80)
	)
	(segment
		(start 97.6945 54.50346)
		(end 97.6945 55.443161)
		(width 0.202)
		(layer "B.Cu")
		(net 80)
	)
	(segment
		(start 97.749999 55.49866)
		(end 97.749999 56.27066)
		(width 0.202)
		(layer "B.Cu")
		(net 80)
	)
	(segment
		(start 95.1 76.718862)
		(end 95.1 61.238493)
		(width 0.202)
		(layer "B.Cu")
		(net 80)
	)
	(segment
		(start 97.692499 56.738661)
		(end 97.747999 56.683161)
		(width 0.202)
		(layer "B.Cu")
		(net 80)
	)
	(segment
		(start 88.370287 84.429779)
		(end 94.406184 78.393882)
		(width 0.202)
		(layer "B.Cu")
		(net 80)
	)
	(segment
		(start 87.4195 91.272393)
		(end 87.4195 90.99231)
		(width 0.202)
		(layer "B.Cu")
		(net 80)
	)
	(segment
		(start 87.725 91.785)
		(end 87.565946 91.625946)
		(width 0.202)
		(layer "B.Cu")
		(net 80)
	)
	(segment
		(start 87.7845 90.111212)
		(end 87.7845 85.843993)
		(width 0.202)
		(layer "B.Cu")
		(net 80)
	)
	(segment
		(start 97.8185 54.37946)
		(end 97.6945 54.50346)
		(width 0.202)
		(layer "B.Cu")
		(net 80)
	)
	(segment
		(start 97.6945 55.443161)
		(end 97.749999 55.49866)
		(width 0.202)
		(layer "B.Cu")
		(net 80)
	)
	(segment
		(start 95.685787 59.824279)
		(end 97.292206 58.21786)
		(width 0.202)
		(layer "B.Cu")
		(net 80)
	)
	(segment
		(start 97.747999 56.683161)
		(end 97.747999 56.27066)
		(width 0.202)
		(layer "B.Cu")
		(net 80)
	)
	(segment
		(start 97.692499 57.251466)
		(end 97.692499 56.738661)
		(width 0.202)
		(layer "B.Cu")
		(net 80)
	)
	(arc
		(start 94.406184 78.393882)
		(mid 94.919683 77.625376)
		(end 95.1 76.718862)
		(width 0.202)
		(layer "B.Cu")
		(net 80)
	)
	(arc
		(start 87.7845 85.843993)
		(mid 87.936741 85.078626)
		(end 88.370287 84.429779)
		(width 0.202)
		(layer "B.Cu")
		(net 80)
	)
	(arc
		(start 95.1 61.238493)
		(mid 95.252241 60.473126)
		(end 95.685787 59.824279)
		(width 0.202)
		(layer "B.Cu")
		(net 80)
	)
	(arc
		(start 97.292206 58.21786)
		(mid 97.588467 57.774475)
		(end 97.692499 57.251466)
		(width 0.202)
		(layer "B.Cu")
		(net 80)
	)
	(arc
		(start 87.523264 90.741802)
		(mid 87.716622 90.452452)
		(end 87.7845 90.111212)
		(width 0.202)
		(layer "B.Cu")
		(net 80)
	)
	(arc
		(start 87.4195 90.99231)
		(mid 87.446468 90.856736)
		(end 87.523264 90.741802)
		(width 0.202)
		(layer "B.Cu")
		(net 80)
	)
	(arc
		(start 87.565946 91.625946)
		(mid 87.45756 91.463734)
		(end 87.4195 91.272393)
		(width 0.202)
		(layer "B.Cu")
		(net 80)
	)
	(via
		(at 74.480001 144.86)
		(size 0.45)
		(drill 0.2)
		(layers "F.Cu" "B.Cu")
		(remove_unused_layers yes)
		(keep_end_layers yes)
		(zone_layer_connections)
		(net 81)
	)
	(via
		(at 92.725 95.245)
		(size 0.45)
		(drill 0.2)
		(layers "F.Cu" "B.Cu")
		(remove_unused_layers yes)
		(keep_end_layers yes)
		(zone_layer_connections)
		(net 81)
	)
	(segment
		(start 91.3 96.67)
		(end 91.3 98.95)
		(width 0.15)
		(layer "In5.Cu")
		(net 81)
	)
	(segment
		(start 92.725 95.245)
		(end 91.3 96.67)
		(width 0.15)
		(layer "In5.Cu")
		(net 81)
	)
	(segment
		(start 91.79 111.32)
		(end 90.7 112.41)
		(width 0.15)
		(layer "In5.Cu")
		(net 81)
	)
	(segment
		(start 81.15 134.69)
		(end 81.15 139.95)
		(width 0.15)
		(layer "In5.Cu")
		(net 81)
	)
	(segment
		(start 91.7 103.4)
		(end 91.2 103.9)
		(width 0.15)
		(layer "In5.Cu")
		(net 81)
	)
	(segment
		(start 92.7 99.745678)
		(end 92.7 101.06)
		(width 0.15)
		(layer "In5.Cu")
		(net 81)
	)
	(segment
		(start 75.220001 145.6)
		(end 74.480001 144.86)
		(width 0.15)
		(layer "In5.Cu")
		(net 81)
	)
	(segment
		(start 91.21 102.44)
		(end 91.7 102.93)
		(width 0.15)
		(layer "In5.Cu")
		(net 81)
	)
	(segment
		(start 91.2 107.52)
		(end 91.73 108.05)
		(width 0.15)
		(layer "In5.Cu")
		(net 81)
	)
	(segment
		(start 91.73 108.34)
		(end 92.25 108.86)
		(width 0.15)
		(layer "In5.Cu")
		(net 81)
	)
	(segment
		(start 91.73 108.05)
		(end 91.73 108.34)
		(width 0.15)
		(layer "In5.Cu")
		(net 81)
	)
	(segment
		(start 78.038906 143.061094)
		(end 78.038906 144.761094)
		(width 0.15)
		(layer "In5.Cu")
		(net 81)
	)
	(segment
		(start 91.2 103.9)
		(end 91.2 107.52)
		(width 0.15)
		(layer "In5.Cu")
		(net 81)
	)
	(segment
		(start 77.2 145.6)
		(end 75.220001 145.6)
		(width 0.15)
		(layer "In5.Cu")
		(net 81)
	)
	(segment
		(start 92.338119 101.421881)
		(end 91.818119 101.421881)
		(width 0.15)
		(layer "In5.Cu")
		(net 81)
	)
	(segment
		(start 92.25 109.24)
		(end 91.79 109.7)
		(width 0.15)
		(layer "In5.Cu")
		(net 81)
	)
	(segment
		(start 91.3 98.95)
		(end 91.7 99.35)
		(width 0.15)
		(layer "In5.Cu")
		(net 81)
	)
	(segment
		(start 92.25 108.86)
		(end 92.25 109.24)
		(width 0.15)
		(layer "In5.Cu")
		(net 81)
	)
	(segment
		(start 91.21 102.03)
		(end 91.21 102.44)
		(width 0.15)
		(layer "In5.Cu")
		(net 81)
	)
	(segment
		(start 92.304322 99.35)
		(end 92.7 99.745678)
		(width 0.15)
		(layer "In5.Cu")
		(net 81)
	)
	(segment
		(start 78.038906 144.761094)
		(end 77.2 145.6)
		(width 0.15)
		(layer "In5.Cu")
		(net 81)
	)
	(segment
		(start 81.15 139.95)
		(end 78.038906 143.061094)
		(width 0.15)
		(layer "In5.Cu")
		(net 81)
	)
	(segment
		(start 90.7 112.41)
		(end 90.7 125.14)
		(width 0.15)
		(layer "In5.Cu")
		(net 81)
	)
	(segment
		(start 91.7 99.35)
		(end 92.304322 99.35)
		(width 0.15)
		(layer "In5.Cu")
		(net 81)
	)
	(segment
		(start 91.7 102.93)
		(end 91.7 103.4)
		(width 0.15)
		(layer "In5.Cu")
		(net 81)
	)
	(segment
		(start 90.7 125.14)
		(end 81.15 134.69)
		(width 0.15)
		(layer "In5.Cu")
		(net 81)
	)
	(segment
		(start 92.7 101.06)
		(end 92.338119 101.421881)
		(width 0.15)
		(layer "In5.Cu")
		(net 81)
	)
	(segment
		(start 91.818119 101.421881)
		(end 91.21 102.03)
		(width 0.15)
		(layer "In5.Cu")
		(net 81)
	)
	(segment
		(start 91.79 109.7)
		(end 91.79 111.32)
		(width 0.15)
		(layer "In5.Cu")
		(net 81)
	)
	(via
		(at 93.725 95.245)
		(size 0.45)
		(drill 0.2)
		(layers "F.Cu" "B.Cu")
		(remove_unused_layers yes)
		(keep_end_layers yes)
		(zone_layer_connections)
		(net 82)
	)
	(via
		(at 72.48 144.86)
		(size 0.45)
		(drill 0.2)
		(layers "F.Cu" "B.Cu")
		(remove_unused_layers yes)
		(keep_end_layers yes)
		(zone_layer_connections)
		(net 82)
	)
	(segment
		(start 77.3 146.3)
		(end 73.92 146.3)
		(width 0.15)
		(layer "In5.Cu")
		(net 82)
	)
	(segment
		(start 81.05 141)
		(end 78.85 143.2)
		(width 0.15)
		(layer "In5.Cu")
		(net 82)
	)
	(segment
		(start 92.75 111.39)
		(end 92.95 111.59)
		(width 0.15)
		(layer "In5.Cu")
		(net 82)
	)
	(segment
		(start 78.85 144.75)
		(end 77.3 146.3)
		(width 0.15)
		(layer "In5.Cu")
		(net 82)
	)
	(segment
		(start 73.92 146.3)
		(end 72.48 144.86)
		(width 0.15)
		(layer "In5.Cu")
		(net 82)
	)
	(segment
		(start 85.45 131.55)
		(end 85.45 139.05)
		(width 0.15)
		(layer "In5.Cu")
		(net 82)
	)
	(segment
		(start 83.5 141)
		(end 81.05 141)
		(width 0.15)
		(layer "In5.Cu")
		(net 82)
	)
	(segment
		(start 92.75 107.95)
		(end 92.75 111.39)
		(width 0.15)
		(layer "In5.Cu")
		(net 82)
	)
	(segment
		(start 93.725 95.245)
		(end 93.705 95.245)
		(width 0.15)
		(layer "In5.Cu")
		(net 82)
	)
	(segment
		(start 92.25 98.87)
		(end 93.019 99.639)
		(width 0.15)
		(layer "In5.Cu")
		(net 82)
	)
	(segment
		(start 92.95 111.59)
		(end 92.95 124.05)
		(width 0.15)
		(layer "In5.Cu")
		(net 82)
	)
	(segment
		(start 92.95 124.05)
		(end 85.45 131.55)
		(width 0.15)
		(layer "In5.Cu")
		(net 82)
	)
	(segment
		(start 93.019 99.639)
		(end 93.019 101.170549)
		(width 0.15)
		(layer "In5.Cu")
		(net 82)
	)
	(segment
		(start 93.019 101.170549)
		(end 92.25 101.939549)
		(width 0.15)
		(layer "In5.Cu")
		(net 82)
	)
	(segment
		(start 78.85 143.2)
		(end 78.85 144.75)
		(width 0.15)
		(layer "In5.Cu")
		(net 82)
	)
	(segment
		(start 92.25 107.45)
		(end 92.75 107.95)
		(width 0.15)
		(layer "In5.Cu")
		(net 82)
	)
	(segment
		(start 92.25 96.7)
		(end 92.25 98.87)
		(width 0.15)
		(layer "In5.Cu")
		(net 82)
	)
	(segment
		(start 93.705 95.245)
		(end 92.25 96.7)
		(width 0.15)
		(layer "In5.Cu")
		(net 82)
	)
	(segment
		(start 92.25 101.939549)
		(end 92.25 107.45)
		(width 0.15)
		(layer "In5.Cu")
		(net 82)
	)
	(segment
		(start 85.45 139.05)
		(end 83.5 141)
		(width 0.15)
		(layer "In5.Cu")
		(net 82)
	)
	(via
		(at 77.225 103.03)
		(size 0.45)
		(drill 0.2)
		(layers "F.Cu" "B.Cu")
		(remove_unused_layers yes)
		(keep_end_layers yes)
		(zone_layer_connections)
		(net 83)
	)
	(segment
		(start 77.28 102.8)
		(end 77.28 102.975)
		(width 0.15)
		(layer "B.Cu")
		(net 83)
	)
	(segment
		(start 77.28 102.975)
		(end 77.225 103.03)
		(width 0.15)
		(layer "B.Cu")
		(net 83)
	)
	(via
		(at 76.225 106.49)
		(size 0.45)
		(drill 0.2)
		(layers "F.Cu" "B.Cu")
		(remove_unused_layers yes)
		(keep_end_layers yes)
		(zone_layer_connections)
		(net 84)
	)
	(segment
		(start 76.225 106.49)
		(end 76.5 106.49)
		(width 0.125)
		(layer "B.Cu")
		(net 84)
	)
	(segment
		(start 76.5 106.49)
		(end 76.51 106.48)
		(width 0.125)
		(layer "B.Cu")
		(net 84)
	)
	(segment
		(start 91.225 103.15)
		(end 91.225 103.03)
		(width 0.15)
		(layer "F.Cu")
		(net 85)
	)
	(via
		(at 91.225 103.15)
		(size 0.45)
		(drill 0.2)
		(layers "F.Cu" "B.Cu")
		(remove_unused_layers yes)
		(keep_end_layers yes)
		(zone_layer_connections)
		(net 85)
	)
	(segment
		(start 91.22 103.155)
		(end 91.225 103.15)
		(width 0.15)
		(layer "B.Cu")
		(net 85)
	)
	(segment
		(start 91.22 103.45)
		(end 91.22 103.155)
		(width 0.15)
		(layer "B.Cu")
		(net 85)
	)
	(segment
		(start 91 103.23)
		(end 91.22 103.45)
		(width 0.15)
		(layer "B.Cu")
		(net 85)
	)
	(segment
		(start 91.22 104.45)
		(end 91.22 103.45)
		(width 0.15)
		(layer "B.Cu")
		(net 85)
	)
	(via
		(at 74.725 93.515)
		(size 0.45)
		(drill 0.2)
		(layers "F.Cu" "B.Cu")
		(remove_unused_layers yes)
		(keep_end_layers yes)
		(zone_layer_connections)
		(net 86)
	)
	(via
		(at 98.48 144.86)
		(size 0.45)
		(drill 0.2)
		(layers "F.Cu" "B.Cu")
		(remove_unused_layers yes)
		(keep_end_layers yes)
		(zone_layer_connections)
		(net 86)
	)
	(segment
		(start 74.725 93.515)
		(end 74.725 94.325)
		(width 0.15)
		(layer "In5.Cu")
		(net 86)
	)
	(segment
		(start 63.4 139.95)
		(end 70.45 147)
		(width 0.15)
		(layer "In5.Cu")
		(net 86)
	)
	(segment
		(start 71.36 95.39)
		(end 70.05 96.7)
		(width 0.15)
		(layer "In5.Cu")
		(net 86)
	)
	(segment
		(start 74.725 94.325)
		(end 73.66 95.39)
		(width 0.15)
		(layer "In5.Cu")
		(net 86)
	)
	(segment
		(start 70.45 147)
		(end 77.7 147)
		(width 0.15)
		(layer "In5.Cu")
		(net 86)
	)
	(segment
		(start 67.45 103.1)
		(end 67.45 124.8)
		(width 0.15)
		(layer "In5.Cu")
		(net 86)
	)
	(segment
		(start 89.9 144.05)
		(end 92.301 146.451)
		(width 0.15)
		(layer "In5.Cu")
		(net 86)
	)
	(segment
		(start 67.45 124.8)
		(end 63.4 128.85)
		(width 0.15)
		(layer "In5.Cu")
		(net 86)
	)
	(segment
		(start 70.05 96.7)
		(end 70.05 100.5)
		(width 0.15)
		(layer "In5.Cu")
		(net 86)
	)
	(segment
		(start 96.889 146.451)
		(end 98.48 144.86)
		(width 0.15)
		(layer "In5.Cu")
		(net 86)
	)
	(segment
		(start 73.66 95.39)
		(end 71.36 95.39)
		(width 0.15)
		(layer "In5.Cu")
		(net 86)
	)
	(segment
		(start 77.7 147)
		(end 80.65 144.05)
		(width 0.15)
		(layer "In5.Cu")
		(net 86)
	)
	(segment
		(start 92.301 146.451)
		(end 96.889 146.451)
		(width 0.15)
		(layer "In5.Cu")
		(net 86)
	)
	(segment
		(start 63.4 128.85)
		(end 63.4 139.95)
		(width 0.15)
		(layer "In5.Cu")
		(net 86)
	)
	(segment
		(start 70.05 100.5)
		(end 67.45 103.1)
		(width 0.15)
		(layer "In5.Cu")
		(net 86)
	)
	(segment
		(start 80.65 144.05)
		(end 89.9 144.05)
		(width 0.15)
		(layer "In5.Cu")
		(net 86)
	)
	(via
		(at 92.725 96.975)
		(size 0.45)
		(drill 0.2)
		(layers "F.Cu" "B.Cu")
		(remove_unused_layers yes)
		(keep_end_layers yes)
		(zone_layer_connections)
		(net 87)
	)
	(via
		(at 96.48 144.86)
		(size 0.45)
		(drill 0.2)
		(layers "F.Cu" "B.Cu")
		(remove_unused_layers yes)
		(keep_end_layers yes)
		(zone_layer_connections)
		(net 87)
	)
	(segment
		(start 102.63 102.46)
		(end 97.16 102.46)
		(width 0.15)
		(layer "In5.Cu")
		(net 87)
	)
	(segment
		(start 97.16 102.46)
		(end 96.1 101.4)
		(width 0.15)
		(layer "In5.Cu")
		(net 87)
	)
	(segment
		(start 94.25 96.81)
		(end 93.84 96.4)
		(width 0.15)
		(layer "In5.Cu")
		(net 87)
	)
	(segment
		(start 93.774 99.126)
		(end 94.25 98.65)
		(width 0.15)
		(layer "In5.Cu")
		(net 87)
	)
	(segment
		(start 96.48 136.87)
		(end 97.6 135.75)
		(width 0.15)
		(layer "In5.Cu")
		(net 87)
	)
	(segment
		(start 93.3 96.4)
		(end 92.725 96.975)
		(width 0.15)
		(layer "In5.Cu")
		(net 87)
	)
	(segment
		(start 103.15 126.75)
		(end 103.15 102.98)
		(width 0.15)
		(layer "In5.Cu")
		(net 87)
	)
	(segment
		(start 96.1 100.82)
		(end 95.306406 100.026406)
		(width 0.15)
		(layer "In5.Cu")
		(net 87)
	)
	(segment
		(start 93.774 99.756811)
		(end 93.774 99.126)
		(width 0.15)
		(layer "In5.Cu")
		(net 87)
	)
	(segment
		(start 95.306406 100.026406)
		(end 94.043594 100.026406)
		(width 0.15)
		(layer "In5.Cu")
		(net 87)
	)
	(segment
		(start 103.15 102.98)
		(end 102.63 102.46)
		(width 0.15)
		(layer "In5.Cu")
		(net 87)
	)
	(segment
		(start 94.043594 100.026406)
		(end 93.774 99.756811)
		(width 0.15)
		(layer "In5.Cu")
		(net 87)
	)
	(segment
		(start 93.84 96.4)
		(end 93.3 96.4)
		(width 0.15)
		(layer "In5.Cu")
		(net 87)
	)
	(segment
		(start 96.48 144.86)
		(end 96.48 136.87)
		(width 0.15)
		(layer "In5.Cu")
		(net 87)
	)
	(segment
		(start 94.25 98.65)
		(end 94.25 96.81)
		(width 0.15)
		(layer "In5.Cu")
		(net 87)
	)
	(segment
		(start 96.1 101.4)
		(end 96.1 100.82)
		(width 0.15)
		(layer "In5.Cu")
		(net 87)
	)
	(segment
		(start 101.7 135.75)
		(end 104.9 132.55)
		(width 0.15)
		(layer "In5.Cu")
		(net 87)
	)
	(segment
		(start 97.6 135.75)
		(end 101.7 135.75)
		(width 0.15)
		(layer "In5.Cu")
		(net 87)
	)
	(segment
		(start 104.9 132.55)
		(end 104.9 128.5)
		(width 0.15)
		(layer "In5.Cu")
		(net 87)
	)
	(segment
		(start 104.9 128.5)
		(end 103.15 126.75)
		(width 0.15)
		(layer "In5.Cu")
		(net 87)
	)
	(via
		(at 93.725 96.975)
		(size 0.45)
		(drill 0.2)
		(layers "F.Cu" "B.Cu")
		(remove_unused_layers yes)
		(keep_end_layers yes)
		(zone_layer_connections)
		(net 88)
	)
	(via
		(at 94.48 144.86)
		(size 0.45)
		(drill 0.2)
		(layers "F.Cu" "B.Cu")
		(remove_unused_layers yes)
		(keep_end_layers yes)
		(zone_layer_connections)
		(net 88)
	)
	(segment
		(start 103.95 129)
		(end 102.5 127.55)
		(width 0.15)
		(layer "In5.Cu")
		(net 88)
	)
	(segment
		(start 93.97 101.74)
		(end 93.32 101.09)
		(width 0.15)
		(layer "In5.Cu")
		(net 88)
	)
	(segment
		(start 102.2 102.77)
		(end 96.07 102.77)
		(width 0.15)
		(layer "In5.Cu")
		(net 88)
	)
	(segment
		(start 93.32 101.09)
		(end 93.32 97.38)
		(width 0.15)
		(layer "In5.Cu")
		(net 88)
	)
	(segment
		(start 96.07 102.77)
		(end 95.04 101.74)
		(width 0.15)
		(layer "In5.Cu")
		(net 88)
	)
	(segment
		(start 95.04 101.74)
		(end 93.97 101.74)
		(width 0.15)
		(layer "In5.Cu")
		(net 88)
	)
	(segment
		(start 95.45 143.89)
		(end 95.45 136.85)
		(width 0.15)
		(layer "In5.Cu")
		(net 88)
	)
	(segment
		(start 97.65 134.65)
		(end 101.15 134.65)
		(width 0.15)
		(layer "In5.Cu")
		(net 88)
	)
	(segment
		(start 101.15 134.65)
		(end 103.95 131.85)
		(width 0.15)
		(layer "In5.Cu")
		(net 88)
	)
	(segment
		(start 93.32 97.38)
		(end 93.725 96.975)
		(width 0.15)
		(layer "In5.Cu")
		(net 88)
	)
	(segment
		(start 95.45 136.85)
		(end 97.65 134.65)
		(width 0.15)
		(layer "In5.Cu")
		(net 88)
	)
	(segment
		(start 102.5 103.07)
		(end 102.2 102.77)
		(width 0.15)
		(layer "In5.Cu")
		(net 88)
	)
	(segment
		(start 102.5 127.55)
		(end 102.5 103.07)
		(width 0.15)
		(layer "In5.Cu")
		(net 88)
	)
	(segment
		(start 103.95 131.85)
		(end 103.95 129)
		(width 0.15)
		(layer "In5.Cu")
		(net 88)
	)
	(segment
		(start 94.48 144.86)
		(end 95.45 143.89)
		(width 0.15)
		(layer "In5.Cu")
		(net 88)
	)
	(segment
		(start 52.85 76.9)
		(end 55.6495 76.9)
		(width 0.15)
		(layer "F.Cu")
		(net 89)
	)
	(segment
		(start 52.3 77.3)
		(end 52.45 77.3)
		(width 0.15)
		(layer "F.Cu")
		(net 89)
	)
	(segment
		(start 52.45 77.3)
		(end 52.85 76.9)
		(width 0.15)
		(layer "F.Cu")
		(net 89)
	)
	(segment
		(start 94.18 60.6)
		(end 93.33 60.6)
		(width 0.3)
		(layer "F.Cu")
		(net 90)
	)
	(segment
		(start 94.18 60.6)
		(end 94.21 60.6)
		(width 0.3)
		(layer "F.Cu")
		(net 90)
	)
	(segment
		(start 95.65 56.61)
		(end 104.325 56.61)
		(width 0.3)
		(layer "F.Cu")
		(net 90)
	)
	(segment
		(start 94.45 58.835)
		(end 94.45 60.36)
		(width 0.3)
		(layer "F.Cu")
		(net 90)
	)
	(segment
		(start 104.75 56.185)
		(end 104.75 55.500001)
		(width 0.3)
		(layer "F.Cu")
		(net 90)
	)
	(segment
		(start 94.45 60.36)
		(end 94.45 60.6)
		(width 0.3)
		(layer "F.Cu")
		(net 90)
	)
	(segment
		(start 82.825 80.35)
		(end 81.77 81.405)
		(width 0.3)
		(layer "F.Cu")
		(net 90)
	)
	(segment
		(start 94.21 60.6)
		(end 94.45 60.36)
		(width 0.3)
		(layer "F.Cu")
		(net 90)
	)
	(segment
		(start 95.25 57.690001)
		(end 95.25 58.035)
		(width 0.3)
		(layer "F.Cu")
		(net 90)
	)
	(segment
		(start 94.45 60.6)
		(end 94.45 60.84)
		(width 0.3)
		(layer "F.Cu")
		(net 90)
	)
	(segment
		(start 81.77 81.405)
		(end 81.77 82.15)
		(width 0.3)
		(layer "F.Cu")
		(net 90)
	)
	(segment
		(start 104.325 56.61)
		(end 104.75 56.185)
		(width 0.3)
		(layer "F.Cu")
		(net 90)
	)
	(segment
		(start 95.25 58.035)
		(end 94.45 58.835)
		(width 0.3)
		(layer "F.Cu")
		(net 90)
	)
	(segment
		(start 94.45 72.6)
		(end 86.7 80.35)
		(width 0.3)
		(layer "F.Cu")
		(net 90)
	)
	(segment
		(start 94.45 60.84)
		(end 94.45 72.6)
		(width 0.3)
		(layer "F.Cu")
		(net 90)
	)
	(segment
		(start 94.45 60.6)
		(end 94.18 60.6)
		(width 0.3)
		(layer "F.Cu")
		(net 90)
	)
	(segment
		(start 86.7 80.35)
		(end 82.825 80.35)
		(width 0.3)
		(layer "F.Cu")
		(net 90)
	)
	(segment
		(start 95.25 57.690001)
		(end 95.25 57.01)
		(width 0.3)
		(layer "F.Cu")
		(net 90)
	)
	(segment
		(start 95.25 57.01)
		(end 95.65 56.61)
		(width 0.3)
		(layer "F.Cu")
		(net 90)
	)
	(segment
		(start 94.21 60.6)
		(end 94.45 60.84)
		(width 0.3)
		(layer "F.Cu")
		(net 90)
	)
	(via
		(at 93.725 102.165)
		(size 0.45)
		(drill 0.2)
		(layers "F.Cu" "B.Cu")
		(remove_unused_layers yes)
		(keep_end_layers yes)
		(zone_layer_connections)
		(net 94)
	)
	(segment
		(start 95.084867 102.55)
		(end 95.42 102.55)
		(width 0.125)
		(layer "B.Cu")
		(net 94)
	)
	(segment
		(start 94.55 102.7)
		(end 94.934867 102.7)
		(width 0.125)
		(layer "B.Cu")
		(net 94)
	)
	(segment
		(start 95.42 102.55)
		(end 95.97 103.1)
		(width 0.125)
		(layer "B.Cu")
		(net 94)
	)
	(segment
		(start 94.934867 102.7)
		(end 95.084867 102.55)
		(width 0.125)
		(layer "B.Cu")
		(net 94)
	)
	(segment
		(start 94.015 102.165)
		(end 94.55 102.7)
		(width 0.125)
		(layer "B.Cu")
		(net 94)
	)
	(segment
		(start 93.725 102.165)
		(end 94.015 102.165)
		(width 0.125)
		(layer "B.Cu")
		(net 94)
	)
	(via
		(at 94.725 102.165)
		(size 0.45)
		(drill 0.2)
		(layers "F.Cu" "B.Cu")
		(remove_unused_layers yes)
		(keep_end_layers yes)
		(zone_layer_connections)
		(net 95)
	)
	(segment
		(start 94.725 102.165)
		(end 95.235 102.165)
		(width 0.125)
		(layer "B.Cu")
		(net 95)
	)
	(segment
		(start 95.97 102.1)
		(end 95.3 102.1)
		(width 0.125)
		(layer "B.Cu")
		(net 95)
	)
	(segment
		(start 95.235 102.165)
		(end 95.3 102.1)
		(width 0.125)
		(layer "B.Cu")
		(net 95)
	)
	(via
		(at 94.225 101.3)
		(size 0.45)
		(drill 0.2)
		(layers "F.Cu" "B.Cu")
		(remove_unused_layers yes)
		(keep_end_layers yes)
		(zone_layer_connections)
		(net 96)
	)
	(segment
		(start 95.25 100.35)
		(end 95.5 100.1)
		(width 0.15)
		(layer "B.Cu")
		(net 96)
	)
	(segment
		(start 94.587189 101.3)
		(end 95.25 100.637189)
		(width 0.15)
		(layer "B.Cu")
		(net 96)
	)
	(segment
		(start 95.25 100.637189)
		(end 95.25 100.35)
		(width 0.15)
		(layer "B.Cu")
		(net 96)
	)
	(segment
		(start 94.225 101.3)
		(end 94.587189 101.3)
		(width 0.15)
		(layer "B.Cu")
		(net 96)
	)
	(segment
		(start 95.5 100.1)
		(end 95.97 100.1)
		(width 0.15)
		(layer "B.Cu")
		(net 96)
	)
	(via
		(at 75.225 96.11)
		(size 0.45)
		(drill 0.2)
		(layers "F.Cu" "B.Cu")
		(remove_unused_layers yes)
		(keep_end_layers yes)
		(zone_layer_connections)
		(net 97)
	)
	(segment
		(start 74.94 96.11)
		(end 75.225 96.11)
		(width 0.15)
		(layer "B.Cu")
		(net 97)
	)
	(segment
		(start 74.48 95.65)
		(end 74.94 96.11)
		(width 0.15)
		(layer "B.Cu")
		(net 97)
	)
	(segment
		(start 96.25 55.200001)
		(end 96.1945 55.144501)
		(width 0.202)
		(layer "F.Cu")
		(net 98)
	)
	(segment
		(start 96.1945 55.144501)
		(end 96.1945 54.50346)
		(width 0.202)
		(layer "F.Cu")
		(net 98)
	)
	(segment
		(start 96.25 55.500001)
		(end 96.25 55.200001)
		(width 0.202)
		(layer "F.Cu")
		(net 98)
	)
	(segment
		(start 96.1945 54.50346)
		(end 96.3185 54.37946)
		(width 0.202)
		(layer "F.Cu")
		(net 98)
	)
	(via
		(at 96.3185 54.37946)
		(size 0.45)
		(drill 0.2)
		(layers "F.Cu" "B.Cu")
		(remove_unused_layers yes)
		(keep_end_layers yes)
		(zone_layer_connections)
		(net 98)
	)
	(via
		(at 84.725 91.785)
		(size 0.45)
		(drill 0.2)
		(layers "F.Cu" "B.Cu")
		(remove_unused_layers yes)
		(keep_end_layers yes)
		(zone_layer_connections)
		(net 98)
	)
	(segment
		(start 93.539 75.519301)
		(end 93.539 60.349493)
		(width 0.202)
		(layer "B.Cu")
		(net 98)
	)
	(segment
		(start 96.3185 54.37946)
		(end 96.1945 54.50346)
		(width 0.202)
		(layer "B.Cu")
		(net 98)
	)
	(segment
		(start 96.249999 55.49866)
		(end 96.249999 56.27066)
		(width 0.202)
		(layer "B.Cu")
		(net 98)
	)
	(segment
		(start 84.4195 91.272393)
		(end 84.4195 90.987607)
		(width 0.202)
		(layer "B.Cu")
		(net 98)
	)
	(segment
		(start 84.565946 90.634054)
		(end 84.633544 90.566462)
		(width 0.202)
		(layer "B.Cu")
		(net 98)
	)
	(segment
		(start 84.9445 89.815803)
		(end 84.9445 85.934059)
		(width 0.202)
		(layer "B.Cu")
		(net 98)
	)
	(segment
		(start 96.1945 55.443161)
		(end 96.249999 55.49866)
		(width 0.202)
		(layer "B.Cu")
		(net 98)
	)
	(segment
		(start 96.194496 56.534096)
		(end 96.194497 56.509619)
		(width 0.202)
		(layer "B.Cu")
		(net 98)
	)
	(segment
		(start 94.124786 58.93528)
		(end 95.960096 57.09997)
		(width 0.202)
		(layer "B.Cu")
		(net 98)
	)
	(segment
		(start 96.194497 56.509619)
		(end 96.194499 56.47616)
		(width 0.202)
		(layer "B.Cu")
		(net 98)
	)
	(segment
		(start 84.725 91.785)
		(end 84.565947 91.625947)
		(width 0.202)
		(layer "B.Cu")
		(net 98)
	)
	(segment
		(start 85.530286 84.519846)
		(end 92.83767 77.212462)
		(width 0.202)
		(layer "B.Cu")
		(net 98)
	)
	(segment
		(start 96.1945 54.50346)
		(end 96.1945 55.443161)
		(width 0.202)
		(layer "B.Cu")
		(net 98)
	)
	(segment
		(start 96.194499 56.47616)
		(end 96.249999 56.42066)
		(width 0.202)
		(layer "B.Cu")
		(net 98)
	)
	(segment
		(start 96.249999 56.42066)
		(end 96.249999 56.27066)
		(width 0.202)
		(layer "B.Cu")
		(net 98)
	)
	(arc
		(start 93.539 60.349493)
		(mid 93.691241 59.584126)
		(end 94.124786 58.93528)
		(width 0.202)
		(layer "B.Cu")
		(net 98)
	)
	(arc
		(start 95.960096 57.09997)
		(mid 96.133574 56.840345)
		(end 96.194496 56.534096)
		(width 0.202)
		(layer "B.Cu")
		(net 98)
	)
	(arc
		(start 92.83767 77.212462)
		(mid 93.35673 76.435633)
		(end 93.539 75.519301)
		(width 0.202)
		(layer "B.Cu")
		(net 98)
	)
	(arc
		(start 84.565947 91.625947)
		(mid 84.45756 91.463735)
		(end 84.4195 91.272393)
		(width 0.202)
		(layer "B.Cu")
		(net 98)
	)
	(arc
		(start 84.633544 90.566462)
		(mid 84.863685 90.222061)
		(end 84.9445 89.815803)
		(width 0.202)
		(layer "B.Cu")
		(net 98)
	)
	(arc
		(start 84.9445 85.934059)
		(mid 85.096741 85.168692)
		(end 85.530286 84.519846)
		(width 0.202)
		(layer "B.Cu")
		(net 98)
	)
	(arc
		(start 84.4195 90.987607)
		(mid 84.45756 90.796266)
		(end 84.565946 90.634054)
		(width 0.202)
		(layer "B.Cu")
		(net 98)
	)
	(segment
		(start 81.698999 87.299)
		(end 82.651 87.299)
		(width 0.15)
		(layer "F.Cu")
		(net 99)
	)
	(segment
		(start 74.875 88.975)
		(end 81.949 88.975)
		(width 0.15)
		(layer "F.Cu")
		(net 99)
	)
	(segment
		(start 81.3 85.58)
		(end 81.3 86.9)
		(width 0.15)
		(layer "F.Cu")
		(net 99)
	)
	(segment
		(start 72.8 91.785)
		(end 73.7 91.785)
		(width 0.15)
		(layer "F.Cu")
		(net 99)
	)
	(segment
		(start 82.651 88.273)
		(end 82.651 87.299)
		(width 0.15)
		(layer "F.Cu")
		(net 99)
	)
	(segment
		(start 73.7 91.785)
		(end 73.7 90.15)
		(width 0.15)
		(layer "F.Cu")
		(net 99)
	)
	(segment
		(start 73.7 91.785)
		(end 74.725 91.785)
		(width 0.15)
		(layer "F.Cu")
		(net 99)
	)
	(segment
		(start 79.87 84.15)
		(end 81.3 85.58)
		(width 0.15)
		(layer "F.Cu")
		(net 99)
	)
	(segment
		(start 73.7 90.15)
		(end 74.875 88.975)
		(width 0.15)
		(layer "F.Cu")
		(net 99)
	)
	(segment
		(start 81.3 86.9)
		(end 81.698999 87.299)
		(width 0.15)
		(layer "F.Cu")
		(net 99)
	)
	(segment
		(start 81.949 88.975)
		(end 82.651 88.273)
		(width 0.15)
		(layer "F.Cu")
		(net 99)
	)
	(segment
		(start 96.5 104.25)
		(end 96.92 104.25)
		(width 0.15)
		(layer "F.Cu")
		(net 100)
	)
	(segment
		(start 95.85 105.865)
		(end 95.85 104.9)
		(width 0.15)
		(layer "F.Cu")
		(net 100)
	)
	(segment
		(start 95.85 104.9)
		(end 96.5 104.25)
		(width 0.15)
		(layer "F.Cu")
		(net 100)
	)
	(segment
		(start 95.225 106.49)
		(end 95.85 105.865)
		(width 0.15)
		(layer "F.Cu")
		(net 100)
	)
	(segment
		(start 96.92 104.25)
		(end 96.92 103.3)
		(width 0.15)
		(layer "F.Cu")
		(net 100)
	)
	(via
		(at 95.225 101.3)
		(size 0.45)
		(drill 0.2)
		(layers "F.Cu" "B.Cu")
		(remove_unused_layers yes)
		(keep_end_layers yes)
		(zone_layer_connections)
		(net 101)
	)
	(segment
		(start 95.97 101.1)
		(end 95.425 101.1)
		(width 0.15)
		(layer "B.Cu")
		(net 101)
	)
	(segment
		(start 95.425 101.1)
		(end 95.225 101.3)
		(width 0.15)
		(layer "B.Cu")
		(net 101)
	)
	(via
		(at 93.725 100.435)
		(size 0.45)
		(drill 0.2)
		(layers "F.Cu" "B.Cu")
		(remove_unused_layers yes)
		(keep_end_layers yes)
		(zone_layer_connections)
		(net 102)
	)
	(segment
		(start 93.725 98.525)
		(end 93.725 100.435)
		(width 0.15)
		(layer "B.Cu")
		(net 102)
	)
	(segment
		(start 94.911811 98.254)
		(end 93.996 98.254)
		(width 0.15)
		(layer "B.Cu")
		(net 102)
	)
	(segment
		(start 94.957811 98.3)
		(end 94.911811 98.254)
		(width 0.15)
		(layer "B.Cu")
		(net 102)
	)
	(segment
		(start 95.97 98.1)
		(end 95.77 98.3)
		(width 0.15)
		(layer "B.Cu")
		(net 102)
	)
	(segment
		(start 95.77 98.3)
		(end 94.957811 98.3)
		(width 0.15)
		(layer "B.Cu")
		(net 102)
	)
	(segment
		(start 93.996 98.254)
		(end 93.725 98.525)
		(width 0.15)
		(layer "B.Cu")
		(net 102)
	)
	(via
		(at 94.725 100.435)
		(size 0.45)
		(drill 0.2)
		(layers "F.Cu" "B.Cu")
		(remove_unused_layers yes)
		(keep_end_layers yes)
		(zone_layer_connections)
		(net 103)
	)
	(segment
		(start 94.967811 99.1)
		(end 94.725 99.342811)
		(width 0.15)
		(layer "B.Cu")
		(net 103)
	)
	(segment
		(start 95.97 99.1)
		(end 94.967811 99.1)
		(width 0.15)
		(layer "B.Cu")
		(net 103)
	)
	(segment
		(start 94.725 99.342811)
		(end 94.725 100.435)
		(width 0.15)
		(layer "B.Cu")
		(net 103)
	)
	(segment
		(start 97.3055 55.144501)
		(end 97.3055 54.50346)
		(width 0.202)
		(layer "F.Cu")
		(net 104)
	)
	(segment
		(start 97.25 55.200001)
		(end 97.3055 55.144501)
		(width 0.202)
		(layer "F.Cu")
		(net 104)
	)
	(segment
		(start 97.3055 54.50346)
		(end 97.1815 54.37946)
		(width 0.202)
		(layer "F.Cu")
		(net 104)
	)
	(segment
		(start 97.25 55.500001)
		(end 97.25 55.200001)
		(width 0.202)
		(layer "F.Cu")
		(net 104)
	)
	(via
		(at 97.1815 54.37946)
		(size 0.45)
		(drill 0.2)
		(layers "F.Cu" "B.Cu")
		(remove_unused_layers yes)
		(keep_end_layers yes)
		(zone_layer_connections)
		(net 104)
	)
	(via
		(at 86.725 91.785)
		(size 0.45)
		(drill 0.2)
		(layers "F.Cu" "B.Cu")
		(remove_unused_layers yes)
		(keep_end_layers yes)
		(zone_layer_connections)
		(net 104)
	)
	(segment
		(start 88.090457 84.159543)
		(end 94.125214 78.124786)
		(width 0.202)
		(layer "B.Cu")
		(net 104)
	)
	(segment
		(start 97.247999 56.683161)
		(end 97.247999 56.27066)
		(width 0.202)
		(layer "B.Cu")
		(net 104)
	)
	(segment
		(start 97.3055 55.443158)
		(end 97.249999 55.498659)
		(width 0.202)
		(layer "B.Cu")
		(net 104)
	)
	(segment
		(start 97.303499 57.242221)
		(end 97.303499 56.738661)
		(width 0.202)
		(layer "B.Cu")
		(net 104)
	)
	(segment
		(start 97.1815 54.37946)
		(end 97.3055 54.50346)
		(width 0.202)
		(layer "B.Cu")
		(net 104)
	)
	(segment
		(start 95.39748 59.562454)
		(end 97.010606 57.949328)
		(width 0.202)
		(layer "B.Cu")
		(net 104)
	)
	(segment
		(start 87.3955 90.112327)
		(end 87.3955 85.837317)
		(width 0.202)
		(layer "B.Cu")
		(net 104)
	)
	(segment
		(start 97.249999 55.498659)
		(end 97.249999 56.27066)
		(width 0.202)
		(layer "B.Cu")
		(net 104)
	)
	(segment
		(start 97.3055 54.50346)
		(end 97.3055 55.443158)
		(width 0.202)
		(layer "B.Cu")
		(net 104)
	)
	(segment
		(start 97.303499 56.738661)
		(end 97.247999 56.683161)
		(width 0.202)
		(layer "B.Cu")
		(net 104)
	)
	(segment
		(start 94.711 76.710573)
		(end 94.711 61.219764)
		(width 0.202)
		(layer "B.Cu")
		(net 104)
	)
	(segment
		(start 86.725 91.785)
		(end 86.884054 91.625946)
		(width 0.202)
		(layer "B.Cu")
		(net 104)
	)
	(segment
		(start 87.0305 91.272393)
		(end 87.0305 90.993477)
		(width 0.202)
		(layer "B.Cu")
		(net 104)
	)
	(arc
		(start 87.249054 90.46588)
		(mid 87.35744 90.303668)
		(end 87.3955 90.112327)
		(width 0.202)
		(layer "B.Cu")
		(net 104)
	)
	(arc
		(start 86.884054 91.625946)
		(mid 86.99244 91.463734)
		(end 87.0305 91.272393)
		(width 0.202)
		(layer "B.Cu")
		(net 104)
	)
	(arc
		(start 87.3955 85.837317)
		(mid 87.576113 84.929312)
		(end 88.090457 84.159543)
		(width 0.202)
		(layer "B.Cu")
		(net 104)
	)
	(arc
		(start 87.0305 90.993477)
		(mid 87.087294 90.707958)
		(end 87.249054 90.46588)
		(width 0.202)
		(layer "B.Cu")
		(net 104)
	)
	(arc
		(start 94.711 61.219764)
		(mid 94.88941 60.322834)
		(end 95.39748 59.562454)
		(width 0.202)
		(layer "B.Cu")
		(net 104)
	)
	(arc
		(start 94.125214 78.124786)
		(mid 94.558759 77.47594)
		(end 94.711 76.710573)
		(width 0.202)
		(layer "B.Cu")
		(net 104)
	)
	(arc
		(start 97.010606 57.949328)
		(mid 97.227379 57.624904)
		(end 97.303499 57.242221)
		(width 0.202)
		(layer "B.Cu")
		(net 104)
	)
	(segment
		(start 74.151 93.501)
		(end 74.151 95.727834)
		(width 0.15)
		(layer "F.Cu")
		(net 105)
	)
	(segment
		(start 71.8 91.785)
		(end 71.8 92.15)
		(width 0.15)
		(layer "F.Cu")
		(net 105)
	)
	(segment
		(start 71.8 92.15)
		(end 72.35 92.7)
		(width 0.15)
		(layer "F.Cu")
		(net 105)
	)
	(segment
		(start 73.35 92.7)
		(end 74.151 93.501)
		(width 0.15)
		(layer "F.Cu")
		(net 105)
	)
	(segment
		(start 75.225 96.801834)
		(end 75.225 97.84)
		(width 0.15)
		(layer "F.Cu")
		(net 105)
	)
	(segment
		(start 74.151 95.727834)
		(end 75.225 96.801834)
		(width 0.15)
		(layer "F.Cu")
		(net 105)
	)
	(segment
		(start 72.35 92.7)
		(end 73.35 92.7)
		(width 0.15)
		(layer "F.Cu")
		(net 105)
	)
	(via
		(at 73.35 92.7)
		(size 0.45)
		(drill 0.2)
		(layers "F.Cu" "B.Cu")
		(remove_unused_layers yes)
		(keep_end_layers yes)
		(zone_layer_connections)
		(net 105)
	)
	(segment
		(start 74.15 92.7)
		(end 74.65 92.2)
		(width 0.15)
		(layer "B.Cu")
		(net 105)
	)
	(segment
		(start 74.65 90.78)
		(end 75.94 89.49)
		(width 0.15)
		(layer "B.Cu")
		(net 105)
	)
	(segment
		(start 57.61 74.344)
		(end 56.97 74.984)
		(width 0.15)
		(layer "B.Cu")
		(net 105)
	)
	(segment
		(start 72.596854 93.453146)
		(end 72.055 93.453146)
		(width 0.15)
		(layer "B.Cu")
		(net 105)
	)
	(segment
		(start 74.65 92.2)
		(end 74.65 90.78)
		(width 0.15)
		(layer "B.Cu")
		(net 105)
	)
	(segment
		(start 75.94 89.49)
		(end 75.94 82.65)
		(width 0.15)
		(layer "B.Cu")
		(net 105)
	)
	(segment
		(start 57.61 73.19)
		(end 57.61 74.344)
		(width 0.15)
		(layer "B.Cu")
		(net 105)
	)
	(segment
		(start 73.35 92.7)
		(end 72.596854 93.453146)
		(width 0.15)
		(layer "B.Cu")
		(net 105)
	)
	(segment
		(start 75.355 76.955)
		(end 71 72.6)
		(width 0.15)
		(layer "B.Cu")
		(net 105)
	)
	(segment
		(start 58.2 72.6)
		(end 57.61 73.19)
		(width 0.15)
		(layer "B.Cu")
		(net 105)
	)
	(segment
		(start 75.355 82.065)
		(end 75.355 76.955)
		(width 0.15)
		(layer "B.Cu")
		(net 105)
	)
	(segment
		(start 73.35 92.7)
		(end 74.15 92.7)
		(width 0.15)
		(layer "B.Cu")
		(net 105)
	)
	(segment
		(start 75.94 82.65)
		(end 75.355 82.065)
		(width 0.15)
		(layer "B.Cu")
		(net 105)
	)
	(segment
		(start 71 72.6)
		(end 58.2 72.6)
		(width 0.15)
		(layer "B.Cu")
		(net 105)
	)
	(segment
		(start 69.517 90.542)
		(end 69.517 87.6)
		(width 0.15)
		(layer "F.Cu")
		(net 106)
	)
	(segment
		(start 69.8 90.825)
		(end 69.517 90.542)
		(width 0.15)
		(layer "F.Cu")
		(net 106)
	)
	(segment
		(start 70.799999 90.825001)
		(end 69.800001 90.825001)
		(width 0.15)
		(layer "F.Cu")
		(net 106)
	)
	(via
		(at 69.517 87.6)
		(size 0.45)
		(drill 0.2)
		(layers "F.Cu" "B.Cu")
		(remove_unused_layers yes)
		(keep_end_layers yes)
		(zone_layer_connections)
		(net 106)
	)
	(segment
		(start 61.2 74.1)
		(end 65.25 74.1)
		(width 0.15)
		(layer "B.Cu")
		(net 106)
	)
	(segment
		(start 65.25 74.1)
		(end 67.5 76.35)
		(width 0.15)
		(layer "B.Cu")
		(net 106)
	)
	(segment
		(start 67.5 76.35)
		(end 67.5 80.95)
		(width 0.15)
		(layer "B.Cu")
		(net 106)
	)
	(segment
		(start 54.431 74.984)
		(end 54.431 75.581)
		(width 0.15)
		(layer "B.Cu")
		(net 106)
	)
	(segment
		(start 69.517 87.6)
		(end 69.517 86.252146)
		(width 0.15)
		(layer "B.Cu")
		(net 106)
	)
	(segment
		(start 54.7 75.85)
		(end 59.45 75.85)
		(width 0.15)
		(layer "B.Cu")
		(net 106)
	)
	(segment
		(start 67.5 80.95)
		(end 69.517 82.967)
		(width 0.15)
		(layer "B.Cu")
		(net 106)
	)
	(segment
		(start 69.517 82.967)
		(end 69.517 86.252146)
		(width 0.15)
		(layer "B.Cu")
		(net 106)
	)
	(segment
		(start 59.45 75.85)
		(end 61.2 74.1)
		(width 0.15)
		(layer "B.Cu")
		(net 106)
	)
	(segment
		(start 54.431 75.581)
		(end 54.7 75.85)
		(width 0.15)
		(layer "B.Cu")
		(net 106)
	)
	(segment
		(start 75.398166 98.705)
		(end 73.996583 97.303417)
		(width 0.15)
		(layer "F.Cu")
		(net 107)
	)
	(segment
		(start 73.996583 96.946583)
		(end 70.8 93.75)
		(width 0.15)
		(layer "F.Cu")
		(net 107)
	)
	(segment
		(start 73.996583 97.303417)
		(end 73.996583 96.946583)
		(width 0.15)
		(layer "F.Cu")
		(net 107)
	)
	(segment
		(start 70.8 93.75)
		(end 70.8 91.785)
		(width 0.15)
		(layer "F.Cu")
		(net 107)
	)
	(segment
		(start 75.725 98.705)
		(end 75.398166 98.705)
		(width 0.15)
		(layer "F.Cu")
		(net 107)
	)
	(segment
		(start 92.225 100.85)
		(end 92.225 101.3)
		(width 0.3)
		(layer "F.Cu")
		(net 108)
	)
	(via
		(at 92.225 100.85)
		(size 0.45)
		(drill 0.2)
		(layers "F.Cu" "B.Cu")
		(remove_unused_layers yes)
		(keep_end_layers yes)
		(zone_layer_connections)
		(net 108)
	)
	(via
		(at 71.95 96.55)
		(size 0.45)
		(drill 0.2)
		(layers "F.Cu" "B.Cu")
		(remove_unused_layers yes)
		(keep_end_layers yes)
		(zone_layer_connections)
		(net 108)
	)
	(segment
		(start 73.52 97.65)
		(end 73.05 97.65)
		(width 0.15)
		(layer "B.Cu")
		(net 108)
	)
	(segment
		(start 73.05 97.65)
		(end 71.95 96.55)
		(width 0.15)
		(layer "B.Cu")
		(net 108)
	)
	(segment
		(start 90.74 101.55)
		(end 90.34 101.95)
		(width 0.15)
		(layer "In5.Cu")
		(net 108)
	)
	(segment
		(start 90.75 110.45)
		(end 91.03 110.73)
		(width 0.15)
		(layer "In5.Cu")
		(net 108)
	)
	(segment
		(start 72.9 97.5)
		(end 71.95 96.55)
		(width 0.15)
		(layer "In5.Cu")
		(net 108)
	)
	(segment
		(start 91.03 111.07)
		(end 90.54 111.56)
		(width 0.15)
		(layer "In5.Cu")
		(net 108)
	)
	(segment
		(start 90.349 104.581)
		(end 90.349 107.619)
		(width 0.15)
		(layer "In5.Cu")
		(net 108)
	)
	(segment
		(start 72.9 99.17)
		(end 72.9 97.5)
		(width 0.15)
		(layer "In5.Cu")
		(net 108)
	)
	(segment
		(start 76.84 111.56)
		(end 71.72 106.44)
		(width 0.15)
		(layer "In5.Cu")
		(net 108)
	)
	(segment
		(start 91.03 110.73)
		(end 91.03 111.07)
		(width 0.15)
		(layer "In5.Cu")
		(net 108)
	)
	(segment
		(start 90.34 101.95)
		(end 90.34 102.5)
		(width 0.15)
		(layer "In5.Cu")
		(net 108)
	)
	(segment
		(start 90.601 102.761)
		(end 90.601 104.329)
		(width 0.15)
		(layer "In5.Cu")
		(net 108)
	)
	(segment
		(start 90.74 101.1)
		(end 90.74 101.55)
		(width 0.15)
		(layer "In5.Cu")
		(net 108)
	)
	(segment
		(start 90.54 111.56)
		(end 76.84 111.56)
		(width 0.15)
		(layer "In5.Cu")
		(net 108)
	)
	(segment
		(start 90.99 100.85)
		(end 90.74 101.1)
		(width 0.15)
		(layer "In5.Cu")
		(net 108)
	)
	(segment
		(start 92.225 100.85)
		(end 90.99 100.85)
		(width 0.15)
		(layer "In5.Cu")
		(net 108)
	)
	(segment
		(start 90.34 102.5)
		(end 90.601 102.761)
		(width 0.15)
		(layer "In5.Cu")
		(net 108)
	)
	(segment
		(start 71.72 100.35)
		(end 72.9 99.17)
		(width 0.15)
		(layer "In5.Cu")
		(net 108)
	)
	(segment
		(start 90.601 104.329)
		(end 90.349 104.581)
		(width 0.15)
		(layer "In5.Cu")
		(net 108)
	)
	(segment
		(start 90.349 107.619)
		(end 90.75 108.02)
		(width 0.15)
		(layer "In5.Cu")
		(net 108)
	)
	(segment
		(start 71.72 106.44)
		(end 71.72 100.35)
		(width 0.15)
		(layer "In5.Cu")
		(net 108)
	)
	(segment
		(start 90.75 108.02)
		(end 90.75 110.45)
		(width 0.15)
		(layer "In5.Cu")
		(net 108)
	)
	(segment
		(start 95.75 55.200001)
		(end 95.8055 55.144501)
		(width 0.202)
		(layer "F.Cu")
		(net 109)
	)
	(segment
		(start 95.75 55.500001)
		(end 95.75 55.200001)
		(width 0.202)
		(layer "F.Cu")
		(net 109)
	)
	(segment
		(start 95.8055 55.144501)
		(end 95.8055 54.50346)
		(width 0.202)
		(layer "F.Cu")
		(net 109)
	)
	(segment
		(start 95.8055 54.50346)
		(end 95.6815 54.37946)
		(width 0.202)
		(layer "F.Cu")
		(net 109)
	)
	(via
		(at 95.6815 54.37946)
		(size 0.45)
		(drill 0.2)
		(layers "F.Cu" "B.Cu")
		(remove_unused_layers yes)
		(keep_end_layers yes)
		(zone_layer_connections)
		(net 109)
	)
	(via
		(at 83.725 91.785)
		(size 0.45)
		(drill 0.2)
		(layers "F.Cu" "B.Cu")
		(remove_unused_layers yes)
		(keep_end_layers yes)
		(zone_layer_connections)
		(net 109)
	)
	(segment
		(start 93.15 75.521573)
		(end 93.15 60.351858)
		(width 0.202)
		(layer "B.Cu")
		(net 109)
	)
	(segment
		(start 84.280112 90.369756)
		(end 84.360808 90.28906)
		(width 0.202)
		(layer "B.Cu")
		(net 109)
	)
	(segment
		(start 83.725 91.785)
		(end 83.884053 91.625947)
		(width 0.202)
		(layer "B.Cu")
		(net 109)
	)
	(segment
		(start 95.8055 55.443158)
		(end 95.749999 55.498659)
		(width 0.202)
		(layer "B.Cu")
		(net 109)
	)
	(segment
		(start 84.0305 91.272393)
		(end 84.0305 90.972372)
		(width 0.202)
		(layer "B.Cu")
		(net 109)
	)
	(segment
		(start 85.254222 84.245778)
		(end 92.564213 76.935787)
		(width 0.202)
		(layer "B.Cu")
		(net 109)
	)
	(segment
		(start 93.851396 58.658538)
		(end 95.688341 56.821593)
		(width 0.202)
		(layer "B.Cu")
		(net 109)
	)
	(segment
		(start 95.6815 54.37946)
		(end 95.8055 54.50346)
		(width 0.202)
		(layer "B.Cu")
		(net 109)
	)
	(segment
		(start 95.749999 56.42066)
		(end 95.749999 56.27066)
		(width 0.202)
		(layer "B.Cu")
		(net 109)
	)
	(segment
		(start 84.5555 89.819033)
		(end 84.5555 85.932642)
		(width 0.202)
		(layer "B.Cu")
		(net 109)
	)
	(segment
		(start 95.749999 55.498659)
		(end 95.749999 56.27066)
		(width 0.202)
		(layer "B.Cu")
		(net 109)
	)
	(segment
		(start 95.8055 54.50346)
		(end 95.8055 55.443158)
		(width 0.202)
		(layer "B.Cu")
		(net 109)
	)
	(segment
		(start 95.805499 56.47616)
		(end 95.749999 56.42066)
		(width 0.202)
		(layer "B.Cu")
		(net 109)
	)
	(segment
		(start 95.805499 56.53875)
		(end 95.805499 56.47616)
		(width 0.202)
		(layer "B.Cu")
		(net 109)
	)
	(arc
		(start 84.360808 90.28906)
		(mid 84.504901 90.07341)
		(end 84.5555 89.819033)
		(width 0.202)
		(layer "B.Cu")
		(net 109)
	)
	(arc
		(start 83.884053 91.625947)
		(mid 83.99244 91.463735)
		(end 84.0305 91.272393)
		(width 0.202)
		(layer "B.Cu")
		(net 109)
	)
	(arc
		(start 84.5555 85.932642)
		(mid 84.737092 85.019718)
		(end 85.254222 84.245778)
		(width 0.202)
		(layer "B.Cu")
		(net 109)
	)
	(arc
		(start 95.688341 56.821593)
		(mid 95.77505 56.691824)
		(end 95.805499 56.53875)
		(width 0.202)
		(layer "B.Cu")
		(net 109)
	)
	(arc
		(start 93.15 60.351858)
		(mid 93.332287 59.43544)
		(end 93.851396 58.658538)
		(width 0.202)
		(layer "B.Cu")
		(net 109)
	)
	(arc
		(start 92.564213 76.935787)
		(mid 92.997759 76.28694)
		(end 93.15 75.521573)
		(width 0.202)
		(layer "B.Cu")
		(net 109)
	)
	(arc
		(start 84.0305 90.972372)
		(mid 84.095372 90.646238)
		(end 84.280112 90.369756)
		(width 0.202)
		(layer "B.Cu")
		(net 109)
	)
	(via
		(at 72.055 87.355)
		(size 0.45)
		(drill 0.2)
		(layers "F.Cu" "B.Cu")
		(remove_unused_layers yes)
		(keep_end_layers yes)
		(zone_layer_connections)
		(net 110)
	)
	(via
		(at 58.24 74.984)
		(size 0.45)
		(drill 0.2)
		(layers "F.Cu" "B.Cu")
		(remove_unused_layers yes)
		(keep_end_layers yes)
		(zone_layer_connections)
		(net 110)
	)
	(segment
		(start 74.9 86.049)
		(end 75.249 86.049)
		(width 0.15)
		(layer "B.Cu")
		(net 110)
	)
	(segment
		(start 75.475 86.275)
		(end 75.475 88.575)
		(width 0.15)
		(layer "B.Cu")
		(net 110)
	)
	(segment
		(start 73.971 86.049)
		(end 73.75 86.27)
		(width 0.15)
		(layer "B.Cu")
		(net 110)
	)
	(segment
		(start 73.732146 86.252146)
		(end 73.75 86.27)
		(width 0.15)
		(layer "B.Cu")
		(net 110)
	)
	(segment
		(start 75.249 86.049)
		(end 75.475 86.275)
		(width 0.15)
		(layer "B.Cu")
		(net 110)
	)
	(segment
		(start 74.9 86.049)
		(end 73.971 86.049)
		(width 0.15)
		(layer "B.Cu")
		(net 110)
	)
	(segment
		(start 73.75 89.38)
		(end 73.75 90.32)
		(width 0.15)
		(layer "B.Cu")
		(net 110)
	)
	(segment
		(start 72.055 87.355)
		(end 72.055 86.252146)
		(width 0.3)
		(layer "B.Cu")
		(net 110)
	)
	(segment
		(start 75.475 88.575)
		(end 74.67 89.38)
		(width 0.15)
		(layer "B.Cu")
		(net 110)
	)
	(segment
		(start 74.67 89.38)
		(end 73.75 89.38)
		(width 0.15)
		(layer "B.Cu")
		(net 110)
	)
	(segment
		(start 72.055 86.252146)
		(end 73.732146 86.252146)
		(width 0.15)
		(layer "B.Cu")
		(net 110)
	)
	(segment
		(start 58.26 74.964)
		(end 58.24 74.984)
		(width 0.3)
		(layer "In5.Cu")
		(net 110)
	)
	(segment
		(start 64.39 72.99)
		(end 59.18 72.99)
		(width 0.3)
		(layer "In5.Cu")
		(net 110)
	)
	(segment
		(start 59.18 72.99)
		(end 58.24 73.93)
		(width 0.3)
		(layer "In5.Cu")
		(net 110)
	)
	(segment
		(start 72.055 87.355)
		(end 69.8 85.1)
		(width 0.3)
		(layer "In5.Cu")
		(net 110)
	)
	(segment
		(start 67.37 79.94)
		(end 67.37 75.97)
		(width 0.3)
		(layer "In5.Cu")
		(net 110)
	)
	(segment
		(start 67.37 75.97)
		(end 64.39 72.99)
		(width 0.3)
		(layer "In5.Cu")
		(net 110)
	)
	(segment
		(start 69.8 82.37)
		(end 67.37 79.94)
		(width 0.3)
		(layer "In5.Cu")
		(net 110)
	)
	(segment
		(start 69.8 85.1)
		(end 69.8 82.37)
		(width 0.3)
		(layer "In5.Cu")
		(net 110)
	)
	(segment
		(start 58.24 73.93)
		(end 58.24 74.984)
		(width 0.3)
		(layer "In5.Cu")
		(net 110)
	)
	(via
		(at 79.225 101.3)
		(size 0.45)
		(drill 0.2)
		(layers "F.Cu" "B.Cu")
		(remove_unused_layers yes)
		(keep_end_layers yes)
		(zone_layer_connections)
		(net 112)
	)
	(segment
		(start 79.225 101.545)
		(end 79.33 101.65)
		(width 0.15)
		(layer "B.Cu")
		(net 112)
	)
	(segment
		(start 79.225 101.3)
		(end 79.225 101.545)
		(width 0.15)
		(layer "B.Cu")
		(net 112)
	)
	(via
		(at 75.725 102.165)
		(size 0.45)
		(drill 0.2)
		(layers "F.Cu" "B.Cu")
		(remove_unused_layers yes)
		(keep_end_layers yes)
		(zone_layer_connections)
		(net 113)
	)
	(segment
		(start 75.43 102.46)
		(end 75.725 102.165)
		(width 0.15)
		(layer "B.Cu")
		(net 113)
	)
	(segment
		(start 75.43 103.2)
		(end 75.43 102.46)
		(width 0.15)
		(layer "B.Cu")
		(net 113)
	)
	(segment
		(start 117.061999 88.66)
		(end 117.061999 89.928)
		(width 0.15)
		(layer "F.Cu")
		(net 114)
	)
	(via
		(at 117.061999 88.66)
		(size 0.45)
		(drill 0.2)
		(layers "F.Cu" "B.Cu")
		(remove_unused_layers yes)
		(keep_end_layers yes)
		(zone_layer_connections)
		(net 114)
	)
	(segment
		(start 117.061999 88.66)
		(end 114.681999 86.28)
		(width 0.15)
		(layer "B.Cu")
		(net 114)
	)
	(segment
		(start 114.681999 86.28)
		(end 109.49 86.28)
		(width 0.15)
		(layer "B.Cu")
		(net 114)
	)
	(segment
		(start 90.225 103.03)
		(end 90.225 103.15)
		(width 0.15)
		(layer "F.Cu")
		(net 115)
	)
	(via
		(at 90.225 103.15)
		(size 0.45)
		(drill 0.2)
		(layers "F.Cu" "B.Cu")
		(remove_unused_layers yes)
		(keep_end_layers yes)
		(zone_layer_connections)
		(net 115)
	)
	(segment
		(start 90.225 103.15)
		(end 90.225 103.43)
		(width 0.15)
		(layer "B.Cu")
		(net 115)
	)
	(segment
		(start 90.225 103.43)
		(end 90.205 103.45)
		(width 0.15)
		(layer "B.Cu")
		(net 115)
	)
	(via
		(at 86.725 107.355)
		(size 0.45)
		(drill 0.2)
		(layers "F.Cu" "B.Cu")
		(remove_unused_layers yes)
		(keep_end_layers yes)
		(zone_layer_connections)
		(net 116)
	)
	(segment
		(start 85.176 105.803189)
		(end 85.774 106.401189)
		(width 0.15)
		(layer "B.Cu")
		(net 116)
	)
	(segment
		(start 84.774 105.036189)
		(end 85.176 105.438189)
		(width 0.15)
		(layer "B.Cu")
		(net 116)
	)
	(segment
		(start 84.774 104.671189)
		(end 84.774 105.036189)
		(width 0.15)
		(layer "B.Cu")
		(net 116)
	)
	(segment
		(start 85.176 105.438189)
		(end 85.176 105.803189)
		(width 0.15)
		(layer "B.Cu")
		(net 116)
	)
	(segment
		(start 84.176 103.356)
		(end 84.176 104.073189)
		(width 0.15)
		(layer "B.Cu")
		(net 116)
	)
	(segment
		(start 86.055 107.355)
		(end 86.725 107.355)
		(width 0.15)
		(layer "B.Cu")
		(net 116)
	)
	(segment
		(start 84.176 104.073189)
		(end 84.774 104.671189)
		(width 0.15)
		(layer "B.Cu")
		(net 116)
	)
	(segment
		(start 83.3 102.48)
		(end 84.176 103.356)
		(width 0.15)
		(layer "B.Cu")
		(net 116)
	)
	(segment
		(start 85.774 106.401189)
		(end 85.774 107.074)
		(width 0.15)
		(layer "B.Cu")
		(net 116)
	)
	(segment
		(start 85.774 107.074)
		(end 86.055 107.355)
		(width 0.15)
		(layer "B.Cu")
		(net 116)
	)
	(via
		(at 85.725 93.515)
		(size 0.45)
		(drill 0.2)
		(layers "F.Cu" "B.Cu")
		(remove_unused_layers yes)
		(keep_end_layers yes)
		(zone_layer_connections)
		(net 119)
	)
	(via
		(at 109.49 87.81)
		(size 0.45)
		(drill 0.2)
		(layers "F.Cu" "B.Cu")
		(remove_unused_layers yes)
		(keep_end_layers yes)
		(zone_layer_connections)
		(net 119)
	)
	(segment
		(start 109.49 87.71)
		(end 109.49 87.24)
		(width 0.15)
		(layer "B.Cu")
		(net 119)
	)
	(segment
		(start 109.49 88.38)
		(end 109.49 87.81)
		(width 0.15)
		(layer "B.Cu")
		(net 119)
	)
	(segment
		(start 85.725 92.455)
		(end 86.19 91.99)
		(width 0.15)
		(layer "In5.Cu")
		(net 119)
	)
	(segment
		(start 108.38 86.65)
		(end 109.49 87.76)
		(width 0.15)
		(layer "In5.Cu")
		(net 119)
	)
	(segment
		(start 86.19 91.99)
		(end 86.19 91.61)
		(width 0.15)
		(layer "In5.Cu")
		(net 119)
	)
	(segment
		(start 91.42 89.62)
		(end 94.39 86.65)
		(width 0.15)
		(layer "In5.Cu")
		(net 119)
	)
	(segment
		(start 88.18 89.62)
		(end 91.42 89.62)
		(width 0.15)
		(layer "In5.Cu")
		(net 119)
	)
	(segment
		(start 109.49 87.76)
		(end 109.49 87.81)
		(width 0.15)
		(layer "In5.Cu")
		(net 119)
	)
	(segment
		(start 94.39 86.65)
		(end 108.38 86.65)
		(width 0.15)
		(layer "In5.Cu")
		(net 119)
	)
	(segment
		(start 86.19 91.61)
		(end 88.18 89.62)
		(width 0.15)
		(layer "In5.Cu")
		(net 119)
	)
	(segment
		(start 85.725 93.515)
		(end 85.725 92.455)
		(width 0.15)
		(layer "In5.Cu")
		(net 119)
	)
	(via
		(at 92.225 94.38)
		(size 0.45)
		(drill 0.2)
		(layers "F.Cu" "B.Cu")
		(remove_unused_layers yes)
		(keep_end_layers yes)
		(zone_layer_connections)
		(net 120)
	)
	(via
		(at 111.49 87.81)
		(size 0.45)
		(drill 0.2)
		(layers "F.Cu" "B.Cu")
		(remove_unused_layers yes)
		(keep_end_layers yes)
		(zone_layer_connections)
		(net 120)
	)
	(segment
		(start 111.49 87.81)
		(end 111.49 88.38)
		(width 0.15)
		(layer "B.Cu")
		(net 120)
	)
	(segment
		(start 111.49 87.71)
		(end 111.49 87.24)
		(width 0.15)
		(layer "B.Cu")
		(net 120)
	)
	(segment
		(start 92.675 93.93)
		(end 92.225 94.38)
		(width 0.15)
		(layer "In5.Cu")
		(net 120)
	)
	(segment
		(start 111.49 87.81)
		(end 111.31 87.81)
		(width 0.15)
		(layer "In5.Cu")
		(net 120)
	)
	(segment
		(start 110.039 89.481)
		(end 105.59 93.93)
		(width 0.15)
		(layer "In5.Cu")
		(net 120)
	)
	(segment
		(start 110.039 89.081)
		(end 110.039 89.481)
		(width 0.15)
		(layer "In5.Cu")
		(net 120)
	)
	(segment
		(start 111.31 87.81)
		(end 110.039 89.081)
		(width 0.15)
		(layer "In5.Cu")
		(net 120)
	)
	(segment
		(start 105.59 93.93)
		(end 92.675 93.93)
		(width 0.15)
		(layer "In5.Cu")
		(net 120)
	)
	(via
		(at 110.49 87.81)
		(size 0.45)
		(drill 0.2)
		(layers "F.Cu" "B.Cu")
		(remove_unused_layers yes)
		(keep_end_layers yes)
		(zone_layer_connections)
		(net 121)
	)
	(via
		(at 87.725 93.515)
		(size 0.45)
		(drill 0.2)
		(layers "F.Cu" "B.Cu")
		(remove_unused_layers yes)
		(keep_end_layers yes)
		(zone_layer_connections)
		(net 121)
	)
	(segment
		(start 110.49 87.81)
		(end 110.49 88.38)
		(width 0.15)
		(layer "B.Cu")
		(net 121)
	)
	(segment
		(start 110.49 87.71)
		(end 110.49 87.24)
		(width 0.15)
		(layer "B.Cu")
		(net 121)
	)
	(segment
		(start 108.98 88.52)
		(end 105.226 92.274)
		(width 0.15)
		(layer "In5.Cu")
		(net 121)
	)
	(segment
		(start 110.49 87.81)
		(end 109.78 88.52)
		(width 0.15)
		(layer "In5.Cu")
		(net 121)
	)
	(segment
		(start 88.5 91.36)
		(end 88.24 91.62)
		(width 0.15)
		(layer "In5.Cu")
		(net 121)
	)
	(segment
		(start 88.24 91.95)
		(end 87.725 92.465)
		(width 0.15)
		(layer "In5.Cu")
		(net 121)
	)
	(segment
		(start 105.226 92.274)
		(end 95.074 92.274)
		(width 0.15)
		(layer "In5.Cu")
		(net 121)
	)
	(segment
		(start 94.16 91.36)
		(end 88.5 91.36)
		(width 0.15)
		(layer "In5.Cu")
		(net 121)
	)
	(segment
		(start 95.074 92.274)
		(end 94.16 91.36)
		(width 0.15)
		(layer "In5.Cu")
		(net 121)
	)
	(segment
		(start 88.24 91.62)
		(end 88.24 91.95)
		(width 0.15)
		(layer "In5.Cu")
		(net 121)
	)
	(segment
		(start 109.78 88.52)
		(end 108.98 88.52)
		(width 0.15)
		(layer "In5.Cu")
		(net 121)
	)
	(segment
		(start 87.725 92.465)
		(end 87.725 93.515)
		(width 0.15)
		(layer "In5.Cu")
		(net 121)
	)
	(via
		(at 83.725 93.515)
		(size 0.45)
		(drill 0.2)
		(layers "F.Cu" "B.Cu")
		(remove_unused_layers yes)
		(keep_end_layers yes)
		(zone_layer_connections)
		(net 122)
	)
	(segment
		(start 83.225 94.12)
		(end 83.225 94.015)
		(width 0.15)
		(layer "B.Cu")
		(net 122)
	)
	(segment
		(start 83.225 94.015)
		(end 83.725 93.515)
		(width 0.15)
		(layer "B.Cu")
		(net 122)
	)
	(via
		(at 84.725 93.515)
		(size 0.45)
		(drill 0.2)
		(layers "F.Cu" "B.Cu")
		(remove_unused_layers yes)
		(keep_end_layers yes)
		(zone_layer_connections)
		(net 123)
	)
	(segment
		(start 84.225 94.015)
		(end 84.725 93.515)
		(width 0.15)
		(layer "B.Cu")
		(net 123)
	)
	(segment
		(start 84.225 94.12)
		(end 84.225 94.015)
		(width 0.15)
		(layer "B.Cu")
		(net 123)
	)
	(via
		(at 93.225 94.38)
		(size 0.45)
		(drill 0.2)
		(layers "F.Cu" "B.Cu")
		(remove_unused_layers yes)
		(keep_end_layers yes)
		(zone_layer_connections)
		(net 124)
	)
	(segment
		(start 93.225 94.38)
		(end 93.225 94.48)
		(width 0.15)
		(layer "B.Cu")
		(net 124)
	)
	(via
		(at 91.225 99.57)
		(size 0.45)
		(drill 0.2)
		(layers "F.Cu" "B.Cu")
		(remove_unused_layers yes)
		(keep_end_layers yes)
		(zone_layer_connections)
		(net 125)
	)
	(segment
		(start 91.225 99.645)
		(end 91.2 99.67)
		(width 0.15)
		(layer "B.Cu")
		(net 125)
	)
	(segment
		(start 91.225 99.57)
		(end 91.225 99.645)
		(width 0.15)
		(layer "B.Cu")
		(net 125)
	)
	(via
		(at 95.225 94.38)
		(size 0.45)
		(drill 0.2)
		(layers "F.Cu" "B.Cu")
		(remove_unused_layers yes)
		(keep_end_layers yes)
		(zone_layer_connections)
		(net 126)
	)
	(segment
		(start 95.225 94.38)
		(end 95.225 94.48)
		(width 0.15)
		(layer "B.Cu")
		(net 126)
	)
	(segment
		(start 84.495 98.705)
		(end 84.475 98.725)
		(width 0.5)
		(layer "F.Cu")
		(net 127)
	)
	(segment
		(start 84.725 98.705)
		(end 84.495 98.705)
		(width 0.5)
		(layer "F.Cu")
		(net 127)
	)
	(via
		(at 84.475 98.725)
		(size 0.45)
		(drill 0.2)
		(layers "F.Cu" "B.Cu")
		(remove_unused_layers yes)
		(keep_end_layers yes)
		(zone_layer_connections)
		(net 127)
	)
	(segment
		(start 84.475 98.725)
		(end 84.28 98.725)
		(width 0.15)
		(layer "B.Cu")
		(net 127)
	)
	(segment
		(start 84.28 98.725)
		(end 84.225 98.78)
		(width 0.15)
		(layer "B.Cu")
		(net 127)
	)
	(via
		(at 86.725 93.515)
		(size 0.45)
		(drill 0.2)
		(layers "F.Cu" "B.Cu")
		(remove_unused_layers yes)
		(keep_end_layers yes)
		(zone_layer_connections)
		(net 128)
	)
	(segment
		(start 82.475 93)
		(end 82.225 93.25)
		(width 0.15)
		(layer "B.Cu")
		(net 128)
	)
	(segment
		(start 82.847811 93)
		(end 82.475 93)
		(width 0.15)
		(layer "B.Cu")
		(net 128)
	)
	(segment
		(start 83.362811 93.15)
		(end 82.997811 93.15)
		(width 0.15)
		(layer "B.Cu")
		(net 128)
	)
	(segment
		(start 85.55 93)
		(end 85.4 93.15)
		(width 0.15)
		(layer "B.Cu")
		(net 128)
	)
	(segment
		(start 86.44 93.515)
		(end 85.925 93)
		(width 0.15)
		(layer "B.Cu")
		(net 128)
	)
	(segment
		(start 85.925 93)
		(end 85.55 93)
		(width 0.15)
		(layer "B.Cu")
		(net 128)
	)
	(segment
		(start 84.087189 93.15)
		(end 83.937189 93)
		(width 0.15)
		(layer "B.Cu")
		(net 128)
	)
	(segment
		(start 82.225 93.25)
		(end 82.225 94.12)
		(width 0.15)
		(layer "B.Cu")
		(net 128)
	)
	(segment
		(start 84.875 93)
		(end 84.512811 93)
		(width 0.15)
		(layer "B.Cu")
		(net 128)
	)
	(segment
		(start 84.512811 93)
		(end 84.362811 93.15)
		(width 0.15)
		(layer "B.Cu")
		(net 128)
	)
	(segment
		(start 82.997811 93.15)
		(end 82.847811 93)
		(width 0.15)
		(layer "B.Cu")
		(net 128)
	)
	(segment
		(start 85.025 93.15)
		(end 84.875 93)
		(width 0.15)
		(layer "B.Cu")
		(net 128)
	)
	(segment
		(start 86.725 93.515)
		(end 86.44 93.515)
		(width 0.15)
		(layer "B.Cu")
		(net 128)
	)
	(segment
		(start 84.362811 93.15)
		(end 84.087189 93.15)
		(width 0.15)
		(layer "B.Cu")
		(net 128)
	)
	(segment
		(start 83.512811 93)
		(end 83.362811 93.15)
		(width 0.15)
		(layer "B.Cu")
		(net 128)
	)
	(segment
		(start 85.4 93.15)
		(end 85.025 93.15)
		(width 0.15)
		(layer "B.Cu")
		(net 128)
	)
	(segment
		(start 83.937189 93)
		(end 83.512811 93)
		(width 0.15)
		(layer "B.Cu")
		(net 128)
	)
	(via
		(at 91.725 98.705)
		(size 0.45)
		(drill 0.2)
		(layers "F.Cu" "B.Cu")
		(remove_unused_layers yes)
		(keep_end_layers yes)
		(zone_layer_connections)
		(net 129)
	)
	(segment
		(start 91.65 98.78)
		(end 91.725 98.705)
		(width 0.5)
		(layer "B.Cu")
		(net 129)
	)
	(segment
		(start 91.2 98.78)
		(end 91.65 98.78)
		(width 0.5)
		(layer "B.Cu")
		(net 129)
	)
	(segment
		(start 111.375001 94.87)
		(end 110.35 94.87)
		(width 0.15)
		(layer "F.Cu")
		(net 130)
	)
	(via
		(at 110.35 94.87)
		(size 0.45)
		(drill 0.2)
		(layers "F.Cu" "B.Cu")
		(remove_unused_layers yes)
		(keep_end_layers yes)
		(zone_layer_connections)
		(net 130)
	)
	(via
		(at 94.225 99.57)
		(size 0.45)
		(drill 0.2)
		(layers "F.Cu" "B.Cu")
		(remove_unused_layers yes)
		(keep_end_layers yes)
		(zone_layer_connections)
		(net 130)
	)
	(segment
		(start 96.367161 97.492839)
		(end 97.28 96.58)
		(width 0.15)
		(layer "In5.Cu")
		(net 130)
	)
	(segment
		(start 106.28 96.58)
		(end 106.8 96.06)
		(width 0.15)
		(layer "In5.Cu")
		(net 130)
	)
	(segment
		(start 97.28 96.58)
		(end 106.28 96.58)
		(width 0.15)
		(layer "In5.Cu")
		(net 130)
	)
	(segment
		(start 94.225 99.57)
		(end 94.578553 99.57)
		(width 0.15)
		(layer "In5.Cu")
		(net 130)
	)
	(segment
		(start 94.578553 99.57)
		(end 95.142553 99.006)
		(width 0.15)
		(layer "In5.Cu")
		(net 130)
	)
	(segment
		(start 108.7 94.87)
		(end 110.35 94.87)
		(width 0.15)
		(layer "In5.Cu")
		(net 130)
	)
	(segment
		(start 107.51 96.06)
		(end 108.7 94.87)
		(width 0.15)
		(layer "In5.Cu")
		(net 130)
	)
	(segment
		(start 95.142553 99.006)
		(end 95.664 99.006)
		(width 0.15)
		(layer "In5.Cu")
		(net 130)
	)
	(segment
		(start 95.664 99.006)
		(end 96.367161 98.302839)
		(width 0.15)
		(layer "In5.Cu")
		(net 130)
	)
	(segment
		(start 96.367161 98.302839)
		(end 96.367161 97.492839)
		(width 0.15)
		(layer "In5.Cu")
		(net 130)
	)
	(segment
		(start 106.8 96.06)
		(end 107.51 96.06)
		(width 0.15)
		(layer "In5.Cu")
		(net 130)
	)
	(via
		(at 91.725 107.355)
		(size 0.45)
		(drill 0.2)
		(layers "F.Cu" "B.Cu")
		(remove_unused_layers yes)
		(keep_end_layers yes)
		(zone_layer_connections)
		(net 131)
	)
	(segment
		(start 91.725 108.425)
		(end 91.725 107.355)
		(width 0.125)
		(layer "B.Cu")
		(net 131)
	)
	(segment
		(start 90.104866 109.45)
		(end 90.7 109.45)
		(width 0.125)
		(layer "B.Cu")
		(net 131)
	)
	(segment
		(start 89.5 110.67)
		(end 89.5 110.054866)
		(width 0.125)
		(layer "B.Cu")
		(net 131)
	)
	(segment
		(start 89.5 110.054866)
		(end 90.104866 109.45)
		(width 0.125)
		(layer "B.Cu")
		(net 131)
	)
	(segment
		(start 90.7 109.45)
		(end 91.725 108.425)
		(width 0.125)
		(layer "B.Cu")
		(net 131)
	)
	(segment
		(start 111.375001 93.93)
		(end 110.35 93.93)
		(width 0.15)
		(layer "F.Cu")
		(net 132)
	)
	(via
		(at 95.225 99.57)
		(size 0.45)
		(drill 0.2)
		(layers "F.Cu" "B.Cu")
		(remove_unused_layers yes)
		(keep_end_layers yes)
		(zone_layer_connections)
		(net 132)
	)
	(via
		(at 110.35 93.93)
		(size 0.45)
		(drill 0.2)
		(layers "F.Cu" "B.Cu")
		(remove_unused_layers yes)
		(keep_end_layers yes)
		(zone_layer_connections)
		(net 132)
	)
	(segment
		(start 109.02 95.55)
		(end 107.92 96.65)
		(width 0.15)
		(layer "In5.Cu")
		(net 132)
	)
	(segment
		(start 110.35 93.93)
		(end 110.95 94.53)
		(width 0.15)
		(layer "In5.Cu")
		(net 132)
	)
	(segment
		(start 106.54 97.16)
		(end 97.37 97.16)
		(width 0.15)
		(layer "In5.Cu")
		(net 132)
	)
	(segment
		(start 110.95 94.53)
		(end 110.95 95.2)
		(width 0.15)
		(layer "In5.Cu")
		(net 132)
	)
	(segment
		(start 107.05 96.65)
		(end 106.54 97.16)
		(width 0.15)
		(layer "In5.Cu")
		(net 132)
	)
	(segment
		(start 97.37 97.16)
		(end 96.885 97.645)
		(width 0.15)
		(layer "In5.Cu")
		(net 132)
	)
	(segment
		(start 96.885 98.935)
		(end 96.25 99.57)
		(width 0.15)
		(layer "In5.Cu")
		(net 132)
	)
	(segment
		(start 96.25 99.57)
		(end 95.225 99.57)
		(width 0.15)
		(layer "In5.Cu")
		(net 132)
	)
	(segment
		(start 110.6 95.55)
		(end 109.02 95.55)
		(width 0.15)
		(layer "In5.Cu")
		(net 132)
	)
	(segment
		(start 107.92 96.65)
		(end 107.05 96.65)
		(width 0.15)
		(layer "In5.Cu")
		(net 132)
	)
	(segment
		(start 96.885 97.645)
		(end 96.885 98.935)
		(width 0.15)
		(layer "In5.Cu")
		(net 132)
	)
	(segment
		(start 110.95 95.2)
		(end 110.6 95.55)
		(width 0.15)
		(layer "In5.Cu")
		(net 132)
	)
	(segment
		(start 95.834 106.966)
		(end 96.3 106.5)
		(width 0.15)
		(layer "F.Cu")
		(net 133)
	)
	(segment
		(start 96.3 105.4)
		(end 96.5 105.2)
		(width 0.15)
		(layer "F.Cu")
		(net 133)
	)
	(segment
		(start 95.027834 106.966)
		(end 95.834 106.966)
		(width 0.15)
		(layer "F.Cu")
		(net 133)
	)
	(segment
		(start 96.5 105.2)
		(end 96.92 105.2)
		(width 0.15)
		(layer "F.Cu")
		(net 133)
	)
	(segment
		(start 94.551834 106.49)
		(end 95.027834 106.966)
		(width 0.15)
		(layer "F.Cu")
		(net 133)
	)
	(segment
		(start 94.225 106.49)
		(end 94.551834 106.49)
		(width 0.15)
		(layer "F.Cu")
		(net 133)
	)
	(segment
		(start 96.3 106.5)
		(end 96.3 105.4)
		(width 0.15)
		(layer "F.Cu")
		(net 133)
	)
	(via
		(at 87.225 106.49)
		(size 0.45)
		(drill 0.2)
		(layers "F.Cu" "B.Cu")
		(remove_unused_layers yes)
		(keep_end_layers yes)
		(zone_layer_connections)
		(net 134)
	)
	(segment
		(start 87.225 106.49)
		(end 87.14 106.49)
		(width 0.15)
		(layer "B.Cu")
		(net 134)
	)
	(segment
		(start 87.14 106.49)
		(end 87 106.35)
		(width 0.15)
		(layer "B.Cu")
		(net 134)
	)
	(via
		(at 87.725 107.355)
		(size 0.45)
		(drill 0.2)
		(layers "F.Cu" "B.Cu")
		(remove_unused_layers yes)
		(keep_end_layers yes)
		(zone_layer_connections)
		(net 135)
	)
	(segment
		(start 87.725 107.355)
		(end 87.725 107.65)
		(width 0.15)
		(layer "B.Cu")
		(net 135)
	)
	(via
		(at 88.225 106.49)
		(size 0.45)
		(drill 0.2)
		(layers "F.Cu" "B.Cu")
		(remove_unused_layers yes)
		(keep_end_layers yes)
		(zone_layer_connections)
		(net 136)
	)
	(segment
		(start 89.3 106.49)
		(end 88.225 106.49)
		(width 0.15)
		(layer "B.Cu")
		(net 136)
	)
	(via
		(at 87.725 105.625)
		(size 0.45)
		(drill 0.2)
		(layers "F.Cu" "B.Cu")
		(remove_unused_layers yes)
		(keep_end_layers yes)
		(zone_layer_connections)
		(net 137)
	)
	(segment
		(start 87.725 104.85)
		(end 87.725 105.625)
		(width 0.15)
		(layer "B.Cu")
		(net 137)
	)
	(segment
		(start 68.6 92.3)
		(end 73.475 97.175)
		(width 0.15)
		(layer "F.Cu")
		(net 139)
	)
	(segment
		(start 73.475 97.175)
		(end 73.475 97.455)
		(width 0.15)
		(layer "F.Cu")
		(net 139)
	)
	(segment
		(start 73.475 97.455)
		(end 74.725 98.705)
		(width 0.15)
		(layer "F.Cu")
		(net 139)
	)
	(segment
		(start 68.6 87.6)
		(end 68.6 92.3)
		(width 0.15)
		(layer "F.Cu")
		(net 139)
	)
	(via
		(at 55.7 73.715)
		(size 0.45)
		(drill 0.2)
		(layers "F.Cu" "B.Cu")
		(remove_unused_layers yes)
		(keep_end_layers yes)
		(zone_layer_connections)
		(net 139)
	)
	(via
		(at 68.6 87.6)
		(size 0.45)
		(drill 0.2)
		(layers "F.Cu" "B.Cu")
		(remove_unused_layers yes)
		(keep_end_layers yes)
		(zone_layer_connections)
		(net 139)
	)
	(segment
		(start 68.246 87.246)
		(end 68.246 86.252146)
		(width 0.15)
		(layer "B.Cu")
		(net 139)
	)
	(segment
		(start 68.6 87.6)
		(end 68.246 87.246)
		(width 0.15)
		(layer "B.Cu")
		(net 139)
	)
	(segment
		(start 64.56 74.52)
		(end 60.86 74.52)
		(width 0.15)
		(layer "In5.Cu")
		(net 139)
	)
	(segment
		(start 68.03 85.33)
		(end 68.03 81.99)
		(width 0.15)
		(layer "In5.Cu")
		(net 139)
	)
	(segment
		(start 68.04 81.98)
		(end 66.51 80.45)
		(width 0.15)
		(layer "In5.Cu")
		(net 139)
	)
	(segment
		(start 59.38 76)
		(end 57.985 76)
		(width 0.15)
		(layer "In5.Cu")
		(net 139)
	)
	(segment
		(start 57.985 76)
		(end 55.7 73.715)
		(width 0.15)
		(layer "In5.Cu")
		(net 139)
	)
	(segment
		(start 66.51 76.47)
		(end 64.56 74.52)
		(width 0.15)
		(layer "In5.Cu")
		(net 139)
	)
	(segment
		(start 68.03 81.99)
		(end 68.04 81.98)
		(width 0.15)
		(layer "In5.Cu")
		(net 139)
	)
	(segment
		(start 60.86 74.52)
		(end 59.38 76)
		(width 0.15)
		(layer "In5.Cu")
		(net 139)
	)
	(segment
		(start 68.6 87.6)
		(end 68.6 85.9)
		(width 0.15)
		(layer "In5.Cu")
		(net 139)
	)
	(segment
		(start 68.6 85.9)
		(end 68.03 85.33)
		(width 0.15)
		(layer "In5.Cu")
		(net 139)
	)
	(segment
		(start 66.51 80.45)
		(end 66.51 76.47)
		(width 0.15)
		(layer "In5.Cu")
		(net 139)
	)
	(segment
		(start 73.65 95.05)
		(end 73.65 95.9)
		(width 0.15)
		(layer "F.Cu")
		(net 140)
	)
	(segment
		(start 73.45 94.85)
		(end 73.65 95.05)
		(width 0.15)
		(layer "F.Cu")
		(net 140)
	)
	(segment
		(start 73.65 95.9)
		(end 74.725 96.975)
		(width 0.15)
		(layer "F.Cu")
		(net 140)
	)
	(via
		(at 53.161 73.715)
		(size 0.45)
		(drill 0.2)
		(layers "F.Cu" "B.Cu")
		(remove_unused_layers yes)
		(keep_end_layers yes)
		(zone_layer_connections)
		(net 140)
	)
	(via
		(at 73.45 94.85)
		(size 0.45)
		(drill 0.2)
		(layers "F.Cu" "B.Cu")
		(remove_unused_layers yes)
		(keep_end_layers yes)
		(zone_layer_connections)
		(net 140)
	)
	(segment
		(start 70.785 93.453146)
		(end 70.785 94.485)
		(width 0.15)
		(layer "B.Cu")
		(net 140)
	)
	(segment
		(start 70.785 94.485)
		(end 71.15 94.85)
		(width 0.15)
		(layer "B.Cu")
		(net 140)
	)
	(segment
		(start 71.15 94.85)
		(end 73.45 94.85)
		(width 0.15)
		(layer "B.Cu")
		(net 140)
	)
	(segment
		(start 55.2 85.35)
		(end 57.3 87.45)
		(width 0.15)
		(layer "In5.Cu")
		(net 140)
	)
	(segment
		(start 57.3 87.45)
		(end 61.05 87.45)
		(width 0.15)
		(layer "In5.Cu")
		(net 140)
	)
	(segment
		(start 63.4 94.3)
		(end 72.9 94.3)
		(width 0.15)
		(layer "In5.Cu")
		(net 140)
	)
	(segment
		(start 53.161 73.715)
		(end 53.65 74.204)
		(width 0.15)
		(layer "In5.Cu")
		(net 140)
	)
	(segment
		(start 62.35 88.75)
		(end 62.35 93.25)
		(width 0.15)
		(layer "In5.Cu")
		(net 140)
	)
	(segment
		(start 62.35 93.25)
		(end 63.4 94.3)
		(width 0.15)
		(layer "In5.Cu")
		(net 140)
	)
	(segment
		(start 50.8 80.15)
		(end 50.8 83.6)
		(width 0.15)
		(layer "In5.Cu")
		(net 140)
	)
	(segment
		(start 61.05 87.45)
		(end 62.35 88.75)
		(width 0.15)
		(layer "In5.Cu")
		(net 140)
	)
	(segment
		(start 52.55 85.35)
		(end 55.2 85.35)
		(width 0.15)
		(layer "In5.Cu")
		(net 140)
	)
	(segment
		(start 53.65 74.204)
		(end 53.65 77.3)
		(width 0.15)
		(layer "In5.Cu")
		(net 140)
	)
	(segment
		(start 72.9 94.3)
		(end 73.45 94.85)
		(width 0.15)
		(layer "In5.Cu")
		(net 140)
	)
	(segment
		(start 50.8 83.6)
		(end 52.55 85.35)
		(width 0.15)
		(layer "In5.Cu")
		(net 140)
	)
	(segment
		(start 53.65 77.3)
		(end 50.8 80.15)
		(width 0.15)
		(layer "In5.Cu")
		(net 140)
	)
	(segment
		(start 90.71 111.36)
		(end 90.1 111.97)
		(width 0.125)
		(layer "F.Cu")
		(net 141)
	)
	(segment
		(start 90.2 108.850488)
		(end 90.2 109.215488)
		(width 0.125)
		(layer "F.Cu")
		(net 141)
	)
	(segment
		(start 90.416988 106.9535)
		(end 89.978988 106.9535)
		(width 0.125)
		(layer "F.Cu")
		(net 141)
	)
	(segment
		(start 92.93 106.49)
		(end 92.45 106.97)
		(width 0.125)
		(layer "F.Cu")
		(net 141)
	)
	(segment
		(start 89.2615 107.546988)
		(end 89.7 107.985488)
		(width 0.125)
		(layer "F.Cu")
		(net 141)
	)
	(segment
		(start 93.225 106.49)
		(end 92.93 106.49)
		(width 0.125)
		(layer "F.Cu")
		(net 141)
	)
	(segment
		(start 89.7 108.350488)
		(end 90.2 108.850488)
		(width 0.125)
		(layer "F.Cu")
		(net 141)
	)
	(segment
		(start 89.7 107.985488)
		(end 89.7 108.350488)
		(width 0.125)
		(layer "F.Cu")
		(net 141)
	)
	(segment
		(start 91.9 106.87)
		(end 91.554512 106.87)
		(width 0.125)
		(layer "F.Cu")
		(net 141)
	)
	(segment
		(start 89.2615 107.163012)
		(end 89.2615 107.546988)
		(width 0.125)
		(layer "F.Cu")
		(net 141)
	)
	(segment
		(start 89.533012 106.8915)
		(end 89.2615 107.163012)
		(width 0.125)
		(layer "F.Cu")
		(net 141)
	)
	(segment
		(start 90.982744 106.957256)
		(end 90.916988 106.8915)
		(width 0.125)
		(layer "F.Cu")
		(net 141)
	)
	(segment
		(start 90.478988 106.8915)
		(end 90.416988 106.9535)
		(width 0.125)
		(layer "F.Cu")
		(net 141)
	)
	(segment
		(start 89.978988 106.9535)
		(end 89.916988 106.8915)
		(width 0.125)
		(layer "F.Cu")
		(net 141)
	)
	(segment
		(start 90.2 109.215488)
		(end 90.71 109.725488)
		(width 0.125)
		(layer "F.Cu")
		(net 141)
	)
	(segment
		(start 90.916988 106.8915)
		(end 90.478988 106.8915)
		(width 0.125)
		(layer "F.Cu")
		(net 141)
	)
	(segment
		(start 89.916988 106.8915)
		(end 89.533012 106.8915)
		(width 0.125)
		(layer "F.Cu")
		(net 141)
	)
	(segment
		(start 92.45 106.97)
		(end 92 106.97)
		(width 0.125)
		(layer "F.Cu")
		(net 141)
	)
	(segment
		(start 92 106.97)
		(end 91.9 106.87)
		(width 0.125)
		(layer "F.Cu")
		(net 141)
	)
	(segment
		(start 91.467256 106.957256)
		(end 90.982744 106.957256)
		(width 0.125)
		(layer "F.Cu")
		(net 141)
	)
	(segment
		(start 90.71 109.725488)
		(end 90.71 111.36)
		(width 0.125)
		(layer "F.Cu")
		(net 141)
	)
	(segment
		(start 91.554512 106.87)
		(end 91.467256 106.957256)
		(width 0.125)
		(layer "F.Cu")
		(net 141)
	)
	(via
		(at 75.725 100.435)
		(size 0.45)
		(drill 0.2)
		(layers "F.Cu" "B.Cu")
		(remove_unused_layers yes)
		(keep_end_layers yes)
		(zone_layer_connections)
		(net 142)
	)
	(via
		(at 90.25 110.87)
		(size 0.45)
		(drill 0.2)
		(layers "F.Cu" "B.Cu")
		(remove_unused_layers yes)
		(keep_end_layers yes)
		(zone_layer_connections)
		(net 142)
	)
	(segment
		(start 91 110.67)
		(end 90.45 110.67)
		(width 0.125)
		(layer "B.Cu")
		(net 142)
	)
	(segment
		(start 92 110.67)
		(end 91 110.67)
		(width 0.125)
		(layer "B.Cu")
		(net 142)
	)
	(segment
		(start 90.45 110.67)
		(end 90.25 110.87)
		(width 0.125)
		(layer "B.Cu")
		(net 142)
	)
	(segment
		(start 88.75 108.011678)
		(end 88.75 109.37)
		(width 0.125)
		(layer "In5.Cu")
		(net 142)
	)
	(segment
		(start 75.725 100.435)
		(end 75.415 100.435)
		(width 0.125)
		(layer "In5.Cu")
		(net 142)
	)
	(segment
		(start 87.716644 102.6)
		(end 89.3 104.183356)
		(width 0.125)
		(layer "In5.Cu")
		(net 142)
	)
	(segment
		(start 89.3 107.461678)
		(end 88.75 108.011678)
		(width 0.125)
		(layer "In5.Cu")
		(net 142)
	)
	(segment
		(start 74.31 102.36)
		(end 74.55 102.6)
		(width 0.125)
		(layer "In5.Cu")
		(net 142)
	)
	(segment
		(start 89.3 104.183356)
		(end 89.3 107.461678)
		(width 0.125)
		(layer "In5.Cu")
		(net 142)
	)
	(segment
		(start 75.415 100.435)
		(end 74.31 101.54)
		(width 0.125)
		(layer "In5.Cu")
		(net 142)
	)
	(segment
		(start 74.31 101.54)
		(end 74.31 102.36)
		(width 0.125)
		(layer "In5.Cu")
		(net 142)
	)
	(segment
		(start 74.55 102.6)
		(end 87.716644 102.6)
		(width 0.125)
		(layer "In5.Cu")
		(net 142)
	)
	(segment
		(start 88.75 109.37)
		(end 90.25 110.87)
		(width 0.125)
		(layer "In5.Cu")
		(net 142)
	)
	(segment
		(start 100.164999 108.41)
		(end 102.505001 108.41)
		(width 0.16)
		(layer "F.Cu")
		(net 143)
	)
	(segment
		(start 99.829999 108.1)
		(end 99.854999 108.1)
		(width 0.16)
		(layer "F.Cu")
		(net 143)
	)
	(segment
		(start 102.950001 107.965)
		(end 103.4 107.965)
		(width 0.16)
		(layer "F.Cu")
		(net 143)
	)
	(segment
		(start 99.854999 108.1)
		(end 100.164999 108.41)
		(width 0.16)
		(layer "F.Cu")
		(net 143)
	)
	(segment
		(start 102.505001 108.41)
		(end 102.950001 107.965)
		(width 0.16)
		(layer "F.Cu")
		(net 143)
	)
	(segment
		(start 107.12 110.67)
		(end 107.12 112.5)
		(width 0.15)
		(layer "F.Cu")
		(net 149)
	)
	(segment
		(start 106 110.505)
		(end 106.955 110.505)
		(width 0.15)
		(layer "F.Cu")
		(net 149)
	)
	(segment
		(start 106.955 110.505)
		(end 107.12 110.67)
		(width 0.15)
		(layer "F.Cu")
		(net 149)
	)
	(segment
		(start 100.164999 108.79)
		(end 99.854999 109.1)
		(width 0.16)
		(layer "F.Cu")
		(net 150)
	)
	(segment
		(start 99.854999 109.1)
		(end 99.829999 109.1)
		(width 0.16)
		(layer "F.Cu")
		(net 150)
	)
	(segment
		(start 102.505 108.79)
		(end 100.164999 108.79)
		(width 0.16)
		(layer "F.Cu")
		(net 150)
	)
	(segment
		(start 103.4 109.235)
		(end 102.95 109.235)
		(width 0.16)
		(layer "F.Cu")
		(net 150)
	)
	(segment
		(start 102.95 109.235)
		(end 102.505 108.79)
		(width 0.16)
		(layer "F.Cu")
		(net 150)
	)
	(segment
		(start 74.72 107.35)
		(end 74.725 107.355)
		(width 0.2)
		(layer "F.Cu")
		(net 153)
	)
	(segment
		(start 72.9 107.35)
		(end 74.72 107.35)
		(width 0.2)
		(layer "F.Cu")
		(net 153)
	)
	(segment
		(start 83.888 67.436)
		(end 83.888 66.942)
		(width 0.3)
		(layer "F.Cu")
		(net 156)
	)
	(segment
		(start 86 66.23)
		(end 86.353 66.583)
		(width 0.3)
		(layer "F.Cu")
		(net 156)
	)
	(segment
		(start 83.888 66.942)
		(end 84.6 66.23)
		(width 0.3)
		(layer "F.Cu")
		(net 156)
	)
	(segment
		(start 86.353 66.583)
		(end 86.353 67.214)
		(width 0.3)
		(layer "F.Cu")
		(net 156)
	)
	(segment
		(start 84.6 66.23)
		(end 86 66.23)
		(width 0.3)
		(layer "F.Cu")
		(net 156)
	)
	(segment
		(start 97.8 112.313001)
		(end 96.947999 112.313001)
		(width 0.15)
		(layer "F.Cu")
		(net 157)
	)
	(via
		(at 97.8 112.313001)
		(size 0.45)
		(drill 0.2)
		(layers "F.Cu" "B.Cu")
		(remove_unused_layers yes)
		(keep_end_layers yes)
		(zone_layer_connections)
		(net 157)
	)
	(segment
		(start 97.713 112.313001)
		(end 97.36 111.960001)
		(width 0.15)
		(layer "B.Cu")
		(net 157)
	)
	(segment
		(start 97.8 112.313001)
		(end 97.713 112.313001)
		(width 0.15)
		(layer "B.Cu")
		(net 157)
	)
	(segment
		(start 97.8 114.262001)
		(end 96.947999 114.262001)
		(width 0.15)
		(layer "F.Cu")
		(net 158)
	)
	(via
		(at 97.8 114.262001)
		(size 0.45)
		(drill 0.2)
		(layers "F.Cu" "B.Cu")
		(remove_unused_layers yes)
		(keep_end_layers yes)
		(zone_layer_connections)
		(net 158)
	)
	(segment
		(start 97.498 113.960001)
		(end 97.36 113.960001)
		(width 0.15)
		(layer "B.Cu")
		(net 158)
	)
	(segment
		(start 97.8 114.262001)
		(end 97.498 113.960001)
		(width 0.15)
		(layer "B.Cu")
		(net 158)
	)
	(via
		(at 93.725 105.625)
		(size 0.45)
		(drill 0.2)
		(layers "F.Cu" "B.Cu")
		(remove_unused_layers yes)
		(keep_end_layers yes)
		(zone_layer_connections)
		(net 159)
	)
	(segment
		(start 93.725 105.975)
		(end 94.85 107.1)
		(width 0.15)
		(layer "B.Cu")
		(net 159)
	)
	(segment
		(start 94.85 107.1)
		(end 95.97 107.1)
		(width 0.15)
		(layer "B.Cu")
		(net 159)
	)
	(segment
		(start 93.725 105.625)
		(end 93.725 105.975)
		(width 0.15)
		(layer "B.Cu")
		(net 159)
	)
	(via
		(at 93.225 103.03)
		(size 0.45)
		(drill 0.2)
		(layers "F.Cu" "B.Cu")
		(remove_unused_layers yes)
		(keep_end_layers yes)
		(zone_layer_connections)
		(net 160)
	)
	(segment
		(start 94.562189 106.1)
		(end 95.97 106.1)
		(width 0.15)
		(layer "B.Cu")
		(net 160)
	)
	(segment
		(start 93.225 103.03)
		(end 93.225 104.032811)
		(width 0.15)
		(layer "B.Cu")
		(net 160)
	)
	(segment
		(start 94.274 105.446811)
		(end 94.274 105.811811)
		(width 0.15)
		(layer "B.Cu")
		(net 160)
	)
	(segment
		(start 93.692189 104.865)
		(end 94.274 105.446811)
		(width 0.15)
		(layer "B.Cu")
		(net 160)
	)
	(segment
		(start 93.692189 104.5)
		(end 93.692189 104.865)
		(width 0.15)
		(layer "B.Cu")
		(net 160)
	)
	(segment
		(start 93.225 104.032811)
		(end 93.692189 104.5)
		(width 0.15)
		(layer "B.Cu")
		(net 160)
	)
	(segment
		(start 94.274 105.811811)
		(end 94.562189 106.1)
		(width 0.15)
		(layer "B.Cu")
		(net 160)
	)
	(via
		(at 95.225 103.03)
		(size 0.45)
		(drill 0.2)
		(layers "F.Cu" "B.Cu")
		(remove_unused_layers yes)
		(keep_end_layers yes)
		(zone_layer_connections)
		(net 161)
	)
	(segment
		(start 95.225 103.355)
		(end 95.225 103.03)
		(width 0.15)
		(layer "B.Cu")
		(net 161)
	)
	(segment
		(start 95.97 104.1)
		(end 95.225 103.355)
		(width 0.15)
		(layer "B.Cu")
		(net 161)
	)
	(via
		(at 94.225 103.03)
		(size 0.45)
		(drill 0.2)
		(layers "F.Cu" "B.Cu")
		(remove_unused_layers yes)
		(keep_end_layers yes)
		(zone_layer_connections)
		(net 162)
	)
	(segment
		(start 95.038189 105.211)
		(end 95.859 105.211)
		(width 0.15)
		(layer "B.Cu")
		(net 162)
	)
	(segment
		(start 94.774 104.946811)
		(end 95.038189 105.211)
		(width 0.15)
		(layer "B.Cu")
		(net 162)
	)
	(segment
		(start 94.225 104.032811)
		(end 94.774 104.581811)
		(width 0.15)
		(layer "B.Cu")
		(net 162)
	)
	(segment
		(start 94.225 103.03)
		(end 94.225 104.032811)
		(width 0.15)
		(layer "B.Cu")
		(net 162)
	)
	(segment
		(start 94.774 104.581811)
		(end 94.774 104.946811)
		(width 0.15)
		(layer "B.Cu")
		(net 162)
	)
	(segment
		(start 95.859 105.211)
		(end 95.97 105.1)
		(width 0.15)
		(layer "B.Cu")
		(net 162)
	)
	(segment
		(start 75.225 106.49)
		(end 73.04 106.49)
		(width 0.2)
		(layer "F.Cu")
		(net 191)
	)
	(segment
		(start 73.04 106.49)
		(end 72.9 106.35)
		(width 0.2)
		(layer "F.Cu")
		(net 191)
	)
	(via
		(at 93.2 110.95)
		(size 0.45)
		(drill 0.2)
		(layers "F.Cu" "B.Cu")
		(remove_unused_layers yes)
		(keep_end_layers yes)
		(zone_layer_connections)
		(net 198)
	)
	(via
		(at 93.225 104.76)
		(size 0.45)
		(drill 0.2)
		(layers "F.Cu" "B.Cu")
		(remove_unused_layers yes)
		(keep_end_layers yes)
		(zone_layer_connections)
		(net 198)
	)
	(segment
		(start 92.82 111.63)
		(end 92 111.63)
		(width 0.125)
		(layer "B.Cu")
		(net 198)
	)
	(segment
		(start 93.2 111.25)
		(end 92.82 111.63)
		(width 0.125)
		(layer "B.Cu")
		(net 198)
	)
	(segment
		(start 93.2 110.95)
		(end 93.2 111.25)
		(width 0.125)
		(layer "B.Cu")
		(net 198)
	)
	(segment
		(start 93.2 108.85)
		(end 93.7 108.35)
		(width 0.125)
		(layer "In5.Cu")
		(net 198)
	)
	(segment
		(start 93.7 108)
		(end 93.225 107.525)
		(width 0.125)
		(layer "In5.Cu")
		(net 198)
	)
	(segment
		(start 93.225 107.525)
		(end 93.225 104.76)
		(width 0.125)
		(layer "In5.Cu")
		(net 198)
	)
	(segment
		(start 93.7 108.35)
		(end 93.7 108)
		(width 0.125)
		(layer "In5.Cu")
		(net 198)
	)
	(segment
		(start 93.2 110.95)
		(end 93.2 108.85)
		(width 0.125)
		(layer "In5.Cu")
		(net 198)
	)
	(segment
		(start 110.35 92.97)
		(end 109.35 92.97)
		(width 0.15)
		(layer "F.Cu")
		(net 215)
	)
	(segment
		(start 107.937 92.252)
		(end 107.937 92.762)
		(width 0.15)
		(layer "F.Cu")
		(net 215)
	)
	(segment
		(start 108.145 92.97)
		(end 109.35 92.97)
		(width 0.15)
		(layer "F.Cu")
		(net 215)
	)
	(segment
		(start 107.937 92.762)
		(end 108.145 92.97)
		(width 0.15)
		(layer "F.Cu")
		(net 215)
	)
	(segment
		(start 100.1 54.335)
		(end 100.1 54.338348)
		(width 0.15)
		(layer "F.Cu")
		(net 226)
	)
	(segment
		(start 100.1 54.338348)
		(end 100.25 54.488348)
		(width 0.15)
		(layer "F.Cu")
		(net 226)
	)
	(segment
		(start 100.25 54.488348)
		(end 100.25 55.500001)
		(width 0.15)
		(layer "F.Cu")
		(net 226)
	)
	(via
		(at 100.1 54.335)
		(size 0.45)
		(drill 0.2)
		(layers "F.Cu" "B.Cu")
		(remove_unused_layers yes)
		(keep_end_layers yes)
		(zone_layer_connections)
		(net 226)
	)
	(segment
		(start 107.2 67.67)
		(end 107.2 66.83)
		(width 0.15)
		(layer "B.Cu")
		(net 226)
	)
	(segment
		(start 100.1 53.985)
		(end 100.1 54.335)
		(width 0.15)
		(layer "B.Cu")
		(net 226)
	)
	(segment
		(start 107.3 53.935)
		(end 105.85 52.485)
		(width 0.15)
		(layer "B.Cu")
		(net 226)
	)
	(segment
		(start 100.252 54.490348)
		(end 100.252 55.498659)
		(width 0.15)
		(layer "B.Cu")
		(net 226)
	)
	(segment
		(start 106.35 65.98)
		(end 106.35 56.785)
		(width 0.15)
		(layer "B.Cu")
		(net 226)
	)
	(segment
		(start 107.2 66.83)
		(end 106.35 65.98)
		(width 0.15)
		(layer "B.Cu")
		(net 226)
	)
	(segment
		(start 101.6 52.485)
		(end 100.1 53.985)
		(width 0.15)
		(layer "B.Cu")
		(net 226)
	)
	(segment
		(start 105.85 52.485)
		(end 101.6 52.485)
		(width 0.15)
		(layer "B.Cu")
		(net 226)
	)
	(segment
		(start 100.1 54.335)
		(end 100.1 54.338348)
		(width 0.15)
		(layer "B.Cu")
		(net 226)
	)
	(segment
		(start 106.35 56.785)
		(end 107.3 55.835)
		(width 0.15)
		(layer "B.Cu")
		(net 226)
	)
	(segment
		(start 100.1 54.338348)
		(end 100.252 54.490348)
		(width 0.15)
		(layer "B.Cu")
		(net 226)
	)
	(segment
		(start 100.25 55.498659)
		(end 100.25 56.27066)
		(width 0.15)
		(layer "B.Cu")
		(net 226)
	)
	(segment
		(start 107.3 55.835)
		(end 107.3 53.935)
		(width 0.15)
		(layer "B.Cu")
		(net 226)
	)
	(segment
		(start 74.33 79.039996)
		(end 74.33 79.55)
		(width 0.15)
		(layer "F.Cu")
		(net 255)
	)
	(segment
		(start 68.9 85.089996)
		(end 70.7 85.089996)
		(width 0.15)
		(layer "F.Cu")
		(net 255)
	)
	(segment
		(start 52.05 128.55)
		(end 52.05 127.85)
		(width 0.15)
		(layer "F.Cu")
		(net 255)
	)
	(segment
		(start 52.05 127.85)
		(end 52.450001 127.449999)
		(width 0.15)
		(layer "F.Cu")
		(net 255)
	)
	(segment
		(start 52.450001 127.449999)
		(end 53.65 127.449999)
		(width 0.15)
		(layer "F.Cu")
		(net 255)
	)
	(segment
		(start 74.33 79.55)
		(end 74.33 80.039996)
		(width 0.15)
		(layer "F.Cu")
		(net 255)
	)
	(via
		(at 74.224997 85.184997)
		(size 0.45)
		(drill 0.1)
		(layers "F.Cu" "B.Cu")
		(remove_unused_layers yes)
		(keep_end_layers yes)
		(zone_layer_connections)
		(net 255)
	)
	(via
		(at 53.65 118.05)
		(size 0.45)
		(drill 0.2)
		(layers "F.Cu" "B.Cu")
		(remove_unused_layers yes)
		(keep_end_layers yes)
		(zone_layer_connections)
		(net 255)
	)
	(via
		(at 70.85 84.41)
		(size 0.45)
		(drill 0.1)
		(layers "F.Cu" "B.Cu")
		(remove_unused_layers yes)
		(keep_end_layers yes)
		(zone_layer_connections)
		(net 255)
	)
	(via
		(at 53.65 122.75)
		(size 0.45)
		(drill 0.2)
		(layers "F.Cu" "B.Cu")
		(remove_unused_layers yes)
		(keep_end_layers yes)
		(zone_layer_connections)
		(net 255)
	)
	(via
		(at 53.650001 120.4)
		(size 0.45)
		(drill 0.2)
		(layers "F.Cu" "B.Cu")
		(remove_unused_layers yes)
		(keep_end_layers yes)
		(zone_layer_connections)
		(net 255)
	)
	(via
		(at 68.9 85.089996)
		(size 0.45)
		(drill 0.2)
		(layers "F.Cu" "B.Cu")
		(remove_unused_layers yes)
		(keep_end_layers yes)
		(zone_layer_connections)
		(net 255)
	)
	(via
		(at 53.65 125.1)
		(size 0.45)
		(drill 0.2)
		(layers "F.Cu" "B.Cu")
		(remove_unused_layers yes)
		(keep_end_layers yes)
		(zone_layer_connections)
		(net 255)
	)
	(via
		(at 74.33 80.039996)
		(size 0.45)
		(drill 0.1)
		(layers "F.Cu" "B.Cu")
		(remove_unused_layers yes)
		(keep_end_layers yes)
		(zone_layer_connections)
		(net 255)
	)
	(via
		(at 53.65 127.449999)
		(size 0.45)
		(drill 0.2)
		(layers "F.Cu" "B.Cu")
		(remove_unused_layers yes)
		(keep_end_layers yes)
		(zone_layer_connections)
		(net 255)
	)
	(segment
		(start 56.7 113.35)
		(end 58.6 111.45)
		(width 0.15)
		(layer "B.Cu")
		(net 255)
	)
	(segment
		(start 53.65 127.449999)
		(end 53.65 118.05)
		(width 0.15)
		(layer "B.Cu")
		(net 255)
	)
	(segment
		(start 72.799 81.570996)
		(end 74.33 80.039996)
		(width 0.15)
		(layer "B.Cu")
		(net 255)
	)
	(segment
		(start 68.310004 84.5)
		(end 68.9 85.089996)
		(width 0.15)
		(layer "B.Cu")
		(net 255)
	)
	(segment
		(start 63.15 106.9)
		(end 63.15 85.05)
		(width 0.15)
		(layer "B.Cu")
		(net 255)
	)
	(segment
		(start 72.799 83.759)
		(end 72.799 81.570996)
		(width 0.15)
		(layer "B.Cu")
		(net 255)
	)
	(segment
		(start 58.6 111.45)
		(end 63.15 106.9)
		(width 0.15)
		(layer "B.Cu")
		(net 255)
	)
	(segment
		(start 56.7 115)
		(end 56.7 113.35)
		(width 0.15)
		(layer "B.Cu")
		(net 255)
	)
	(segment
		(start 63.15 85.05)
		(end 63.7 84.5)
		(width 0.15)
		(layer "B.Cu")
		(net 255)
	)
	(segment
		(start 74.224997 85.184997)
		(end 72.799 83.759)
		(width 0.15)
		(layer "B.Cu")
		(net 255)
	)
	(segment
		(start 53.65 118.05)
		(end 56.7 115)
		(width 0.15)
		(layer "B.Cu")
		(net 255)
	)
	(segment
		(start 63.7 84.5)
		(end 68.310004 84.5)
		(width 0.15)
		(layer "B.Cu")
		(net 255)
	)
	(segment
		(start 92.829801 101.997559)
		(end 92.829801 102.060199)
		(width 0.15)
		(layer "F.Cu")
		(net 286)
	)
	(segment
		(start 92.829801 102.060199)
		(end 92.725 102.165)
		(width 0.15)
		(layer "F.Cu")
		(net 286)
	)
	(via
		(at 92.829801 101.997559)
		(size 0.45)
		(drill 0.2)
		(layers "F.Cu" "B.Cu")
		(remove_unused_layers yes)
		(keep_end_layers yes)
		(zone_layer_connections)
		(net 286)
	)
	(via
		(at 97.36 109.95)
		(size 0.45)
		(drill 0.2)
		(layers "F.Cu" "B.Cu")
		(remove_unused_layers yes)
		(keep_end_layers yes)
		(zone_layer_connections)
		(net 286)
	)
	(segment
		(start 94.15 105.4)
		(end 94.15 106.74)
		(width 0.125)
		(layer "In5.Cu")
		(net 286)
	)
	(segment
		(start 93.75 104.6)
		(end 93.75 105)
		(width 0.125)
		(layer "In5.Cu")
		(net 286)
	)
	(segment
		(start 92.829801 103.679801)
		(end 93.75 104.6)
		(width 0.125)
		(layer "In5.Cu")
		(net 286)
	)
	(segment
		(start 94.15 106.74)
		(end 97.36 109.95)
		(width 0.125)
		(layer "In5.Cu")
		(net 286)
	)
	(segment
		(start 92.829801 101.997559)
		(end 92.829801 103.679801)
		(width 0.125)
		(layer "In5.Cu")
		(net 286)
	)
	(segment
		(start 93.75 105)
		(end 94.15 105.4)
		(width 0.125)
		(layer "In5.Cu")
		(net 286)
	)
	(via
		(at 88.725 105.625)
		(size 0.45)
		(drill 0.2)
		(layers "F.Cu" "B.Cu")
		(remove_unused_layers yes)
		(keep_end_layers yes)
		(zone_layer_connections)
		(net 287)
	)
	(segment
		(start 96.4 109.15)
		(end 96.4 109.95)
		(width 0.125)
		(layer "B.Cu")
		(net 287)
	)
	(segment
		(start 92.875 105.625)
		(end 96.4 109.15)
		(width 0.125)
		(layer "B.Cu")
		(net 287)
	)
	(segment
		(start 96.4 109.95)
		(end 96.4 110.95)
		(width 0.125)
		(layer "B.Cu")
		(net 287)
	)
	(segment
		(start 88.725 105.625)
		(end 92.875 105.625)
		(width 0.125)
		(layer "B.Cu")
		(net 287)
	)
	(segment
		(start 110.35 95.83)
		(end 109.35 95.83)
		(width 0.15)
		(layer "F.Cu")
		(net 288)
	)
	(segment
		(start 109.325 95.83)
		(end 108.145 95.83)
		(width 0.15)
		(layer "F.Cu")
		(net 288)
	)
	(segment
		(start 108.145 95.83)
		(end 107.937 96.038)
		(width 0.15)
		(layer "F.Cu")
		(net 288)
	)
	(segment
		(start 107.937 96.038)
		(end 107.937 96.551)
		(width 0.15)
		(layer "F.Cu")
		(net 288)
	)
	(via
		(at 94.225 96.11)
		(size 0.45)
		(drill 0.2)
		(layers "F.Cu" "B.Cu")
		(remove_unused_layers yes)
		(keep_end_layers yes)
		(zone_layer_connections)
		(net 289)
	)
	(segment
		(start 95.7 95.35)
		(end 95.95 95.6)
		(width 0.15)
		(layer "B.Cu")
		(net 289)
	)
	(segment
		(start 94.5 95.35)
		(end 95.7 95.35)
		(width 0.15)
		(layer "B.Cu")
		(net 289)
	)
	(segment
		(start 95.95 95.6)
		(end 95.95 96.02)
		(width 0.15)
		(layer "B.Cu")
		(net 289)
	)
	(segment
		(start 94.225 96.11)
		(end 94.225 95.625)
		(width 0.15)
		(layer "B.Cu")
		(net 289)
	)
	(segment
		(start 96.95 96.02)
		(end 95.95 96.02)
		(width 0.15)
		(layer "B.Cu")
		(net 289)
	)
	(segment
		(start 94.225 95.625)
		(end 94.5 95.35)
		(width 0.15)
		(layer "B.Cu")
		(net 289)
	)
	(segment
		(start 96.5 107.1)
		(end 96.92 107.1)
		(width 0.15)
		(layer "F.Cu")
		(net 290)
	)
	(segment
		(start 94.725 107.355)
		(end 96.245 107.355)
		(width 0.15)
		(layer "F.Cu")
		(net 290)
	)
	(segment
		(start 96.245 107.355)
		(end 96.5 107.1)
		(width 0.15)
		(layer "F.Cu")
		(net 290)
	)
	(segment
		(start 96.92 106.15)
		(end 96.92 107.1)
		(width 0.15)
		(layer "F.Cu")
		(net 290)
	)
	(via
		(at 76.48 144.86)
		(size 0.45)
		(drill 0.2)
		(layers "F.Cu" "B.Cu")
		(remove_unused_layers yes)
		(keep_end_layers yes)
		(zone_layer_connections)
		(net 291)
	)
	(via
		(at 75.725 95.245)
		(size 0.45)
		(drill 0.2)
		(layers "F.Cu" "B.Cu")
		(remove_unused_layers yes)
		(keep_end_layers yes)
		(zone_layer_connections)
		(net 291)
	)
	(segment
		(start 71.41 97.5)
		(end 71.41 96.08)
		(width 0.15)
		(layer "In5.Cu")
		(net 291)
	)
	(segment
		(start 81.55 128.8)
		(end 70.65 117.9)
		(width 0.15)
		(layer "In5.Cu")
		(net 291)
	)
	(segment
		(start 74.566034 95.245)
		(end 75.725 95.245)
		(width 0.15)
		(layer "In5.Cu")
		(net 291)
	)
	(segment
		(start 76.48 144.86)
		(end 76.48 136.845)
		(width 0.15)
		(layer "In5.Cu")
		(net 291)
	)
	(segment
		(start 70.65 105.661745)
		(end 70.574 105.585745)
		(width 0.15)
		(layer "In5.Cu")
		(net 291)
	)
	(segment
		(start 70.574 105.585745)
		(end 70.574 105.274255)
		(width 0.15)
		(layer "In5.Cu")
		(net 291)
	)
	(segment
		(start 71.02 97.89)
		(end 71.41 97.5)
		(width 0.15)
		(layer "In5.Cu")
		(net 291)
	)
	(segment
		(start 70.65 98.64)
		(end 71.02 98.27)
		(width 0.15)
		(layer "In5.Cu")
		(net 291)
	)
	(segment
		(start 81.55 132.94)
		(end 81.55 128.8)
		(width 0.15)
		(layer "In5.Cu")
		(net 291)
	)
	(segment
		(start 78.89 135.6)
		(end 81.55 132.94)
		(width 0.15)
		(layer "In5.Cu")
		(net 291)
	)
	(segment
		(start 73.970517 95.840517)
		(end 74.566034 95.245)
		(width 0.15)
		(layer "In5.Cu")
		(net 291)
	)
	(segment
		(start 76.48 136.845)
		(end 77.725 135.6)
		(width 0.15)
		(layer "In5.Cu")
		(net 291)
	)
	(segment
		(start 70.574 105.274255)
		(end 70.65 105.198255)
		(width 0.15)
		(layer "In5.Cu")
		(net 291)
	)
	(segment
		(start 70.65 117.9)
		(end 70.65 105.661745)
		(width 0.15)
		(layer "In5.Cu")
		(net 291)
	)
	(segment
		(start 71.649483 95.840517)
		(end 73.970517 95.840517)
		(width 0.15)
		(layer "In5.Cu")
		(net 291)
	)
	(segment
		(start 71.02 98.27)
		(end 71.02 97.89)
		(width 0.15)
		(layer "In5.Cu")
		(net 291)
	)
	(segment
		(start 77.725 135.6)
		(end 78.89 135.6)
		(width 0.15)
		(layer "In5.Cu")
		(net 291)
	)
	(segment
		(start 71.41 96.08)
		(end 71.649483 95.840517)
		(width 0.15)
		(layer "In5.Cu")
		(net 291)
	)
	(segment
		(start 70.65 105.198255)
		(end 70.65 98.64)
		(width 0.15)
		(layer "In5.Cu")
		(net 291)
	)
	(via
		(at 86.225 106.49)
		(size 0.45)
		(drill 0.2)
		(layers "F.Cu" "B.Cu")
		(remove_unused_layers yes)
		(keep_end_layers yes)
		(zone_layer_connections)
		(net 292)
	)
	(segment
		(start 84.25 102.782189)
		(end 84.25 102.48)
		(width 0.15)
		(layer "B.Cu")
		(net 292)
	)
	(segment
		(start 85.017811 103.55)
		(end 84.25 102.782189)
		(width 0.15)
		(layer "B.Cu")
		(net 292)
	)
	(segment
		(start 86.225 105.487189)
		(end 86.676 105.036189)
		(width 0.15)
		(layer "B.Cu")
		(net 292)
	)
	(segment
		(start 86.676 105.036189)
		(end 86.676 104.526)
		(width 0.15)
		(layer "B.Cu")
		(net 292)
	)
	(segment
		(start 86.225 106.49)
		(end 86.225 105.487189)
		(width 0.15)
		(layer "B.Cu")
		(net 292)
	)
	(segment
		(start 85.7 103.55)
		(end 85.017811 103.55)
		(width 0.15)
		(layer "B.Cu")
		(net 292)
	)
	(segment
		(start 86.676 104.526)
		(end 85.7 103.55)
		(width 0.15)
		(layer "B.Cu")
		(net 292)
	)
	(segment
		(start 86.201 107.570834)
		(end 85.749 108.022834)
		(width 0.125)
		(layer "F.Cu")
		(net 293)
	)
	(segment
		(start 86.1 110.65)
		(end 86.1 111.97)
		(width 0.125)
		(layer "F.Cu")
		(net 293)
	)
	(segment
		(start 86.1 111.97)
		(end 87.1 111.97)
		(width 0.15)
		(layer "F.Cu")
		(net 293)
	)
	(segment
		(start 85.725 104.933166)
		(end 86.201 105.409166)
		(width 0.125)
		(layer "F.Cu")
		(net 293)
	)
	(segment
		(start 85.749 106.705834)
		(end 86.201 107.157834)
		(width 0.125)
		(layer "F.Cu")
		(net 293)
	)
	(segment
		(start 86.201 105.840834)
		(end 85.749 106.292834)
		(width 0.125)
		(layer "F.Cu")
		(net 293)
	)
	(segment
		(start 85.749 110.299)
		(end 86.1 110.65)
		(width 0.125)
		(layer "F.Cu")
		(net 293)
	)
	(segment
		(start 86.201 109.300834)
		(end 85.749 109.752834)
		(width 0.125)
		(layer "F.Cu")
		(net 293)
	)
	(segment
		(start 86.201 107.157834)
		(end 86.201 107.570834)
		(width 0.125)
		(layer "F.Cu")
		(net 293)
	)
	(segment
		(start 86.201 108.869166)
		(end 86.201 109.300834)
		(width 0.125)
		(layer "F.Cu")
		(net 293)
	)
	(segment
		(start 85.749 108.022834)
		(end 85.749 108.417166)
		(width 0.125)
		(layer "F.Cu")
		(net 293)
	)
	(segment
		(start 86.201 105.409166)
		(end 86.201 105.840834)
		(width 0.125)
		(layer "F.Cu")
		(net 293)
	)
	(segment
		(start 85.749 106.292834)
		(end 85.749 106.705834)
		(width 0.125)
		(layer "F.Cu")
		(net 293)
	)
	(segment
		(start 85.725 103.895)
		(end 85.725 104.933166)
		(width 0.125)
		(layer "F.Cu")
		(net 293)
	)
	(segment
		(start 85.749 109.752834)
		(end 85.749 110.299)
		(width 0.125)
		(layer "F.Cu")
		(net 293)
	)
	(segment
		(start 85.749 108.417166)
		(end 86.201 108.869166)
		(width 0.125)
		(layer "F.Cu")
		(net 293)
	)
	(segment
		(start 86.75 108.436834)
		(end 86.75 108.003166)
		(width 0.125)
		(layer "F.Cu")
		(net 294)
	)
	(segment
		(start 87.701 110.351)
		(end 87.701 109.752834)
		(width 0.125)
		(layer "F.Cu")
		(net 294)
	)
	(segment
		(start 88.1 111.97)
		(end 88.1 110.75)
		(width 0.125)
		(layer "F.Cu")
		(net 294)
	)
	(segment
		(start 87.701 109.752834)
		(end 87.201 109.252834)
		(width 0.125)
		(layer "F.Cu")
		(net 294)
	)
	(segment
		(start 86.749 106.274166)
		(end 87.225 105.798166)
		(width 0.125)
		(layer "F.Cu")
		(net 294)
	)
	(segment
		(start 86.75 108.003166)
		(end 87.201 107.552166)
		(width 0.125)
		(layer "F.Cu")
		(net 294)
	)
	(segment
		(start 88.1 110.75)
		(end 87.701 110.351)
		(width 0.125)
		(layer "F.Cu")
		(net 294)
	)
	(segment
		(start 87.201 107.139166)
		(end 86.749 106.687166)
		(width 0.125)
		(layer "F.Cu")
		(net 294)
	)
	(segment
		(start 87.225 105.798166)
		(end 87.225 104.76)
		(width 0.125)
		(layer "F.Cu")
		(net 294)
	)
	(segment
		(start 86.749 106.687166)
		(end 86.749 106.274166)
		(width 0.125)
		(layer "F.Cu")
		(net 294)
	)
	(segment
		(start 87.201 108.887834)
		(end 86.75 108.436834)
		(width 0.125)
		(layer "F.Cu")
		(net 294)
	)
	(segment
		(start 87.201 107.552166)
		(end 87.201 107.139166)
		(width 0.125)
		(layer "F.Cu")
		(net 294)
	)
	(segment
		(start 87.201 109.252834)
		(end 87.201 108.887834)
		(width 0.125)
		(layer "F.Cu")
		(net 294)
	)
	(segment
		(start 89.1 111.97)
		(end 88.1 111.97)
		(width 0.15)
		(layer "F.Cu")
		(net 294)
	)
	(via
		(at 90.725 107.355)
		(size 0.45)
		(drill 0.2)
		(layers "F.Cu" "B.Cu")
		(remove_unused_layers yes)
		(keep_end_layers yes)
		(zone_layer_connections)
		(net 295)
	)
	(via
		(at 66.65 109.15)
		(size 0.45)
		(drill 0.2)
		(layers "F.Cu" "B.Cu")
		(remove_unused_layers yes)
		(keep_end_layers yes)
		(zone_layer_connections)
		(net 302)
	)
	(via
		(at 65.65 107.15)
		(size 0.45)
		(drill 0.2)
		(layers "F.Cu" "B.Cu")
		(remove_unused_layers yes)
		(keep_end_layers yes)
		(zone_layer_connections)
		(net 302)
	)
	(via
		(at 65.65 109.15)
		(size 0.45)
		(drill 0.2)
		(layers "F.Cu" "B.Cu")
		(remove_unused_layers yes)
		(keep_end_layers yes)
		(zone_layer_connections)
		(net 302)
	)
	(via
		(at 66.65 107.15)
		(size 0.45)
		(drill 0.2)
		(layers "F.Cu" "B.Cu")
		(remove_unused_layers yes)
		(keep_end_layers yes)
		(zone_layer_connections)
		(net 302)
	)
	(via
		(at 65.65 108.15)
		(size 0.45)
		(drill 0.2)
		(layers "F.Cu" "B.Cu")
		(remove_unused_layers yes)
		(keep_end_layers yes)
		(zone_layer_connections)
		(net 302)
	)
	(via
		(at 66.65 108.15)
		(size 0.45)
		(drill 0.2)
		(layers "F.Cu" "B.Cu")
		(remove_unused_layers yes)
		(keep_end_layers yes)
		(zone_layer_connections)
		(net 302)
	)
	(via
		(at 63.92 106.92)
		(size 0.45)
		(drill 0.1)
		(layers "F.Cu" "B.Cu")
		(remove_unused_layers yes)
		(keep_end_layers yes)
		(zone_layer_connections)
		(net 302)
	)
	(via
		(at 63.92 107.51)
		(size 0.45)
		(drill 0.1)
		(layers "F.Cu" "B.Cu")
		(remove_unused_layers yes)
		(keep_end_layers yes)
		(zone_layer_connections)
		(net 302)
	)
	(segment
		(start 76.76 95.847811)
		(end 76.76 96.212811)
		(width 0.15)
		(layer "B.Cu")
		(net 302)
	)
	(segment
		(start 73.899 100.799)
		(end 72.013189 100.799)
		(width 0.15)
		(layer "B.Cu")
		(net 302)
	)
	(segment
		(start 77.176 95.431811)
		(end 76.76 95.847811)
		(width 0.15)
		(layer "B.Cu")
		(net 302)
	)
	(segment
		(start 76.774 94.566811)
		(end 77.176 94.968811)
		(width 0.15)
		(layer "B.Cu")
		(net 302)
	)
	(segment
		(start 74.697811 101.1)
		(end 74.2 101.1)
		(width 0.15)
		(layer "B.Cu")
		(net 302)
	)
	(segment
		(start 75.1 99.91516)
		(end 75.21 100.02516)
		(width 0.15)
		(layer "B.Cu")
		(net 302)
	)
	(segment
		(start 77.41 90.07)
		(end 76.24 91.24)
		(width 0.15)
		(layer "B.Cu")
		(net 302)
	)
	(segment
		(start 73.249 104.601)
		(end 72.4 105.45)
		(width 0.15)
		(layer "B.Cu")
		(net 302)
	)
	(segment
		(start 75.1 98.237811)
		(end 75.1 99.91516)
		(width 0.15)
		(layer "B.Cu")
		(net 302)
	)
	(segment
		(start 74.2 101.1)
		(end 73.899 100.799)
		(width 0.15)
		(layer "B.Cu")
		(net 302)
	)
	(segment
		(start 73.249 103.036811)
		(end 73.249 104.601)
		(width 0.15)
		(layer "B.Cu")
		(net 302)
	)
	(segment
		(start 77.41 77.38)
		(end 77.41 90.07)
		(width 0.15)
		(layer "B.Cu")
		(net 302)
	)
	(segment
		(start 76.76 96.212811)
		(end 76.274 96.698811)
		(width 0.15)
		(layer "B.Cu")
		(net 302)
	)
	(segment
		(start 72.013189 100.799)
		(end 71.749 101.063189)
		(width 0.15)
		(layer "B.Cu")
		(net 302)
	)
	(segment
		(start 76.274 96.698811)
		(end 76.274 97.063811)
		(width 0.15)
		(layer "B.Cu")
		(net 302)
	)
	(segment
		(start 77.176 94.968811)
		(end 77.176 95.431811)
		(width 0.15)
		(layer "B.Cu")
		(net 302)
	)
	(segment
		(start 76.24 91.24)
		(end 76.24 92.37)
		(width 0.15)
		(layer "B.Cu")
		(net 302)
	)
	(segment
		(start 71.749 101.536811)
		(end 73.249 103.036811)
		(width 0.15)
		(layer "B.Cu")
		(net 302)
	)
	(segment
		(start 76.774 92.904)
		(end 76.774 94.566811)
		(width 0.15)
		(layer "B.Cu")
		(net 302)
	)
	(segment
		(start 71.749 101.063189)
		(end 71.749 101.536811)
		(width 0.15)
		(layer "B.Cu")
		(net 302)
	)
	(segment
		(start 75.21 100.02516)
		(end 75.21 100.587811)
		(width 0.15)
		(layer "B.Cu")
		(net 302)
	)
	(segment
		(start 80.24 74.55)
		(end 77.41 77.38)
		(width 0.15)
		(layer "B.Cu")
		(net 302)
	)
	(segment
		(start 75.21 100.587811)
		(end 74.697811 101.1)
		(width 0.15)
		(layer "B.Cu")
		(net 302)
	)
	(segment
		(start 76.274 97.063811)
		(end 75.1 98.237811)
		(width 0.15)
		(layer "B.Cu")
		(net 302)
	)
	(segment
		(start 76.24 92.37)
		(end 76.774 92.904)
		(width 0.15)
		(layer "B.Cu")
		(net 302)
	)
	(segment
		(start 54.249999 126.200001)
		(end 52.05 126.200001)
		(width 0.15)
		(layer "F.Cu")
		(net 303)
	)
	(segment
		(start 55.100001 84.669999)
		(end 56.100001 84.669999)
		(width 0.15)
		(layer "F.Cu")
		(net 303)
	)
	(via
		(at 61.925 84.775001)
		(size 0.45)
		(drill 0.1)
		(layers "F.Cu" "B.Cu")
		(remove_unused_layers yes)
		(keep_end_layers yes)
		(zone_layer_connections)
		(net 303)
	)
	(via
		(at 61.150003 88.449998)
		(size 0.45)
		(drill 0.1)
		(layers "F.Cu" "B.Cu")
		(remove_unused_layers yes)
		(keep_end_layers yes)
		(zone_layer_connections)
		(net 303)
	)
	(via
		(at 56.1 84.669999)
		(size 0.45)
		(drill 0.1)
		(layers "F.Cu" "B.Cu")
		(remove_unused_layers yes)
		(keep_end_layers yes)
		(zone_layer_connections)
		(net 303)
	)
	(via
		(at 54.249999 126.200001)
		(size 0.45)
		(drill 0.2)
		(layers "F.Cu" "B.Cu")
		(remove_unused_layers yes)
		(keep_end_layers yes)
		(zone_layer_connections)
		(net 303)
	)
	(segment
		(start 56.1 84.669999)
		(end 56.550998 84.219001)
		(width 0.15)
		(layer "B.Cu")
		(net 303)
	)
	(segment
		(start 56.550998 84.219001)
		(end 58.030999 84.219001)
		(width 0.15)
		(layer "B.Cu")
		(net 303)
	)
	(segment
		(start 54.249999 126.200001)
		(end 54.85 125.6)
		(width 0.15)
		(layer "B.Cu")
		(net 303)
	)
	(segment
		(start 60.399999 83.25)
		(end 61.925 84.775001)
		(width 0.15)
		(layer "B.Cu")
		(net 303)
	)
	(segment
		(start 54.85 125.6)
		(end 55.598 125.6)
		(width 0.15)
		(layer "B.Cu")
		(net 303)
	)
	(segment
		(start 59 83.25)
		(end 60.399999 83.25)
		(width 0.15)
		(layer "B.Cu")
		(net 303)
	)
	(segment
		(start 58.030999 84.219001)
		(end 59 83.25)
		(width 0.15)
		(layer "B.Cu")
		(net 303)
	)
	(segment
		(start 54.249999 126.200001)
		(end 55.149999 126.200001)
		(width 0.15)
		(layer "In5.Cu")
		(net 303)
	)
	(segment
		(start 63.37 115.53)
		(end 63.37 96.52)
		(width 0.15)
		(layer "In5.Cu")
		(net 303)
	)
	(segment
		(start 63.37 96.52)
		(end 60.5 93.65)
		(width 0.15)
		(layer "In5.Cu")
		(net 303)
	)
	(segment
		(start 60.5 89.100001)
		(end 61.150003 88.449998)
		(width 0.15)
		(layer "In5.Cu")
		(net 303)
	)
	(segment
		(start 58.575 120.325)
		(end 63.37 115.53)
		(width 0.15)
		(layer "In5.Cu")
		(net 303)
	)
	(segment
		(start 58.575 122.775)
		(end 58.575 120.325)
		(width 0.15)
		(layer "In5.Cu")
		(net 303)
	)
	(segment
		(start 55.149999 126.200001)
		(end 58.575 122.775)
		(width 0.15)
		(layer "In5.Cu")
		(net 303)
	)
	(segment
		(start 60.5 93.65)
		(end 60.5 89.100001)
		(width 0.15)
		(layer "In5.Cu")
		(net 303)
	)
	(segment
		(start 100.75 54.488967)
		(end 100.75 55.500001)
		(width 0.15)
		(layer "F.Cu")
		(net 304)
	)
	(segment
		(start 100.9 54.338967)
		(end 100.75 54.488967)
		(width 0.15)
		(layer "F.Cu")
		(net 304)
	)
	(segment
		(start 100.9 54.335)
		(end 100.9 54.338967)
		(width 0.15)
		(layer "F.Cu")
		(net 304)
	)
	(via
		(at 100.9 54.335)
		(size 0.45)
		(drill 0.2)
		(layers "F.Cu" "B.Cu")
		(remove_unused_layers yes)
		(keep_end_layers yes)
		(zone_layer_connections)
		(net 304)
	)
	(segment
		(start 100.9 54.335)
		(end 101.9 53.335)
		(width 0.15)
		(layer "B.Cu")
		(net 304)
	)
	(segment
		(start 106.2 66.82)
		(end 106.2 67.67)
		(width 0.15)
		(layer "B.Cu")
		(net 304)
	)
	(segment
		(start 100.9 54.338967)
		(end 100.752 54.486967)
		(width 0.15)
		(layer "B.Cu")
		(net 304)
	)
	(segment
		(start 105.55 53.335)
		(end 106.5 54.285)
		(width 0.15)
		(layer "B.Cu")
		(net 304)
	)
	(segment
		(start 105.65 66.27)
		(end 106.2 66.82)
		(width 0.15)
		(layer "B.Cu")
		(net 304)
	)
	(segment
		(start 100.9 54.335)
		(end 100.9 54.338967)
		(width 0.15)
		(layer "B.Cu")
		(net 304)
	)
	(segment
		(start 100.75 55.49866)
		(end 100.75 56.27066)
		(width 0.15)
		(layer "B.Cu")
		(net 304)
	)
	(segment
		(start 105.65 56.385)
		(end 105.65 66.27)
		(width 0.15)
		(layer "B.Cu")
		(net 304)
	)
	(segment
		(start 101.9 53.335)
		(end 105.55 53.335)
		(width 0.15)
		(layer "B.Cu")
		(net 304)
	)
	(segment
		(start 100.752 54.486967)
		(end 100.752 55.49866)
		(width 0.15)
		(layer "B.Cu")
		(net 304)
	)
	(segment
		(start 106.5 55.535)
		(end 105.65 56.385)
		(width 0.15)
		(layer "B.Cu")
		(net 304)
	)
	(segment
		(start 106.5 54.285)
		(end 106.5 55.535)
		(width 0.15)
		(layer "B.Cu")
		(net 304)
	)
	(segment
		(start 80.675 82.499)
		(end 80.675 81.566202)
		(width 0.15)
		(layer "F.Cu")
		(net 308)
	)
	(segment
		(start 80.675 81.566202)
		(end 80.671263 81.562465)
		(width 0.15)
		(layer "F.Cu")
		(net 308)
	)
	(segment
		(start 80.829999 82.653999)
		(end 80.675 82.499)
		(width 0.15)
		(layer "F.Cu")
		(net 308)
	)
	(segment
		(start 80.829999 83.15)
		(end 80.829999 82.653999)
		(width 0.15)
		(layer "F.Cu")
		(net 308)
	)
	(via
		(at 108.1 67.9)
		(size 0.45)
		(drill 0.2)
		(layers "F.Cu" "B.Cu")
		(remove_unused_layers yes)
		(keep_end_layers yes)
		(zone_layer_connections)
		(net 308)
	)
	(via
		(at 95.225 97.84)
		(size 0.45)
		(drill 0.2)
		(layers "F.Cu" "B.Cu")
		(remove_unused_layers yes)
		(keep_end_layers yes)
		(zone_layer_connections)
		(net 308)
	)
	(via
		(at 80.671263 81.562465)
		(size 0.45)
		(drill 0.2)
		(layers "F.Cu" "B.Cu")
		(remove_unused_layers yes)
		(keep_end_layers yes)
		(zone_layer_connections)
		(net 308)
	)
	(segment
		(start 108.4 67.6)
		(end 108.1 67.9)
		(width 0.15)
		(layer "B.Cu")
		(net 308)
	)
	(segment
		(start 109.02 67.6)
		(end 108.4 67.6)
		(width 0.15)
		(layer "B.Cu")
		(net 308)
	)
	(segment
		(start 80.671263 76.428737)
		(end 87.125 69.975)
		(width 0.15)
		(layer "In5.Cu")
		(net 308)
	)
	(segment
		(start 110.84 85.7)
		(end 110.84 74.59)
		(width 0.15)
		(layer "In5.Cu")
		(net 308)
	)
	(segment
		(start 110.96 89.78)
		(end 110.96 89.232189)
		(width 0.15)
		(layer "In5.Cu")
		(net 308)
	)
	(segment
		(start 89.075 69.975)
		(end 91.85 67.2)
		(width 0.15)
		(layer "In5.Cu")
		(net 308)
	)
	(segment
		(start 95.225 97.84)
		(end 95.225 97.205)
		(width 0.15)
		(layer "In5.Cu")
		(net 308)
	)
	(segment
		(start 108.018906 92.721094)
		(end 110.96 89.78)
		(width 0.15)
		(layer "In5.Cu")
		(net 308)
	)
	(segment
		(start 109.09 67.9)
		(end 108.1 67.9)
		(width 0.15)
		(layer "In5.Cu")
		(net 308)
	)
	(segment
		(start 96.99 95.44)
		(end 105.64 95.44)
		(width 0.15)
		(layer "In5.Cu")
		(net 308)
	)
	(segment
		(start 105.64 95.44)
		(end 108.018906 93.061094)
		(width 0.15)
		(layer "In5.Cu")
		(net 308)
	)
	(segment
		(start 107.4 67.2)
		(end 108.1 67.9)
		(width 0.15)
		(layer "In5.Cu")
		(net 308)
	)
	(segment
		(start 95.225 97.205)
		(end 96.99 95.44)
		(width 0.15)
		(layer "In5.Cu")
		(net 308)
	)
	(segment
		(start 80.671263 81.562465)
		(end 80.671263 76.428737)
		(width 0.15)
		(layer "In5.Cu")
		(net 308)
	)
	(segment
		(start 91.85 67.2)
		(end 107.4 67.2)
		(width 0.15)
		(layer "In5.Cu")
		(net 308)
	)
	(segment
		(start 87.125 69.975)
		(end 89.075 69.975)
		(width 0.15)
		(layer "In5.Cu")
		(net 308)
	)
	(segment
		(start 110.84 74.59)
		(end 109.529 73.279)
		(width 0.15)
		(layer "In5.Cu")
		(net 308)
	)
	(segment
		(start 112.11 86.97)
		(end 110.84 85.7)
		(width 0.15)
		(layer "In5.Cu")
		(net 308)
	)
	(segment
		(start 110.96 89.232189)
		(end 112.11 88.08219)
		(width 0.15)
		(layer "In5.Cu")
		(net 308)
	)
	(segment
		(start 109.529 73.279)
		(end 109.529 68.339)
		(width 0.15)
		(layer "In5.Cu")
		(net 308)
	)
	(segment
		(start 112.11 88.08219)
		(end 112.11 86.97)
		(width 0.15)
		(layer "In5.Cu")
		(net 308)
	)
	(segment
		(start 109.529 68.339)
		(end 109.09 67.9)
		(width 0.15)
		(layer "In5.Cu")
		(net 308)
	)
	(segment
		(start 108.018906 93.061094)
		(end 108.018906 92.721094)
		(width 0.15)
		(layer "In5.Cu")
		(net 308)
	)
	(via
		(at 94.725 98.705)
		(size 0.45)
		(drill 0.2)
		(layers "F.Cu" "B.Cu")
		(remove_unused_layers yes)
		(keep_end_layers yes)
		(zone_layer_connections)
		(net 309)
	)
	(via
		(at 110.35 72.8)
		(size 0.45)
		(drill 0.2)
		(layers "F.Cu" "B.Cu")
		(remove_unused_layers yes)
		(keep_end_layers yes)
		(zone_layer_connections)
		(net 309)
	)
	(segment
		(start 109.5 72.8)
		(end 109.02 72.32)
		(width 0.15)
		(layer "B.Cu")
		(net 309)
	)
	(segment
		(start 109.02 72.32)
		(end 109.02 71.6)
		(width 0.15)
		(layer "B.Cu")
		(net 309)
	)
	(segment
		(start 110.35 72.8)
		(end 109.5 72.8)
		(width 0.15)
		(layer "B.Cu")
		(net 309)
	)
	(segment
		(start 94.725 98.705)
		(end 95.145 98.705)
		(width 0.15)
		(layer "In5.Cu")
		(net 309)
	)
	(segment
		(start 95.78 97.4)
		(end 97.17 96.01)
		(width 0.15)
		(layer "In5.Cu")
		(net 309)
	)
	(segment
		(start 105.84 96.01)
		(end 113.11 88.74)
		(width 0.15)
		(layer "In5.Cu")
		(net 309)
	)
	(segment
		(start 113.11 88.74)
		(end 113.11 86.69)
		(width 0.15)
		(layer "In5.Cu")
		(net 309)
	)
	(segment
		(start 95.145 98.705)
		(end 95.78 98.07)
		(width 0.15)
		(layer "In5.Cu")
		(net 309)
	)
	(segment
		(start 95.78 98.07)
		(end 95.78 97.4)
		(width 0.15)
		(layer "In5.Cu")
		(net 309)
	)
	(segment
		(start 113.11 86.69)
		(end 111.7 85.28)
		(width 0.15)
		(layer "In5.Cu")
		(net 309)
	)
	(segment
		(start 111.7 85.28)
		(end 111.7 74.15)
		(width 0.15)
		(layer "In5.Cu")
		(net 309)
	)
	(segment
		(start 111.7 74.15)
		(end 110.35 72.8)
		(width 0.15)
		(layer "In5.Cu")
		(net 309)
	)
	(segment
		(start 97.17 96.01)
		(end 105.84 96.01)
		(width 0.15)
		(layer "In5.Cu")
		(net 309)
	)
	(segment
		(start 54.249999 123.850001)
		(end 52.05 123.850001)
		(width 0.15)
		(layer "F.Cu")
		(net 310)
	)
	(segment
		(start 55.1 100.069999)
		(end 56.1 100.07)
		(width 0.15)
		(layer "F.Cu")
		(net 310)
	)
	(via
		(at 56.1 100.07)
		(size 0.45)
		(drill 0.1)
		(layers "F.Cu" "B.Cu")
		(remove_unused_layers yes)
		(keep_end_layers yes)
		(zone_layer_connections)
		(net 310)
	)
	(via
		(at 61.150003 103.849999)
		(size 0.45)
		(drill 0.1)
		(layers "F.Cu" "B.Cu")
		(remove_unused_layers yes)
		(keep_end_layers yes)
		(zone_layer_connections)
		(net 310)
	)
	(via
		(at 54.249999 123.850001)
		(size 0.45)
		(drill 0.2)
		(layers "F.Cu" "B.Cu")
		(remove_unused_layers yes)
		(keep_end_layers yes)
		(zone_layer_connections)
		(net 310)
	)
	(via
		(at 61.349999 99.500001)
		(size 0.45)
		(drill 0.1)
		(layers "F.Cu" "B.Cu")
		(remove_unused_layers yes)
		(keep_end_layers yes)
		(zone_layer_connections)
		(net 310)
	)
	(segment
		(start 54.85 123.25)
		(end 55.598 123.25)
		(width 0.15)
		(layer "B.Cu")
		(net 310)
	)
	(segment
		(start 54.249999 123.850001)
		(end 54.85 123.25)
		(width 0.15)
		(layer "B.Cu")
		(net 310)
	)
	(segment
		(start 60.618998 98.769)
		(end 57.401 98.769)
		(width 0.15)
		(layer "B.Cu")
		(net 310)
	)
	(segment
		(start 57.401 98.769)
		(end 56.1 100.07)
		(width 0.15)
		(layer "B.Cu")
		(net 310)
	)
	(segment
		(start 61.349999 99.500001)
		(end 60.618998 98.769)
		(width 0.15)
		(layer "B.Cu")
		(net 310)
	)
	(segment
		(start 54.249999 123.850001)
		(end 56.75 121.35)
		(width 0.15)
		(layer "In5.Cu")
		(net 310)
	)
	(segment
		(start 62.1 104.799996)
		(end 61.150003 103.849999)
		(width 0.15)
		(layer "In5.Cu")
		(net 310)
	)
	(segment
		(start 56.75 121.35)
		(end 56.75 119.72)
		(width 0.15)
		(layer "In5.Cu")
		(net 310)
	)
	(segment
		(start 62.1 114.37)
		(end 62.1 104.799996)
		(width 0.15)
		(layer "In5.Cu")
		(net 310)
	)
	(segment
		(start 56.75 119.72)
		(end 62.1 114.37)
		(width 0.15)
		(layer "In5.Cu")
		(net 310)
	)
	(segment
		(start 55.099999 92.369999)
		(end 56.099998 92.369999)
		(width 0.15)
		(layer "F.Cu")
		(net 311)
	)
	(segment
		(start 56.099998 92.369999)
		(end 56.1 92.369997)
		(width 0.15)
		(layer "F.Cu")
		(net 311)
	)
	(segment
		(start 55.1 92.369997)
		(end 55.099999 92.369999)
		(width 0.15)
		(layer "F.Cu")
		(net 311)
	)
	(segment
		(start 54.249999 119.150001)
		(end 52.05 119.150001)
		(width 0.15)
		(layer "F.Cu")
		(net 311)
	)
	(via
		(at 56.099998 92.369998)
		(size 0.45)
		(drill 0.1)
		(layers "F.Cu" "B.Cu")
		(remove_unused_layers yes)
		(keep_end_layers yes)
		(zone_layer_connections)
		(net 311)
	)
	(via
		(at 61.299999 91.850001)
		(size 0.45)
		(drill 0.1)
		(layers "F.Cu" "B.Cu")
		(remove_unused_layers yes)
		(keep_end_layers yes)
		(zone_layer_connections)
		(net 311)
	)
	(via
		(at 54.249999 119.150001)
		(size 0.45)
		(drill 0.2)
		(layers "F.Cu" "B.Cu")
		(remove_unused_layers yes)
		(keep_end_layers yes)
		(zone_layer_connections)
		(net 311)
	)
	(via
		(at 61.150001 96.149997)
		(size 0.45)
		(drill 0.1)
		(layers "F.Cu" "B.Cu")
		(remove_unused_layers yes)
		(keep_end_layers yes)
		(zone_layer_connections)
		(net 311)
	)
	(segment
		(start 60.469998 91.02)
		(end 57.449996 91.02)
		(width 0.15)
		(layer "B.Cu")
		(net 311)
	)
	(segment
		(start 61.299999 91.850001)
		(end 60.469998 91.02)
		(width 0.15)
		(layer "B.Cu")
		(net 311)
	)
	(segment
		(start 54.85 118.55)
		(end 55.598 118.55)
		(width 0.15)
		(layer "B.Cu")
		(net 311)
	)
	(segment
		(start 57.449996 91.02)
		(end 56.099998 92.369998)
		(width 0.15)
		(layer "B.Cu")
		(net 311)
	)
	(segment
		(start 54.249999 119.150001)
		(end 54.85 118.55)
		(width 0.15)
		(layer "B.Cu")
		(net 311)
	)
	(segment
		(start 54.249999 119.150001)
		(end 54.249999 115.400001)
		(width 0.15)
		(layer "In5.Cu")
		(net 311)
	)
	(segment
		(start 54.249999 115.400001)
		(end 58.5 111.15)
		(width 0.15)
		(layer "In5.Cu")
		(net 311)
	)
	(segment
		(start 58.5 98.799998)
		(end 61.150001 96.149997)
		(width 0.15)
		(layer "In5.Cu")
		(net 311)
	)
	(segment
		(start 58.5 111.15)
		(end 58.5 98.799998)
		(width 0.15)
		(layer "In5.Cu")
		(net 311)
	)
	(segment
		(start 56.099997 107.769996)
		(end 56.1 107.769999)
		(width 0.15)
		(layer "F.Cu")
		(net 312)
	)
	(segment
		(start 55.1 107.769996)
		(end 56.099997 107.769996)
		(width 0.15)
		(layer "F.Cu")
		(net 312)
	)
	(segment
		(start 54.249999 121.500001)
		(end 52.050001 121.500001)
		(width 0.15)
		(layer "F.Cu")
		(net 312)
	)
	(via
		(at 56.1 107.769999)
		(size 0.45)
		(drill 0.1)
		(layers "F.Cu" "B.Cu")
		(remove_unused_layers yes)
		(keep_end_layers yes)
		(zone_layer_connections)
		(net 312)
	)
	(via
		(at 61.150003 111.549998)
		(size 0.45)
		(drill 0.1)
		(layers "F.Cu" "B.Cu")
		(remove_unused_layers yes)
		(keep_end_layers yes)
		(zone_layer_connections)
		(net 312)
	)
	(via
		(at 54.249999 121.500001)
		(size 0.45)
		(drill 0.2)
		(layers "F.Cu" "B.Cu")
		(remove_unused_layers yes)
		(keep_end_layers yes)
		(zone_layer_connections)
		(net 312)
	)
	(via
		(at 61.304999 107.255001)
		(size 0.45)
		(drill 0.1)
		(layers "F.Cu" "B.Cu")
		(remove_unused_layers yes)
		(keep_end_layers yes)
		(zone_layer_connections)
		(net 312)
	)
	(segment
		(start 54.249999 121.500001)
		(end 54.85 120.9)
		(width 0.15)
		(layer "B.Cu")
		(net 312)
	)
	(segment
		(start 54.85 120.9)
		(end 55.598 120.9)
		(width 0.15)
		(layer "B.Cu")
		(net 312)
	)
	(segment
		(start 56.1 107.769999)
		(end 57.419999 106.45)
		(width 0.15)
		(layer "B.Cu")
		(net 312)
	)
	(segment
		(start 60.499999 106.45)
		(end 61.304999 107.255001)
		(width 0.15)
		(layer "B.Cu")
		(net 312)
	)
	(segment
		(start 57.419999 106.45)
		(end 60.499999 106.45)
		(width 0.15)
		(layer "B.Cu")
		(net 312)
	)
	(segment
		(start 54.249999 121.500001)
		(end 56.051 119.699)
		(width 0.15)
		(layer "In5.Cu")
		(net 312)
	)
	(segment
		(start 56.051 116.649001)
		(end 61.150003 111.549998)
		(width 0.15)
		(layer "In5.Cu")
		(net 312)
	)
	(segment
		(start 56.051 119.699)
		(end 56.051 116.649001)
		(width 0.15)
		(layer "In5.Cu")
		(net 312)
	)
	(segment
		(start 116.47 105.55)
		(end 116.47 106.55)
		(width 0.5)
		(layer "F.Cu")
		(net 314)
	)
	(segment
		(start 73.37 76.039996)
		(end 73.37 75.62)
		(width 0.15)
		(layer "F.Cu")
		(net 314)
	)
	(segment
		(start 70.124999 75.475001)
		(end 70.124999 75.514995)
		(width 0.15)
		(layer "F.Cu")
		(net 314)
	)
	(segment
		(start 118.329 104.351)
		(end 117.251 104.351)
		(width 0.3)
		(layer "F.Cu")
		(net 314)
	)
	(segment
		(start 116.3 102.751)
		(end 116.3 104.051)
		(width 0.15)
		(layer "F.Cu")
		(net 314)
	)
	(segment
		(start 65.75 67.456)
		(end 65.77 67.436)
		(width 0.125)
		(layer "F.Cu")
		(net 314)
	)
	(segment
		(start 116.3 104.051)
		(end 116.6 104.351)
		(width 0.15)
		(layer "F.Cu")
		(net 314)
	)
	(segment
		(start 81.89 67.456)
		(end 81.91 67.436)
		(width 0.125)
		(layer "F.Cu")
		(net 314)
	)
	(segment
		(start 81.89 68.35)
		(end 81.89 67.456)
		(width 0.125)
		(layer "F.Cu")
		(net 314)
	)
	(segment
		(start 72.6 74.85)
		(end 70.75 74.85)
		(width 0.15)
		(layer "F.Cu")
		(net 314)
	)
	(segment
		(start 65.75 68.35)
		(end 65.75 67.456)
		(width 0.125)
		(layer "F.Cu")
		(net 314)
	)
	(segment
		(start 70.75 74.85)
		(end 70.124999 75.475001)
		(width 0.15)
		(layer "F.Cu")
		(net 314)
	)
	(segment
		(start 116.6 102.451)
		(end 116.3 102.751)
		(width 0.15)
		(layer "F.Cu")
		(net 314)
	)
	(segment
		(start 118.33 104.35)
		(end 118.329 104.351)
		(width 0.3)
		(layer "F.Cu")
		(net 314)
	)
	(segment
		(start 73.37 75.62)
		(end 72.6 74.85)
		(width 0.15)
		(layer "F.Cu")
		(net 314)
	)
	(segment
		(start 116.6 104.351)
		(end 117.251 104.351)
		(width 0.15)
		(layer "F.Cu")
		(net 314)
	)
	(segment
		(start 117.251001 102.451)
		(end 116.6 102.451)
		(width 0.15)
		(layer "F.Cu")
		(net 314)
	)
	(via
		(at 52.575 88.875)
		(size 0.45)
		(drill 0.1)
		(layers "F.Cu" "B.Cu")
		(remove_unused_layers yes)
		(keep_end_layers yes)
		(zone_layer_connections "In3.Cu")
		(net 314)
	)
	(via
		(at 82.89 69.35)
		(size 0.45)
		(drill 0.2)
		(layers "F.Cu" "B.Cu")
		(remove_unused_layers yes)
		(keep_end_layers yes)
		(zone_layer_connections "In3.Cu")
		(net 314)
	)
	(via
		(at 69.124999 76.514996)
		(size 0.45)
		(drill 0.1)
		(layers "F.Cu" "B.Cu")
		(remove_unused_layers yes)
		(keep_end_layers yes)
		(zone_layer_connections "In3.Cu")
		(net 314)
	)
	(via
		(at 53.575 96.575001)
		(size 0.45)
		(drill 0.1)
		(layers "F.Cu" "B.Cu")
		(remove_unused_layers yes)
		(keep_end_layers yes)
		(zone_layer_connections "In3.Cu")
		(net 314)
	)
	(via
		(at 116.47 106.55)
		(size 0.45)
		(drill 0.2)
		(layers "F.Cu" "B.Cu")
		(remove_unused_layers yes)
		(keep_end_layers yes)
		(zone_layer_connections "In3.Cu")
		(net 314)
	)
	(via
		(at 53.575001 111.975001)
		(size 0.45)
		(drill 0.1)
		(layers "F.Cu" "B.Cu")
		(remove_unused_layers yes)
		(keep_end_layers yes)
		(zone_layer_connections "In3.Cu")
		(net 314)
	)
	(via
		(at 69.124999 77.514996)
		(size 0.45)
		(drill 0.1)
		(layers "F.Cu" "B.Cu")
		(remove_unused_layers yes)
		(keep_end_layers yes)
		(zone_layer_connections "In3.Cu")
		(net 314)
	)
	(via
		(at 53.575001 89.875)
		(size 0.45)
		(drill 0.1)
		(layers "F.Cu" "B.Cu")
		(remove_unused_layers yes)
		(keep_end_layers yes)
		(zone_layer_connections "In3.Cu")
		(net 314)
	)
	(via
		(at 52.574999 97.575001)
		(size 0.45)
		(drill 0.1)
		(layers "F.Cu" "B.Cu")
		(remove_unused_layers yes)
		(keep_end_layers yes)
		(zone_layer_connections "In3.Cu")
		(net 314)
	)
	(via
		(at 52.575 112.975001)
		(size 0.45)
		(drill 0.1)
		(layers "F.Cu" "B.Cu")
		(remove_unused_layers yes)
		(keep_end_layers yes)
		(zone_layer_connections "In3.Cu")
		(net 314)
	)
	(via
		(at 53.575 105.275002)
		(size 0.45)
		(drill 0.1)
		(layers "F.Cu" "B.Cu")
		(remove_unused_layers yes)
		(keep_end_layers yes)
		(zone_layer_connections "In3.Cu")
		(net 314)
	)
	(via
		(at 53.574999 97.575001)
		(size 0.45)
		(drill 0.1)
		(layers "F.Cu" "B.Cu")
		(remove_unused_layers yes)
		(keep_end_layers yes)
		(zone_layer_connections "In3.Cu")
		(net 314)
	)
	(via
		(at 67.75 69.35)
		(size 0.45)
		(drill 0.2)
		(layers "F.Cu" "B.Cu")
		(remove_unused_layers yes)
		(keep_end_layers yes)
		(zone_layer_connections "In3.Cu")
		(net 314)
	)
	(via
		(at 116.47 105.55)
		(size 0.45)
		(drill 0.2)
		(layers "F.Cu" "B.Cu")
		(remove_unused_layers yes)
		(keep_end_layers yes)
		(zone_layer_connections "In3.Cu")
		(net 314)
	)
	(via
		(at 51.575001 89.875)
		(size 0.45)
		(drill 0.1)
		(layers "F.Cu" "B.Cu")
		(remove_unused_layers yes)
		(keep_end_layers yes)
		(zone_layer_connections "In3.Cu")
		(net 314)
	)
	(via
		(at 54.575001 88.875)
		(size 0.45)
		(drill 0.1)
		(layers "F.Cu" "B.Cu")
		(remove_unused_layers yes)
		(keep_end_layers yes)
		(zone_layer_connections "In3.Cu")
		(net 314)
	)
	(via
		(at 65.75 68.35)
		(size 0.45)
		(drill 0.2)
		(layers "F.Cu" "B.Cu")
		(remove_unused_layers yes)
		(keep_end_layers yes)
		(zone_layer_connections "In3.Cu")
		(net 314)
	)
	(via
		(at 69.124999 75.514996)
		(size 0.45)
		(drill 0.1)
		(layers "F.Cu" "B.Cu")
		(remove_unused_layers yes)
		(keep_end_layers yes)
		(zone_layer_connections "In3.Cu")
		(net 314)
	)
	(via
		(at 82.89 68.35)
		(size 0.45)
		(drill 0.2)
		(layers "F.Cu" "B.Cu")
		(remove_unused_layers yes)
		(keep_end_layers yes)
		(zone_layer_connections "In3.Cu")
		(net 314)
	)
	(via
		(at 81.89 68.35)
		(size 0.45)
		(drill 0.2)
		(layers "F.Cu" "B.Cu")
		(remove_unused_layers yes)
		(keep_end_layers yes)
		(zone_layer_connections "In3.Cu")
		(net 314)
	)
	(via
		(at 52.574999 104.275002)
		(size 0.45)
		(drill 0.1)
		(layers "F.Cu" "B.Cu")
		(remove_unused_layers yes)
		(keep_end_layers yes)
		(zone_layer_connections "In3.Cu")
		(net 314)
	)
	(via
		(at 51.575 105.275002)
		(size 0.45)
		(drill 0.1)
		(layers "F.Cu" "B.Cu")
		(remove_unused_layers yes)
		(keep_end_layers yes)
		(zone_layer_connections "In3.Cu")
		(net 314)
	)
	(via
		(at 52.575 105.275002)
		(size 0.45)
		(drill 0.1)
		(layers "F.Cu" "B.Cu")
		(remove_unused_layers yes)
		(keep_end_layers yes)
		(zone_layer_connections "In3.Cu")
		(net 314)
	)
	(via
		(at 81.89 69.35)
		(size 0.45)
		(drill 0.2)
		(layers "F.Cu" "B.Cu")
		(remove_unused_layers yes)
		(keep_end_layers yes)
		(zone_layer_connections "In3.Cu")
		(net 314)
	)
	(via
		(at 70.124999 78.514996)
		(size 0.45)
		(drill 0.1)
		(layers "F.Cu" "B.Cu")
		(remove_unused_layers yes)
		(keep_end_layers yes)
		(zone_layer_connections "In3.Cu")
		(net 314)
	)
	(via
		(at 69.124999 78.514996)
		(size 0.45)
		(drill 0.1)
		(layers "F.Cu" "B.Cu")
		(remove_unused_layers yes)
		(keep_end_layers yes)
		(zone_layer_connections "In3.Cu")
		(net 314)
	)
	(via
		(at 65.75 69.35)
		(size 0.45)
		(drill 0.2)
		(layers "F.Cu" "B.Cu")
		(remove_unused_layers yes)
		(keep_end_layers yes)
		(zone_layer_connections "In3.Cu")
		(net 314)
	)
	(via
		(at 66.75 69.35)
		(size 0.45)
		(drill 0.2)
		(layers "F.Cu" "B.Cu")
		(remove_unused_layers yes)
		(keep_end_layers yes)
		(zone_layer_connections "In3.Cu")
		(net 314)
	)
	(via
		(at 51.575001 88.875)
		(size 0.45)
		(drill 0.1)
		(layers "F.Cu" "B.Cu")
		(remove_unused_layers yes)
		(keep_end_layers yes)
		(zone_layer_connections "In3.Cu")
		(net 314)
	)
	(via
		(at 54.575 105.275002)
		(size 0.45)
		(drill 0.1)
		(layers "F.Cu" "B.Cu")
		(remove_unused_layers yes)
		(keep_end_layers yes)
		(zone_layer_connections "In3.Cu")
		(net 314)
	)
	(via
		(at 83.89 69.35)
		(size 0.45)
		(drill 0.2)
		(layers "F.Cu" "B.Cu")
		(remove_unused_layers yes)
		(keep_end_layers yes)
		(zone_layer_connections "In3.Cu")
		(net 314)
	)
	(via
		(at 51.575 104.275002)
		(size 0.45)
		(drill 0.1)
		(layers "F.Cu" "B.Cu")
		(remove_unused_layers yes)
		(keep_end_layers yes)
		(zone_layer_connections "In3.Cu")
		(net 314)
	)
	(via
		(at 51.575 112.975001)
		(size 0.45)
		(drill 0.1)
		(layers "F.Cu" "B.Cu")
		(remove_unused_layers yes)
		(keep_end_layers yes)
		(zone_layer_connections "In3.Cu")
		(net 314)
	)
	(via
		(at 118.33 104.35)
		(size 0.45)
		(drill 0.2)
		(layers "F.Cu" "B.Cu")
		(remove_unused_layers yes)
		(keep_end_layers yes)
		(zone_layer_connections "In3.Cu")
		(net 314)
	)
	(via
		(at 53.575002 88.875)
		(size 0.45)
		(drill 0.1)
		(layers "F.Cu" "B.Cu")
		(remove_unused_layers yes)
		(keep_end_layers yes)
		(zone_layer_connections "In3.Cu")
		(net 314)
	)
	(via
		(at 66.75 68.35)
		(size 0.45)
		(drill 0.2)
		(layers "F.Cu" "B.Cu")
		(remove_unused_layers yes)
		(keep_end_layers yes)
		(zone_layer_connections "In3.Cu")
		(net 314)
	)
	(via
		(at 54.575 111.975001)
		(size 0.45)
		(drill 0.1)
		(layers "F.Cu" "B.Cu")
		(remove_unused_layers yes)
		(keep_end_layers yes)
		(zone_layer_connections "In3.Cu")
		(net 314)
	)
	(via
		(at 51.575 111.975001)
		(size 0.45)
		(drill 0.1)
		(layers "F.Cu" "B.Cu")
		(remove_unused_layers yes)
		(keep_end_layers yes)
		(zone_layer_connections "In3.Cu")
		(net 314)
	)
	(via
		(at 52.575001 89.875)
		(size 0.45)
		(drill 0.1)
		(layers "F.Cu" "B.Cu")
		(remove_unused_layers yes)
		(keep_end_layers yes)
		(zone_layer_connections "In3.Cu")
		(net 314)
	)
	(via
		(at 70.124999 75.514995)
		(size 0.45)
		(drill 0.1)
		(layers "F.Cu" "B.Cu")
		(remove_unused_layers yes)
		(keep_end_layers yes)
		(zone_layer_connections "In3.Cu")
		(net 314)
	)
	(via
		(at 54.575 112.975001)
		(size 0.45)
		(drill 0.1)
		(layers "F.Cu" "B.Cu")
		(remove_unused_layers yes)
		(keep_end_layers yes)
		(zone_layer_connections "In3.Cu")
		(net 314)
	)
	(via
		(at 52.574999 111.975001)
		(size 0.45)
		(drill 0.1)
		(layers "F.Cu" "B.Cu")
		(remove_unused_layers yes)
		(keep_end_layers yes)
		(zone_layer_connections "In3.Cu")
		(net 314)
	)
	(via
		(at 52.574998 96.575001)
		(size 0.45)
		(drill 0.1)
		(layers "F.Cu" "B.Cu")
		(remove_unused_layers yes)
		(keep_end_layers yes)
		(zone_layer_connections "In3.Cu")
		(net 314)
	)
	(via
		(at 67.75 68.35)
		(size 0.45)
		(drill 0.2)
		(layers "F.Cu" "B.Cu")
		(remove_unused_layers yes)
		(keep_end_layers yes)
		(zone_layer_connections "In3.Cu")
		(net 314)
	)
	(via
		(at 51.574999 96.575001)
		(size 0.45)
		(drill 0.1)
		(layers "F.Cu" "B.Cu")
		(remove_unused_layers yes)
		(keep_end_layers yes)
		(zone_layer_connections "In3.Cu")
		(net 314)
	)
	(via
		(at 54.574999 97.575001)
		(size 0.45)
		(drill 0.1)
		(layers "F.Cu" "B.Cu")
		(remove_unused_layers yes)
		(keep_end_layers yes)
		(zone_layer_connections "In3.Cu")
		(net 314)
	)
	(via
		(at 54.575 104.275002)
		(size 0.45)
		(drill 0.1)
		(layers "F.Cu" "B.Cu")
		(remove_unused_layers yes)
		(keep_end_layers yes)
		(zone_layer_connections "In3.Cu")
		(net 314)
	)
	(via
		(at 53.575 112.975001)
		(size 0.45)
		(drill 0.1)
		(layers "F.Cu" "B.Cu")
		(remove_unused_layers yes)
		(keep_end_layers yes)
		(zone_layer_connections "In3.Cu")
		(net 314)
	)
	(via
		(at 54.575001 89.875)
		(size 0.45)
		(drill 0.1)
		(layers "F.Cu" "B.Cu")
		(remove_unused_layers yes)
		(keep_end_layers yes)
		(zone_layer_connections "In3.Cu")
		(net 314)
	)
	(via
		(at 70.124999 77.514998)
		(size 0.45)
		(drill 0.1)
		(layers "F.Cu" "B.Cu")
		(remove_unused_layers yes)
		(keep_end_layers yes)
		(zone_layer_connections "In3.Cu")
		(net 314)
	)
	(via
		(at 53.575001 104.275002)
		(size 0.45)
		(drill 0.1)
		(layers "F.Cu" "B.Cu")
		(remove_unused_layers yes)
		(keep_end_layers yes)
		(zone_layer_connections "In3.Cu")
		(net 314)
	)
	(via
		(at 51.574999 97.575001)
		(size 0.45)
		(drill 0.1)
		(layers "F.Cu" "B.Cu")
		(remove_unused_layers yes)
		(keep_end_layers yes)
		(zone_layer_connections "In3.Cu")
		(net 314)
	)
	(via
		(at 54.574999 96.575001)
		(size 0.45)
		(drill 0.1)
		(layers "F.Cu" "B.Cu")
		(remove_unused_layers yes)
		(keep_end_layers yes)
		(zone_layer_connections "In3.Cu")
		(net 314)
	)
	(via
		(at 70.124999 76.514994)
		(size 0.45)
		(drill 0.1)
		(layers "F.Cu" "B.Cu")
		(remove_unused_layers yes)
		(keep_end_layers yes)
		(zone_layer_connections "In3.Cu")
		(net 314)
	)
	(via
		(at 83.89 68.35)
		(size 0.45)
		(drill 0.2)
		(layers "F.Cu" "B.Cu")
		(remove_unused_layers yes)
		(keep_end_layers yes)
		(zone_layer_connections "In3.Cu")
		(net 314)
	)
	(segment
		(start 82.49 69.75)
		(end 82.89 69.35)
		(width 0.15)
		(layer "B.Cu")
		(net 314)
	)
	(segment
		(start 82.49 72.3)
		(end 82.49 69.75)
		(width 0.15)
		(layer "B.Cu")
		(net 314)
	)
	(segment
		(start 72.87 80.539996)
		(end 71.874999 80.539996)
		(width 0.15)
		(layer "F.Cu")
		(net 315)
	)
	(segment
		(start 73.369999 81.079995)
		(end 74.329999 82.039995)
		(width 0.15)
		(layer "F.Cu")
		(net 315)
	)
	(segment
		(start 73.37 81.039995)
		(end 72.87 80.539996)
		(width 0.15)
		(layer "F.Cu")
		(net 315)
	)
	(segment
		(start 73.37 81.039995)
		(end 73.369999 81.079995)
		(width 0.15)
		(layer "F.Cu")
		(net 315)
	)
	(segment
		(start 69.58 80.539996)
		(end 70.025 80.539996)
		(width 0.15)
		(layer "F.Cu")
		(net 316)
	)
	(segment
		(start 68.899999 79.859994)
		(end 69.58 80.539996)
		(width 0.15)
		(layer "F.Cu")
		(net 316)
	)
	(segment
		(start 73.37 78.039994)
		(end 73.369999 79.039994)
		(width 0.15)
		(layer "F.Cu")
		(net 317)
	)
	(segment
		(start 73.37 80.039996)
		(end 73.369999 79.039994)
		(width 0.15)
		(layer "F.Cu")
		(net 317)
	)
	(segment
		(start 73.37 80.039996)
		(end 71.875 80.039995)
		(width 0.15)
		(layer "F.Cu")
		(net 317)
	)
	(segment
		(start 56.600001 89.419999)
		(end 56.600001 88.975)
		(width 0.15)
		(layer "F.Cu")
		(net 318)
	)
	(segment
		(start 55.919999 90.099999)
		(end 56.600001 89.419999)
		(width 0.15)
		(layer "F.Cu")
		(net 318)
	)
	(segment
		(start 99.4 54.338967)
		(end 99.25 54.488967)
		(width 0.15)
		(layer "F.Cu")
		(net 319)
	)
	(segment
		(start 99.4 54.335)
		(end 99.4 54.338967)
		(width 0.15)
		(layer "F.Cu")
		(net 319)
	)
	(segment
		(start 99.25 54.488967)
		(end 99.25 55.500001)
		(width 0.15)
		(layer "F.Cu")
		(net 319)
	)
	(via
		(at 99.4 54.335)
		(size 0.45)
		(drill 0.2)
		(layers "F.Cu" "B.Cu")
		(remove_unused_layers yes)
		(keep_end_layers yes)
		(zone_layer_connections)
		(net 319)
	)
	(segment
		(start 106.75 51.685)
		(end 101.4 51.685)
		(width 0.15)
		(layer "B.Cu")
		(net 319)
	)
	(segment
		(start 109.98 67.1)
		(end 110.95 67.1)
		(width 0.15)
		(layer "B.Cu")
		(net 319)
	)
	(segment
		(start 101.4 51.685)
		(end 99.4 53.685)
		(width 0.15)
		(layer "B.Cu")
		(net 319)
	)
	(segment
		(start 109.98 59.98)
		(end 108.1 58.1)
		(width 0.15)
		(layer "B.Cu")
		(net 319)
	)
	(segment
		(start 99.252 54.486967)
		(end 99.252 55.49866)
		(width 0.15)
		(layer "B.Cu")
		(net 319)
	)
	(segment
		(start 99.4 53.685)
		(end 99.4 54.335)
		(width 0.15)
		(layer "B.Cu")
		(net 319)
	)
	(segment
		(start 108.1 53.035)
		(end 106.75 51.685)
		(width 0.15)
		(layer "B.Cu")
		(net 319)
	)
	(segment
		(start 109.98 66.6)
		(end 109.98 59.98)
		(width 0.15)
		(layer "B.Cu")
		(net 319)
	)
	(segment
		(start 108.1 58.1)
		(end 108.1 53.035)
		(width 0.15)
		(layer "B.Cu")
		(net 319)
	)
	(segment
		(start 109.98 66.6)
		(end 109.98 67.1)
		(width 0.15)
		(layer "B.Cu")
		(net 319)
	)
	(segment
		(start 109.98 67.1)
		(end 109.98 67.6)
		(width 0.15)
		(layer "B.Cu")
		(net 319)
	)
	(segment
		(start 99.252 55.49866)
		(end 99.252 56.27066)
		(width 0.15)
		(layer "B.Cu")
		(net 319)
	)
	(segment
		(start 99.4 54.335)
		(end 99.4 54.338967)
		(width 0.15)
		(layer "B.Cu")
		(net 319)
	)
	(segment
		(start 99.4 54.338967)
		(end 99.252 54.486967)
		(width 0.15)
		(layer "B.Cu")
		(net 319)
	)
	(segment
		(start 100.75 60.985)
		(end 100.75 60.370001)
		(width 0.15)
		(layer "F.Cu")
		(net 320)
	)
	(segment
		(start 100.9 61.135)
		(end 100.75 60.985)
		(width 0.15)
		(layer "F.Cu")
		(net 320)
	)
	(segment
		(start 100.75 57.690001)
		(end 100.75 59.598)
		(width 0.15)
		(layer "F.Cu")
		(net 320)
	)
	(segment
		(start 100.75 59.598)
		(end 100.75 60.370001)
		(width 0.15)
		(layer "F.Cu")
		(net 320)
	)
	(via
		(at 109.99 70.59)
		(size 0.45)
		(drill 0.2)
		(layers "F.Cu" "B.Cu")
		(remove_unused_layers yes)
		(keep_end_layers yes)
		(zone_layer_connections)
		(net 320)
	)
	(via
		(at 100.9 61.135)
		(size 0.45)
		(drill 0.2)
		(layers "F.Cu" "B.Cu")
		(remove_unused_layers yes)
		(keep_end_layers yes)
		(zone_layer_connections)
		(net 320)
	)
	(segment
		(start 109.98 70.6)
		(end 109.98 71.1)
		(width 0.15)
		(layer "B.Cu")
		(net 320)
	)
	(segment
		(start 109.98 71.1)
		(end 109.98 71.6)
		(width 0.15)
		(layer "B.Cu")
		(net 320)
	)
	(segment
		(start 110.95 71.1)
		(end 109.98 71.1)
		(width 0.15)
		(layer "B.Cu")
		(net 320)
	)
	(segment
		(start 100.9 61.135)
		(end 100.9 61.14)
		(width 0.15)
		(layer "In5.Cu")
		(net 320)
	)
	(segment
		(start 102.4 62.64)
		(end 105.105 62.64)
		(width 0.15)
		(layer "In5.Cu")
		(net 320)
	)
	(segment
		(start 105.105 62.64)
		(end 108.24 65.775)
		(width 0.15)
		(layer "In5.Cu")
		(net 320)
	)
	(segment
		(start 108.24 65.775)
		(end 109.525 65.775)
		(width 0.15)
		(layer "In5.Cu")
		(net 320)
	)
	(segment
		(start 100.9 61.14)
		(end 102.4 62.64)
		(width 0.15)
		(layer "In5.Cu")
		(net 320)
	)
	(segment
		(start 110.83 69.75)
		(end 109.98 70.6)
		(width 0.15)
		(layer "In5.Cu")
		(net 320)
	)
	(segment
		(start 110.83 67.08)
		(end 110.83 69.75)
		(width 0.15)
		(layer "In5.Cu")
		(net 320)
	)
	(segment
		(start 109.525 65.775)
		(end 110.83 67.08)
		(width 0.15)
		(layer "In5.Cu")
		(net 320)
	)
	(segment
		(start 98.6 54.338348)
		(end 98.75 54.488348)
		(width 0.15)
		(layer "F.Cu")
		(net 321)
	)
	(segment
		(start 98.6 54.335)
		(end 98.6 54.338348)
		(width 0.15)
		(layer "F.Cu")
		(net 321)
	)
	(segment
		(start 98.75 54.488348)
		(end 98.75 55.500001)
		(width 0.15)
		(layer "F.Cu")
		(net 321)
	)
	(via
		(at 98.6 54.335)
		(size 0.45)
		(drill 0.2)
		(layers "F.Cu" "B.Cu")
		(remove_unused_layers yes)
		(keep_end_layers yes)
		(zone_layer_connections)
		(net 321)
	)
	(segment
		(start 98.752 54.490348)
		(end 98.752 55.498659)
		(width 0.15)
		(layer "B.Cu")
		(net 321)
	)
	(segment
		(start 109 57.9)
		(end 109 52.835)
		(width 0.15)
		(layer "B.Cu")
		(net 321)
	)
	(segment
		(start 110.75 59.65)
		(end 109 57.9)
		(width 0.15)
		(layer "B.Cu")
		(net 321)
	)
	(segment
		(start 111.8 67.75)
		(end 111.8 66.1)
		(width 0.15)
		(layer "B.Cu")
		(net 321)
	)
	(segment
		(start 109.98 68.6)
		(end 110.35 68.6)
		(width 0.15)
		(layer "B.Cu")
		(net 321)
	)
	(segment
		(start 107.1 50.935)
		(end 101.05 50.935)
		(width 0.15)
		(layer "B.Cu")
		(net 321)
	)
	(segment
		(start 110.75 65.05)
		(end 110.75 59.65)
		(width 0.15)
		(layer "B.Cu")
		(net 321)
	)
	(segment
		(start 98.6 54.338348)
		(end 98.752 54.490348)
		(width 0.15)
		(layer "B.Cu")
		(net 321)
	)
	(segment
		(start 111.8 66.1)
		(end 110.75 65.05)
		(width 0.15)
		(layer "B.Cu")
		(net 321)
	)
	(segment
		(start 110.35 68.6)
		(end 110.7 68.25)
		(width 0.15)
		(layer "B.Cu")
		(net 321)
	)
	(segment
		(start 109.98 69.1)
		(end 110.95 69.1)
		(width 0.15)
		(layer "B.Cu")
		(net 321)
	)
	(segment
		(start 109.98 69.1)
		(end 109.98 69.6)
		(width 0.15)
		(layer "B.Cu")
		(net 321)
	)
	(segment
		(start 109.98 68.6)
		(end 109.98 69.1)
		(width 0.15)
		(layer "B.Cu")
		(net 321)
	)
	(segment
		(start 109 52.835)
		(end 107.1 50.935)
		(width 0.15)
		(layer "B.Cu")
		(net 321)
	)
	(segment
		(start 98.6 54.335)
		(end 98.6 54.338348)
		(width 0.15)
		(layer "B.Cu")
		(net 321)
	)
	(segment
		(start 101.05 50.935)
		(end 98.6 53.385)
		(width 0.15)
		(layer "B.Cu")
		(net 321)
	)
	(segment
		(start 98.6 53.385)
		(end 98.6 54.335)
		(width 0.15)
		(layer "B.Cu")
		(net 321)
	)
	(segment
		(start 111.3 68.25)
		(end 111.8 67.75)
		(width 0.15)
		(layer "B.Cu")
		(net 321)
	)
	(segment
		(start 110.7 68.25)
		(end 111.3 68.25)
		(width 0.15)
		(layer "B.Cu")
		(net 321)
	)
	(segment
		(start 98.752 56.27066)
		(end 98.752 55.498659)
		(width 0.15)
		(layer "B.Cu")
		(net 321)
	)
	(segment
		(start 57.1 85.629999)
		(end 56.600001 86.129999)
		(width 0.15)
		(layer "F.Cu")
		(net 322)
	)
	(segment
		(start 57.14 85.63)
		(end 58.1 84.67)
		(width 0.15)
		(layer "F.Cu")
		(net 322)
	)
	(segment
		(start 56.600001 86.129999)
		(end 56.600001 87.125)
		(width 0.15)
		(layer "F.Cu")
		(net 322)
	)
	(segment
		(start 57.1 85.629999)
		(end 57.14 85.63)
		(width 0.15)
		(layer "F.Cu")
		(net 322)
	)
	(segment
		(start 56.6 104.820002)
		(end 56.6 104.375001)
		(width 0.15)
		(layer "F.Cu")
		(net 323)
	)
	(segment
		(start 55.919998 105.500002)
		(end 56.6 104.820002)
		(width 0.15)
		(layer "F.Cu")
		(net 323)
	)
	(segment
		(start 56.6 101.530001)
		(end 56.6 102.525002)
		(width 0.15)
		(layer "F.Cu")
		(net 324)
	)
	(segment
		(start 57.1 101.030001)
		(end 56.6 101.530001)
		(width 0.15)
		(layer "F.Cu")
		(net 324)
	)
	(segment
		(start 57.1 101.030001)
		(end 57.139998 101.030002)
		(width 0.15)
		(layer "F.Cu")
		(net 324)
	)
	(segment
		(start 57.139998 101.030002)
		(end 58.099998 100.070002)
		(width 0.15)
		(layer "F.Cu")
		(net 324)
	)
	(segment
		(start 56.6 97.119999)
		(end 56.6 96.674999)
		(width 0.15)
		(layer "F.Cu")
		(net 325)
	)
	(segment
		(start 55.919998 97.8)
		(end 56.6 97.119999)
		(width 0.15)
		(layer "F.Cu")
		(net 325)
	)
	(segment
		(start 56.6 93.829999)
		(end 56.6 94.825)
		(width 0.15)
		(layer "F.Cu")
		(net 326)
	)
	(segment
		(start 57.14 93.33)
		(end 58.099999 92.37)
		(width 0.15)
		(layer "F.Cu")
		(net 326)
	)
	(segment
		(start 57.099999 93.329999)
		(end 57.14 93.33)
		(width 0.15)
		(layer "F.Cu")
		(net 326)
	)
	(segment
		(start 57.099999 93.329999)
		(end 56.6 93.829999)
		(width 0.15)
		(layer "F.Cu")
		(net 326)
	)
	(segment
		(start 56.600001 112.519998)
		(end 56.600001 112.074998)
		(width 0.15)
		(layer "F.Cu")
		(net 327)
	)
	(segment
		(start 55.919999 113.199999)
		(end 56.600001 112.519998)
		(width 0.15)
		(layer "F.Cu")
		(net 327)
	)
	(segment
		(start 56.600001 109.229998)
		(end 56.600001 110.224999)
		(width 0.15)
		(layer "F.Cu")
		(net 328)
	)
	(segment
		(start 57.1 108.729997)
		(end 57.14 108.729999)
		(width 0.15)
		(layer "F.Cu")
		(net 328)
	)
	(segment
		(start 57.1 108.729997)
		(end 56.600001 109.229998)
		(width 0.15)
		(layer "F.Cu")
		(net 328)
	)
	(segment
		(start 57.14 108.729999)
		(end 58.1 107.769999)
		(width 0.15)
		(layer "F.Cu")
		(net 328)
	)
	(segment
		(start 54.099999 85.629999)
		(end 55.099998 85.63)
		(width 0.15)
		(layer "F.Cu")
		(net 329)
	)
	(segment
		(start 56.100001 85.629999)
		(end 56.1 87.124999)
		(width 0.15)
		(layer "F.Cu")
		(net 329)
	)
	(segment
		(start 56.100001 85.629999)
		(end 55.099998 85.63)
		(width 0.15)
		(layer "F.Cu")
		(net 329)
	)
	(segment
		(start 56.1 101.03)
		(end 56.099998 102.525001)
		(width 0.15)
		(layer "F.Cu")
		(net 330)
	)
	(segment
		(start 56.1 101.03)
		(end 55.099998 101.030002)
		(width 0.15)
		(layer "F.Cu")
		(net 330)
	)
	(segment
		(start 54.099998 101.03)
		(end 55.099998 101.030002)
		(width 0.15)
		(layer "F.Cu")
		(net 330)
	)
	(segment
		(start 56.1 93.329999)
		(end 55.099998 93.33)
		(width 0.15)
		(layer "F.Cu")
		(net 331)
	)
	(segment
		(start 56.1 93.329999)
		(end 56.1 94.824999)
		(width 0.15)
		(layer "F.Cu")
		(net 331)
	)
	(segment
		(start 54.099998 93.329999)
		(end 55.099998 93.33)
		(width 0.15)
		(layer "F.Cu")
		(net 331)
	)
	(segment
		(start 54.099999 108.729997)
		(end 55.099999 108.729999)
		(width 0.15)
		(layer "F.Cu")
		(net 332)
	)
	(segment
		(start 56.100001 108.729997)
		(end 55.099999 108.729999)
		(width 0.15)
		(layer "F.Cu")
		(net 332)
	)
	(segment
		(start 56.100001 108.729997)
		(end 56.1 110.224998)
		(width 0.15)
		(layer "F.Cu")
		(net 332)
	)
	(segment
		(start 68.9 80.819994)
		(end 68.9 81.547998)
		(width 0.125)
		(layer "F.Cu")
		(net 333)
	)
	(segment
		(start 69.441998 82.089996)
		(end 70.7 82.089996)
		(width 0.125)
		(layer "F.Cu")
		(net 333)
	)
	(segment
		(start 68.9 81.547998)
		(end 69.441998 82.089996)
		(width 0.125)
		(layer "F.Cu")
		(net 333)
	)
	(segment
		(start 56.879999 90.1)
		(end 58.200001 90.1)
		(width 0.15)
		(layer "F.Cu")
		(net 334)
	)
	(segment
		(start 58.200001 90.1)
		(end 58.399999 89.900002)
		(width 0.15)
		(layer "F.Cu")
		(net 334)
	)
	(segment
		(start 58.399999 89.900002)
		(end 58.4 88.449999)
		(width 0.15)
		(layer "F.Cu")
		(net 334)
	)
	(segment
		(start 58.199999 105.500002)
		(end 58.399998 105.300004)
		(width 0.15)
		(layer "F.Cu")
		(net 335)
	)
	(segment
		(start 56.879999 105.500002)
		(end 58.199999 105.500002)
		(width 0.15)
		(layer "F.Cu")
		(net 335)
	)
	(segment
		(start 58.399998 105.300004)
		(end 58.399998 103.850001)
		(width 0.15)
		(layer "F.Cu")
		(net 335)
	)
	(segment
		(start 56.879998 97.8)
		(end 58.199999 97.8)
		(width 0.15)
		(layer "F.Cu")
		(net 336)
	)
	(segment
		(start 58.399998 97.600002)
		(end 58.399999 96.149999)
		(width 0.15)
		(layer "F.Cu")
		(net 336)
	)
	(segment
		(start 58.199999 97.8)
		(end 58.399998 97.600002)
		(width 0.15)
		(layer "F.Cu")
		(net 336)
	)
	(segment
		(start 56.88 113.199999)
		(end 58.2 113.199999)
		(width 0.15)
		(layer "F.Cu")
		(net 337)
	)
	(segment
		(start 58.399999 113)
		(end 58.4 111.549998)
		(width 0.15)
		(layer "F.Cu")
		(net 337)
	)
	(segment
		(start 58.2 113.199999)
		(end 58.399999 113)
		(width 0.15)
		(layer "F.Cu")
		(net 337)
	)
	(segment
		(start 71.2 80.714995)
		(end 71.2 80.839995)
		(width 0.15)
		(layer "F.Cu")
		(net 338)
	)
	(segment
		(start 72.799999 81.889995)
		(end 72.95 82.039995)
		(width 0.15)
		(layer "F.Cu")
		(net 338)
	)
	(segment
		(start 72.799999 81.089997)
		(end 72.799999 81.889995)
		(width 0.15)
		(layer "F.Cu")
		(net 338)
	)
	(segment
		(start 71.269998 80.909994)
		(end 72.619997 80.909995)
		(width 0.15)
		(layer "F.Cu")
		(net 338)
	)
	(segment
		(start 72.619997 80.909995)
		(end 72.799999 81.089997)
		(width 0.15)
		(layer "F.Cu")
		(net 338)
	)
	(segment
		(start 71.2 80.839995)
		(end 71.269998 80.909994)
		(width 0.15)
		(layer "F.Cu")
		(net 338)
	)
	(segment
		(start 72.95 82.039995)
		(end 73.369999 82.039995)
		(width 0.15)
		(layer "F.Cu")
		(net 338)
	)
	(via
		(at 73.369999 82.039995)
		(size 0.45)
		(drill 0.1)
		(layers "F.Cu" "B.Cu")
		(remove_unused_layers yes)
		(keep_end_layers yes)
		(zone_layer_connections)
		(net 338)
	)
	(via
		(at 53.1 84.67)
		(size 0.45)
		(drill 0.1)
		(layers "F.Cu" "B.Cu")
		(remove_unused_layers yes)
		(keep_end_layers yes)
		(zone_layer_connections)
		(net 338)
	)
	(segment
		(start 54.7 77.241)
		(end 52.71 79.231)
		(width 0.15)
		(layer "In5.Cu")
		(net 338)
	)
	(segment
		(start 72.039995 82.039995)
		(end 68.14 78.14)
		(width 0.15)
		(layer "In5.Cu")
		(net 338)
	)
	(segment
		(start 54.7 73.35)
		(end 54.7 77.241)
		(width 0.15)
		(layer "In5.Cu")
		(net 338)
	)
	(segment
		(start 68.14 75.64)
		(end 64.85 72.35)
		(width 0.15)
		(layer "In5.Cu")
		(net 338)
	)
	(segment
		(start 68.14 78.14)
		(end 68.14 75.64)
		(width 0.15)
		(layer "In5.Cu")
		(net 338)
	)
	(segment
		(start 52.71 84.28)
		(end 53.1 84.67)
		(width 0.15)
		(layer "In5.Cu")
		(net 338)
	)
	(segment
		(start 52.71 79.231)
		(end 52.71 84.28)
		(width 0.15)
		(layer "In5.Cu")
		(net 338)
	)
	(segment
		(start 73.369999 82.039995)
		(end 72.039995 82.039995)
		(width 0.15)
		(layer "In5.Cu")
		(net 338)
	)
	(segment
		(start 64.85 72.35)
		(end 55.7 72.35)
		(width 0.15)
		(layer "In5.Cu")
		(net 338)
	)
	(segment
		(start 55.7 72.35)
		(end 54.7 73.35)
		(width 0.15)
		(layer "In5.Cu")
		(net 338)
	)
	(segment
		(start 55.6 87.125001)
		(end 55.6 86.7)
		(width 0.15)
		(layer "F.Cu")
		(net 340)
	)
	(segment
		(start 53.1 85.999998)
		(end 53.099999 85.63)
		(width 0.15)
		(layer "F.Cu")
		(net 340)
	)
	(segment
		(start 53.400001 86.299999)
		(end 53.1 85.999998)
		(width 0.15)
		(layer "F.Cu")
		(net 340)
	)
	(segment
		(start 55.6 86.7)
		(end 55.199999 86.299999)
		(width 0.15)
		(layer "F.Cu")
		(net 340)
	)
	(segment
		(start 55.199999 86.299999)
		(end 53.400001 86.299999)
		(width 0.15)
		(layer "F.Cu")
		(net 340)
	)
	(segment
		(start 57.949999 109.299999)
		(end 58.1 109.149998)
		(width 0.15)
		(layer "F.Cu")
		(net 341)
	)
	(segment
		(start 58.1 109.149998)
		(end 58.1 108.729999)
		(width 0.15)
		(layer "F.Cu")
		(net 341)
	)
	(segment
		(start 56.970001 109.480001)
		(end 57.150001 109.299999)
		(width 0.15)
		(layer "F.Cu")
		(net 341)
	)
	(segment
		(start 56.775 110.899998)
		(end 56.900001 110.899998)
		(width 0.15)
		(layer "F.Cu")
		(net 341)
	)
	(segment
		(start 56.900001 110.899998)
		(end 56.969998 110.83)
		(width 0.15)
		(layer "F.Cu")
		(net 341)
	)
	(segment
		(start 57.150001 109.299999)
		(end 57.949999 109.299999)
		(width 0.15)
		(layer "F.Cu")
		(net 341)
	)
	(segment
		(start 56.969998 110.83)
		(end 56.970001 109.480001)
		(width 0.15)
		(layer "F.Cu")
		(net 341)
	)
	(via
		(at 53.099998 92.37)
		(size 0.45)
		(drill 0.2)
		(layers "F.Cu" "B.Cu")
		(remove_unused_layers yes)
		(keep_end_layers yes)
		(zone_layer_connections)
		(net 341)
	)
	(via
		(at 58.1 108.73)
		(size 0.45)
		(drill 0.2)
		(layers "F.Cu" "B.Cu")
		(remove_unused_layers yes)
		(keep_end_layers yes)
		(zone_layer_connections)
		(net 341)
	)
	(segment
		(start 51.1 94.369998)
		(end 53.099998 92.37)
		(width 0.15)
		(layer "B.Cu")
		(net 341)
	)
	(segment
		(start 52.829998 108.73)
		(end 51.1 107.000002)
		(width 0.15)
		(layer "B.Cu")
		(net 341)
	)
	(segment
		(start 58.1 108.73)
		(end 52.829998 108.73)
		(width 0.15)
		(layer "B.Cu")
		(net 341)
	)
	(segment
		(start 51.1 107.000002)
		(end 51.1 94.369998)
		(width 0.15)
		(layer "B.Cu")
		(net 341)
	)
	(segment
		(start 56.969999 87.730001)
		(end 56.9 87.799999)
		(width 0.15)
		(layer "F.Cu")
		(net 342)
	)
	(segment
		(start 56.97 86.380002)
		(end 56.969999 87.730001)
		(width 0.15)
		(layer "F.Cu")
		(net 342)
	)
	(segment
		(start 57.949999 86.200001)
		(end 57.150001 86.200001)
		(width 0.15)
		(layer "F.Cu")
		(net 342)
	)
	(segment
		(start 58.1 86.049999)
		(end 57.949999 86.200001)
		(width 0.15)
		(layer "F.Cu")
		(net 342)
	)
	(segment
		(start 56.9 87.799999)
		(end 56.775 87.799999)
		(width 0.15)
		(layer "F.Cu")
		(net 342)
	)
	(segment
		(start 58.1 85.63)
		(end 58.1 86.049999)
		(width 0.15)
		(layer "F.Cu")
		(net 342)
	)
	(segment
		(start 57.150001 86.200001)
		(end 56.97 86.380002)
		(width 0.15)
		(layer "F.Cu")
		(net 342)
	)
	(via
		(at 58.1 85.63)
		(size 0.45)
		(drill 0.2)
		(layers "F.Cu" "B.Cu")
		(remove_unused_layers yes)
		(keep_end_layers yes)
		(zone_layer_connections)
		(net 342)
	)
	(via
		(at 53.099998 100.070002)
		(size 0.45)
		(drill 0.2)
		(layers "F.Cu" "B.Cu")
		(remove_unused_layers yes)
		(keep_end_layers yes)
		(zone_layer_connections)
		(net 342)
	)
	(segment
		(start 58.1 87.8)
		(end 58.1 85.63)
		(width 0.15)
		(layer "B.Cu")
		(net 342)
	)
	(segment
		(start 56.45 96.72)
		(end 56.45 94.850002)
		(width 0.15)
		(layer "B.Cu")
		(net 342)
	)
	(segment
		(start 56.45 94.850002)
		(end 54.8 93.200002)
		(width 0.15)
		(layer "B.Cu")
		(net 342)
	)
	(segment
		(start 54.8 93.200002)
		(end 54.8 91.1)
		(width 0.15)
		(layer "B.Cu")
		(net 342)
	)
	(segment
		(start 54.8 91.1)
		(end 58.1 87.8)
		(width 0.15)
		(layer "B.Cu")
		(net 342)
	)
	(segment
		(start 53.099998 100.070002)
		(end 56.45 96.72)
		(width 0.15)
		(layer "B.Cu")
		(net 342)
	)
	(segment
		(start 63.41 65.443001)
		(end 66.76 65.443001)
		(width 0.3)
		(layer "F.Cu")
		(net 350)
	)
	(segment
		(start 66.76 65.443001)
		(end 67.116999 65.8)
		(width 0.3)
		(layer "F.Cu")
		(net 350)
	)
	(segment
		(start 71.163999 63.709001)
		(end 71.173 63.7)
		(width 0.3)
		(layer "F.Cu")
		(net 350)
	)
	(segment
		(start 64.273 62.02)
		(end 66.67 62.02)
		(width 0.15)
		(layer "F.Cu")
		(net 350)
	)
	(segment
		(start 67.116999 65.8)
		(end 70.763999 65.8)
		(width 0.3)
		(layer "F.Cu")
		(net 350)
	)
	(segment
		(start 71.163999 64.9)
		(end 71.163999 63.709001)
		(width 0.3)
		(layer "F.Cu")
		(net 350)
	)
	(segment
		(start 70.763999 65.8)
		(end 71.163999 65.4)
		(width 0.3)
		(layer "F.Cu")
		(net 350)
	)
	(segment
		(start 71.163999 65.4)
		(end 71.163999 64.9)
		(width 0.3)
		(layer "F.Cu")
		(net 350)
	)
	(via
		(at 66.76 65.443)
		(size 0.45)
		(drill 0.2)
		(layers "F.Cu" "B.Cu")
		(remove_unused_layers yes)
		(keep_end_layers yes)
		(zone_layer_connections)
		(net 350)
	)
	(segment
		(start 77.99 72.3)
		(end 78.114678 72.175322)
		(width 0.15)
		(layer "B.Cu")
		(net 350)
	)
	(segment
		(start 77.99 72.725678)
		(end 77.99 72.3)
		(width 0.15)
		(layer "B.Cu")
		(net 350)
	)
	(segment
		(start 70.425894 65.443)
		(end 66.76 65.443)
		(width 0.15)
		(layer "B.Cu")
		(net 350)
	)
	(segment
		(start 78.291 72.175322)
		(end 78.202839 72.087161)
		(width 0.15)
		(layer "B.Cu")
		(net 350)
	)
	(segment
		(start 77.282894 72.3)
		(end 70.425894 65.443)
		(width 0.15)
		(layer "B.Cu")
		(net 350)
	)
	(segment
		(start 78.114678 72.175322)
		(end 78.291 72.175322)
		(width 0.15)
		(layer "B.Cu")
		(net 350)
	)
	(segment
		(start 77.99 72.3)
		(end 77.282894 72.3)
		(width 0.15)
		(layer "B.Cu")
		(net 350)
	)
	(segment
		(start 87.313 63.043)
		(end 87.05 62.78)
		(width 0.5)
		(layer "F.Cu")
		(net 351)
	)
	(segment
		(start 79.55 65.443001)
		(end 82.9 65.443001)
		(width 0.3)
		(layer "F.Cu")
		(net 351)
	)
	(segment
		(start 87.303999 64.22)
		(end 87.303999 63.029001)
		(width 0.5)
		(layer "F.Cu")
		(net 351)
	)
	(segment
		(start 87.313 63.7)
		(end 87.313 63.043)
		(width 0.5)
		(layer "F.Cu")
		(net 351)
	)
	(segment
		(start 87.303999 63.709001)
		(end 87.313 63.7)
		(width 0.5)
		(layer "F.Cu")
		(net 351)
	)
	(segment
		(start 87.05 62.78)
		(end 85.5 62.78)
		(width 0.5)
		(layer "F.Cu")
		(net 351)
	)
	(via
		(at 82.9 65.443)
		(size 0.45)
		(drill 0.2)
		(layers "F.Cu" "B.Cu")
		(remove_unused_layers yes)
		(keep_end_layers yes)
		(zone_layer_connections)
		(net 351)
	)
	(segment
		(start 80.24 72.3)
		(end 81.439 71.101)
		(width 0.15)
		(layer "B.Cu")
		(net 351)
	)
	(segment
		(start 81.439 66.904)
		(end 82.9 65.443)
		(width 0.15)
		(layer "B.Cu")
		(net 351)
	)
	(segment
		(start 81.439 71.101)
		(end 81.439 66.904)
		(width 0.15)
		(layer "B.Cu")
		(net 351)
	)
	(segment
		(start 53.399998 101.700001)
		(end 53.099998 101.400001)
		(width 0.15)
		(layer "F.Cu")
		(net 353)
	)
	(segment
		(start 55.599999 102.100002)
		(end 55.199998 101.7)
		(width 0.15)
		(layer "F.Cu")
		(net 353)
	)
	(segment
		(start 55.599999 102.525002)
		(end 55.599999 102.100002)
		(width 0.15)
		(layer "F.Cu")
		(net 353)
	)
	(segment
		(start 53.099998 101.400001)
		(end 53.099998 101.030002)
		(width 0.15)
		(layer "F.Cu")
		(net 353)
	)
	(segment
		(start 55.199998 101.7)
		(end 53.399998 101.700001)
		(width 0.15)
		(layer "F.Cu")
		(net 353)
	)
	(segment
		(start 81.47 57.291999)
		(end 81.47 57.771999)
		(width 0.125)
		(layer "F.Cu")
		(net 356)
	)
	(segment
		(start 81.151 56.204)
		(end 81.151 56.972999)
		(width 0.125)
		(layer "F.Cu")
		(net 356)
	)
	(segment
		(start 81.151 56.972999)
		(end 81.47 57.291999)
		(width 0.125)
		(layer "F.Cu")
		(net 356)
	)
	(segment
		(start 84.15 56.204)
		(end 84.15 57.051999)
		(width 0.125)
		(layer "F.Cu")
		(net 357)
	)
	(segment
		(start 84.33 57.231999)
		(end 84.33 57.771999)
		(width 0.125)
		(layer "F.Cu")
		(net 357)
	)
	(segment
		(start 84.15 57.051999)
		(end 84.33 57.231999)
		(width 0.125)
		(layer "F.Cu")
		(net 357)
	)
	(via
		(at 99.83 104.25)
		(size 0.45)
		(drill 0.2)
		(layers "F.Cu" "B.Cu")
		(remove_unused_layers yes)
		(keep_end_layers yes)
		(zone_layer_connections)
		(net 360)
	)
	(segment
		(start 101.329001 107.979001)
		(end 102.05 108.7)
		(width 0.15)
		(layer "B.Cu")
		(net 360)
	)
	(segment
		(start 99.83 104.25)
		(end 100.304231 104.724231)
		(width 0.15)
		(layer "B.Cu")
		(net 360)
	)
	(segment
		(start 100.304231 104.724231)
		(end 100.998462 104.724231)
		(width 0.15)
		(layer "B.Cu")
		(net 360)
	)
	(segment
		(start 97.33 104.7)
		(end 99.38 104.7)
		(width 0.15)
		(layer "B.Cu")
		(net 360)
	)
	(segment
		(start 100.998462 104.724231)
		(end 101.329001 105.05477)
		(width 0.15)
		(layer "B.Cu")
		(net 360)
	)
	(segment
		(start 96.93 105.1)
		(end 97.33 104.7)
		(width 0.15)
		(layer "B.Cu")
		(net 360)
	)
	(segment
		(start 99.38 104.7)
		(end 99.83 104.25)
		(width 0.15)
		(layer "B.Cu")
		(net 360)
	)
	(segment
		(start 101.329001 105.05477)
		(end 101.329001 107.979001)
		(width 0.15)
		(layer "B.Cu")
		(net 360)
	)
	(via
		(at 101.78 106.15)
		(size 0.45)
		(drill 0.2)
		(layers "F.Cu" "B.Cu")
		(remove_unused_layers yes)
		(keep_end_layers yes)
		(zone_layer_connections)
		(net 361)
	)
	(via
		(at 95.225 104.76)
		(size 0.45)
		(drill 0.2)
		(layers "F.Cu" "B.Cu")
		(remove_unused_layers yes)
		(keep_end_layers yes)
		(zone_layer_connections)
		(net 361)
	)
	(segment
		(start 103.55 105.7)
		(end 102.18 105.7)
		(width 0.15)
		(layer "B.Cu")
		(net 361)
	)
	(segment
		(start 102.18 105.7)
		(end 101.78 106.1)
		(width 0.15)
		(layer "B.Cu")
		(net 361)
	)
	(segment
		(start 101.33 106.6)
		(end 97.065 106.6)
		(width 0.15)
		(layer "In5.Cu")
		(net 361)
	)
	(segment
		(start 97.065 106.6)
		(end 95.225 104.76)
		(width 0.15)
		(layer "In5.Cu")
		(net 361)
	)
	(segment
		(start 101.78 106.15)
		(end 101.33 106.6)
		(width 0.15)
		(layer "In5.Cu")
		(net 361)
	)
	(via
		(at 99.83 103.3)
		(size 0.45)
		(drill 0.2)
		(layers "F.Cu" "B.Cu")
		(remove_unused_layers yes)
		(keep_end_layers yes)
		(zone_layer_connections)
		(net 362)
	)
	(segment
		(start 98.25 104.1)
		(end 98.557739 103.792261)
		(width 0.15)
		(layer "B.Cu")
		(net 362)
	)
	(segment
		(start 101.527806 104.720288)
		(end 102.056573 104.720288)
		(width 0.15)
		(layer "B.Cu")
		(net 362)
	)
	(segment
		(start 104.8 103.55)
		(end 104.8 107.45)
		(width 0.15)
		(layer "B.Cu")
		(net 362)
	)
	(segment
		(start 104.8 107.45)
		(end 103.55 108.7)
		(width 0.15)
		(layer "B.Cu")
		(net 362)
	)
	(segment
		(start 104.65 103.4)
		(end 104.8 103.55)
		(width 0.15)
		(layer "B.Cu")
		(net 362)
	)
	(segment
		(start 102.056573 104.720288)
		(end 103.376861 103.4)
		(width 0.15)
		(layer "B.Cu")
		(net 362)
	)
	(segment
		(start 99.337739 103.792261)
		(end 99.83 103.3)
		(width 0.15)
		(layer "B.Cu")
		(net 362)
	)
	(segment
		(start 99.83 103.3)
		(end 100.33 103.8)
		(width 0.15)
		(layer "B.Cu")
		(net 362)
	)
	(segment
		(start 101.05 103.8)
		(end 101.3 104.05)
		(width 0.15)
		(layer "B.Cu")
		(net 362)
	)
	(segment
		(start 96.93 104.1)
		(end 98.25 104.1)
		(width 0.15)
		(layer "B.Cu")
		(net 362)
	)
	(segment
		(start 100.33 103.8)
		(end 101.05 103.8)
		(width 0.15)
		(layer "B.Cu")
		(net 362)
	)
	(segment
		(start 103.376861 103.4)
		(end 104.65 103.4)
		(width 0.15)
		(layer "B.Cu")
		(net 362)
	)
	(segment
		(start 98.557739 103.792261)
		(end 99.337739 103.792261)
		(width 0.15)
		(layer "B.Cu")
		(net 362)
	)
	(segment
		(start 101.3 104.492482)
		(end 101.527806 104.720288)
		(width 0.15)
		(layer "B.Cu")
		(net 362)
	)
	(segment
		(start 101.3 104.05)
		(end 101.3 104.492482)
		(width 0.15)
		(layer "B.Cu")
		(net 362)
	)
	(via
		(at 101.78 107.1)
		(size 0.45)
		(drill 0.2)
		(layers "F.Cu" "B.Cu")
		(remove_unused_layers yes)
		(keep_end_layers yes)
		(zone_layer_connections)
		(net 363)
	)
	(via
		(at 94.725 105.625)
		(size 0.45)
		(drill 0.2)
		(layers "F.Cu" "B.Cu")
		(remove_unused_layers yes)
		(keep_end_layers yes)
		(zone_layer_connections)
		(net 363)
	)
	(segment
		(start 103.45 107.1)
		(end 103.55 107.2)
		(width 0.15)
		(layer "B.Cu")
		(net 363)
	)
	(segment
		(start 101.78 107.1)
		(end 103.45 107.1)
		(width 0.15)
		(layer "B.Cu")
		(net 363)
	)
	(segment
		(start 101.28 107.6)
		(end 101.78 107.1)
		(width 0.15)
		(layer "In5.Cu")
		(net 363)
	)
	(segment
		(start 94.725 105.625)
		(end 96.7 107.6)
		(width 0.15)
		(layer "In5.Cu")
		(net 363)
	)
	(segment
		(start 96.7 107.6)
		(end 101.28 107.6)
		(width 0.15)
		(layer "In5.Cu")
		(net 363)
	)
	(via
		(at 99.83 106.15)
		(size 0.45)
		(drill 0.2)
		(layers "F.Cu" "B.Cu")
		(remove_unused_layers yes)
		(keep_end_layers yes)
		(zone_layer_connections)
		(net 364)
	)
	(segment
		(start 99.281 106.649)
		(end 97.381 106.649)
		(width 0.15)
		(layer "B.Cu")
		(net 364)
	)
	(segment
		(start 99.83 106.1)
		(end 99.281 106.649)
		(width 0.15)
		(layer "B.Cu")
		(net 364)
	)
	(segment
		(start 97.381 106.649)
		(end 96.93 107.1)
		(width 0.15)
		(layer "B.Cu")
		(net 364)
	)
	(segment
		(start 99.049999 108.7)
		(end 99.049999 106.649)
		(width 0.15)
		(layer "B.Cu")
		(net 364)
	)
	(via
		(at 99.83 105.2)
		(size 0.45)
		(drill 0.2)
		(layers "F.Cu" "B.Cu")
		(remove_unused_layers yes)
		(keep_end_layers yes)
		(zone_layer_connections)
		(net 365)
	)
	(segment
		(start 99.38 105.65)
		(end 99.83 105.2)
		(width 0.15)
		(layer "B.Cu")
		(net 365)
	)
	(segment
		(start 98.232189 106.1)
		(end 98.682189 105.65)
		(width 0.15)
		(layer "B.Cu")
		(net 365)
	)
	(segment
		(start 99.83 105.2)
		(end 100.280999 105.650999)
		(width 0.15)
		(layer "B.Cu")
		(net 365)
	)
	(segment
		(start 96.93 106.1)
		(end 98.232189 106.1)
		(width 0.15)
		(layer "B.Cu")
		(net 365)
	)
	(segment
		(start 98.682189 105.65)
		(end 99.38 105.65)
		(width 0.15)
		(layer "B.Cu")
		(net 365)
	)
	(segment
		(start 100.280999 105.650999)
		(end 100.280999 108.430999)
		(width 0.15)
		(layer "B.Cu")
		(net 365)
	)
	(segment
		(start 100.280999 108.430999)
		(end 100.55 108.7)
		(width 0.15)
		(layer "B.Cu")
		(net 365)
	)
	(via
		(at 101.78 103.3)
		(size 0.45)
		(drill 0.2)
		(layers "F.Cu" "B.Cu")
		(remove_unused_layers yes)
		(keep_end_layers yes)
		(zone_layer_connections)
		(net 366)
	)
	(via
		(at 93.725 103.895)
		(size 0.45)
		(drill 0.2)
		(layers "F.Cu" "B.Cu")
		(remove_unused_layers yes)
		(keep_end_layers yes)
		(zone_layer_connections)
		(net 366)
	)
	(segment
		(start 101.78 103.2)
		(end 101.78 102.97)
		(width 0.15)
		(layer "B.Cu")
		(net 366)
	)
	(segment
		(start 101.78 102.97)
		(end 103.55 101.2)
		(width 0.15)
		(layer "B.Cu")
		(net 366)
	)
	(segment
		(start 97.640517 103.78)
		(end 97.283714 103.423197)
		(width 0.15)
		(layer "In5.Cu")
		(net 366)
	)
	(segment
		(start 94.196803 103.423197)
		(end 93.725 103.895)
		(width 0.15)
		(layer "In5.Cu")
		(net 366)
	)
	(segment
		(start 97.283714 103.423197)
		(end 94.196803 103.423197)
		(width 0.15)
		(layer "In5.Cu")
		(net 366)
	)
	(segment
		(start 101.3 103.78)
		(end 97.640517 103.78)
		(width 0.15)
		(layer "In5.Cu")
		(net 366)
	)
	(segment
		(start 101.78 103.3)
		(end 101.3 103.78)
		(width 0.15)
		(layer "In5.Cu")
		(net 366)
	)
	(via
		(at 94.725 103.895)
		(size 0.45)
		(drill 0.2)
		(layers "F.Cu" "B.Cu")
		(remove_unused_layers yes)
		(keep_end_layers yes)
		(zone_layer_connections)
		(net 367)
	)
	(via
		(at 101.78 104.25)
		(size 0.45)
		(drill 0.2)
		(layers "F.Cu" "B.Cu")
		(remove_unused_layers yes)
		(keep_end_layers yes)
		(zone_layer_connections)
		(net 367)
	)
	(segment
		(start 103.55 102.7)
		(end 103.23 102.7)
		(width 0.15)
		(layer "B.Cu")
		(net 367)
	)
	(segment
		(start 103.23 102.7)
		(end 101.78 104.15)
		(width 0.15)
		(layer "B.Cu")
		(net 367)
	)
	(segment
		(start 101.38 104.65)
		(end 101.78 104.25)
		(width 0.15)
		(layer "In5.Cu")
		(net 367)
	)
	(segment
		(start 96.855 103.895)
		(end 97.61 104.65)
		(width 0.15)
		(layer "In5.Cu")
		(net 367)
	)
	(segment
		(start 94.725 103.895)
		(end 96.855 103.895)
		(width 0.15)
		(layer "In5.Cu")
		(net 367)
	)
	(segment
		(start 97.61 104.65)
		(end 101.38 104.65)
		(width 0.15)
		(layer "In5.Cu")
		(net 367)
	)
	(via
		(at 94.225 104.76)
		(size 0.45)
		(drill 0.2)
		(layers "F.Cu" "B.Cu")
		(remove_unused_layers yes)
		(keep_end_layers yes)
		(zone_layer_connections)
		(net 368)
	)
	(via
		(at 101.780001 105.2)
		(size 0.45)
		(drill 0.2)
		(layers "F.Cu" "B.Cu")
		(remove_unused_layers yes)
		(keep_end_layers yes)
		(zone_layer_connections)
		(net 368)
	)
	(segment
		(start 102.65 105.1)
		(end 101.780001 105.1)
		(width 0.15)
		(layer "B.Cu")
		(net 368)
	)
	(segment
		(start 103.55 104.2)
		(end 102.65 105.1)
		(width 0.15)
		(layer "B.Cu")
		(net 368)
	)
	(segment
		(start 96.3 104.3)
		(end 97.65 105.65)
		(width 0.15)
		(layer "In5.Cu")
		(net 368)
	)
	(segment
		(start 101.330001 105.65)
		(end 101.780001 105.2)
		(width 0.15)
		(layer "In5.Cu")
		(net 368)
	)
	(segment
		(start 95 104.3)
		(end 96.3 104.3)
		(width 0.15)
		(layer "In5.Cu")
		(net 368)
	)
	(segment
		(start 94.225 104.76)
		(end 94.54 104.76)
		(width 0.15)
		(layer "In5.Cu")
		(net 368)
	)
	(segment
		(start 97.65 105.65)
		(end 101.330001 105.65)
		(width 0.15)
		(layer "In5.Cu")
		(net 368)
	)
	(segment
		(start 94.54 104.76)
		(end 95 104.3)
		(width 0.15)
		(layer "In5.Cu")
		(net 368)
	)
	(segment
		(start 56.899999 103.200001)
		(end 56.774999 103.200002)
		(width 0.15)
		(layer "F.Cu")
		(net 369)
	)
	(segment
		(start 58.099999 101.450001)
		(end 57.949998 101.600002)
		(width 0.15)
		(layer "F.Cu")
		(net 369)
	)
	(segment
		(start 58.099999 101.030002)
		(end 58.099999 101.450001)
		(width 0.15)
		(layer "F.Cu")
		(net 369)
	)
	(segment
		(start 57.15 101.600002)
		(end 56.969999 101.780004)
		(width 0.15)
		(layer "F.Cu")
		(net 369)
	)
	(segment
		(start 57.949998 101.600002)
		(end 57.15 101.600002)
		(width 0.15)
		(layer "F.Cu")
		(net 369)
	)
	(segment
		(start 56.969999 101.780004)
		(end 56.969999 103.130003)
		(width 0.15)
		(layer "F.Cu")
		(net 369)
	)
	(segment
		(start 56.969999 103.130003)
		(end 56.899999 103.200001)
		(width 0.15)
		(layer "F.Cu")
		(net 369)
	)
	(via
		(at 58.099999 101.030002)
		(size 0.45)
		(drill 0.2)
		(layers "F.Cu" "B.Cu")
		(remove_unused_layers yes)
		(keep_end_layers yes)
		(zone_layer_connections)
		(net 369)
	)
	(via
		(at 53.1 107.77)
		(size 0.45)
		(drill 0.2)
		(layers "F.Cu" "B.Cu")
		(remove_unused_layers yes)
		(keep_end_layers yes)
		(zone_layer_connections)
		(net 369)
	)
	(segment
		(start 58.099999 101.030002)
		(end 58.099999 102.770001)
		(width 0.15)
		(layer "B.Cu")
		(net 369)
	)
	(segment
		(start 58.099999 102.770001)
		(end 53.1 107.77)
		(width 0.15)
		(layer "B.Cu")
		(net 369)
	)
	(segment
		(start 69.93 66.3)
		(end 70.213 66.583)
		(width 0.3)
		(layer "F.Cu")
		(net 373)
	)
	(segment
		(start 70.213 66.583)
		(end 70.213 67.214)
		(width 0.3)
		(layer "F.Cu")
		(net 373)
	)
	(segment
		(start 68.39 66.3)
		(end 69.93 66.3)
		(width 0.3)
		(layer "F.Cu")
		(net 373)
	)
	(segment
		(start 67.748 66.942)
		(end 68.39 66.3)
		(width 0.3)
		(layer "F.Cu")
		(net 373)
	)
	(segment
		(start 67.748 67.436)
		(end 67.748 66.942)
		(width 0.3)
		(layer "F.Cu")
		(net 373)
	)
	(segment
		(start 55.199998 93.999999)
		(end 53.399998 93.999998)
		(width 0.15)
		(layer "F.Cu")
		(net 376)
	)
	(segment
		(start 55.599999 94.825001)
		(end 55.599999 94.4)
		(width 0.15)
		(layer "F.Cu")
		(net 376)
	)
	(segment
		(start 53.399998 93.999998)
		(end 53.099998 93.699998)
		(width 0.15)
		(layer "F.Cu")
		(net 376)
	)
	(segment
		(start 55.599999 94.4)
		(end 55.199998 93.999999)
		(width 0.15)
		(layer "F.Cu")
		(net 376)
	)
	(segment
		(start 53.099998 93.699998)
		(end 53.099998 93.330001)
		(width 0.15)
		(layer "F.Cu")
		(net 376)
	)
	(segment
		(start 53.099999 109.099998)
		(end 53.099999 108.729999)
		(width 0.15)
		(layer "F.Cu")
		(net 377)
	)
	(segment
		(start 55.6 109.799999)
		(end 55.199998 109.399998)
		(width 0.15)
		(layer "F.Cu")
		(net 377)
	)
	(segment
		(start 55.6 110.225)
		(end 55.6 109.799999)
		(width 0.15)
		(layer "F.Cu")
		(net 377)
	)
	(segment
		(start 55.199998 109.399998)
		(end 53.399999 109.399998)
		(width 0.15)
		(layer "F.Cu")
		(net 377)
	)
	(segment
		(start 53.399999 109.399998)
		(end 53.099999 109.099998)
		(width 0.15)
		(layer "F.Cu")
		(net 377)
	)
	(segment
		(start 57.05 78.1)
		(end 57.43 78.48)
		(width 0.15)
		(layer "F.Cu")
		(net 378)
	)
	(segment
		(start 58.28 78.48)
		(end 57.85 78.48)
		(width 0.15)
		(layer "F.Cu")
		(net 378)
	)
	(segment
		(start 56.969999 94.080002)
		(end 57.149999 93.9)
		(width 0.15)
		(layer "F.Cu")
		(net 378)
	)
	(segment
		(start 57.43 78.48)
		(end 57.85 78.48)
		(width 0.15)
		(layer "F.Cu")
		(net 378)
	)
	(segment
		(start 55.05 78.1)
		(end 57.05 78.1)
		(width 0.15)
		(layer "F.Cu")
		(net 378)
	)
	(segment
		(start 56.774999 95.499999)
		(end 56.899999 95.499999)
		(width 0.15)
		(layer "F.Cu")
		(net 378)
	)
	(segment
		(start 56.899999 95.499999)
		(end 56.969998 95.430001)
		(width 0.15)
		(layer "F.Cu")
		(net 378)
	)
	(segment
		(start 54.699 78.451)
		(end 55.05 78.1)
		(width 0.15)
		(layer "F.Cu")
		(net 378)
	)
	(segment
		(start 57.149999 93.9)
		(end 57.949997 93.9)
		(width 0.15)
		(layer "F.Cu")
		(net 378)
	)
	(segment
		(start 61.6 83)
		(end 61.6 81.8)
		(width 0.15)
		(layer "F.Cu")
		(net 378)
	)
	(segment
		(start 58.099999 93.749999)
		(end 58.099999 93.33)
		(width 0.15)
		(layer "F.Cu")
		(net 378)
	)
	(segment
		(start 56.969998 95.430001)
		(end 56.969999 94.080002)
		(width 0.15)
		(layer "F.Cu")
		(net 378)
	)
	(segment
		(start 54.699 79.1)
		(end 54.699 78.451)
		(width 0.15)
		(layer "F.Cu")
		(net 378)
	)
	(segment
		(start 61.6 81.8)
		(end 58.28 78.48)
		(width 0.15)
		(layer "F.Cu")
		(net 378)
	)
	(segment
		(start 57.949997 93.9)
		(end 58.099999 93.749999)
		(width 0.15)
		(layer "F.Cu")
		(net 378)
	)
	(via
		(at 58.099999 93.33)
		(size 0.45)
		(drill 0.2)
		(layers "F.Cu" "B.Cu")
		(remove_unused_layers yes)
		(keep_end_layers yes)
		(zone_layer_connections)
		(net 378)
	)
	(via
		(at 61.6 83)
		(size 0.45)
		(drill 0.2)
		(layers "F.Cu" "B.Cu")
		(remove_unused_layers yes)
		(keep_end_layers yes)
		(zone_layer_connections)
		(net 378)
	)
	(segment
		(start 62.7 92.85)
		(end 61.6 93.95)
		(width 0.15)
		(layer "B.Cu")
		(net 378)
	)
	(segment
		(start 61.6 93.95)
		(end 58.719999 93.95)
		(width 0.15)
		(layer "B.Cu")
		(net 378)
	)
	(segment
		(start 62.7 84.1)
		(end 62.7 92.85)
		(width 0.15)
		(layer "B.Cu")
		(net 378)
	)
	(segment
		(start 58.719999 93.95)
		(end 58.099999 93.33)
		(width 0.15)
		(layer "B.Cu")
		(net 378)
	)
	(segment
		(start 61.6 83)
		(end 62.7 84.1)
		(width 0.15)
		(layer "B.Cu")
		(net 378)
	)
	(segment
		(start 72.7 77.339994)
		(end 73 77.039994)
		(width 0.15)
		(layer "F.Cu")
		(net 379)
	)
	(segment
		(start 72.7 79.139994)
		(end 72.7 77.339994)
		(width 0.15)
		(layer "F.Cu")
		(net 379)
	)
	(segment
		(start 71.874998 79.539995)
		(end 72.299999 79.539995)
		(width 0.15)
		(layer "F.Cu")
		(net 379)
	)
	(segment
		(start 72.299999 79.539995)
		(end 72.7 79.139994)
		(width 0.15)
		(layer "F.Cu")
		(net 379)
	)
	(segment
		(start 73.369999 77.039994)
		(end 74.33 76.079993)
		(width 0.15)
		(layer "F.Cu")
		(net 379)
	)
	(segment
		(start 73 77.039994)
		(end 73.369999 77.039994)
		(width 0.15)
		(layer "F.Cu")
		(net 379)
	)
	(segment
		(start 74.33 76.079993)
		(end 74.33 76.039996)
		(width 0.15)
		(layer "F.Cu")
		(net 379)
	)
	(segment
		(start 90.1 112.9405)
		(end 90.1 113.56)
		(width 0.125)
		(layer "F.Cu")
		(net 380)
	)
	(segment
		(start 91.1 111.97)
		(end 90.14 112.93)
		(width 0.125)
		(layer "F.Cu")
		(net 380)
	)
	(segment
		(start 90.802 114.262)
		(end 92.649 114.262)
		(width 0.125)
		(layer "F.Cu")
		(net 380)
	)
	(segment
		(start 90.1 113.56)
		(end 90.802 114.262)
		(width 0.125)
		(layer "F.Cu")
		(net 380)
	)
	(segment
		(start 90.14 112.93)
		(end 90.1 112.93)
		(width 0.125)
		(layer "F.Cu")
		(net 380)
	)
	(segment
		(start 105.988 92.787)
		(end 105.988 92.252)
		(width 0.15)
		(layer "F.Cu")
		(net 381)
	)
	(segment
		(start 105.805 92.97)
		(end 105.988 92.787)
		(width 0.15)
		(layer "F.Cu")
		(net 381)
	)
	(segment
		(start 104 92.97)
		(end 104.625001 92.97)
		(width 0.15)
		(layer "F.Cu")
		(net 381)
	)
	(segment
		(start 104.625 92.97)
		(end 105.805 92.97)
		(width 0.15)
		(layer "F.Cu")
		(net 381)
	)
	(via
		(at 104 92.97)
		(size 0.45)
		(drill 0.2)
		(layers "F.Cu" "B.Cu")
		(remove_unused_layers yes)
		(keep_end_layers yes)
		(zone_layer_connections)
		(net 381)
	)
	(via
		(at 74.725 100.435)
		(size 0.45)
		(drill 0.2)
		(layers "F.Cu" "B.Cu")
		(remove_unused_layers yes)
		(keep_end_layers yes)
		(zone_layer_connections)
		(net 381)
	)
	(segment
		(start 90.66475 94.27525)
		(end 90.66475 95.08475)
		(width 0.15)
		(layer "In5.Cu")
		(net 381)
	)
	(segment
		(start 91.24 93.7)
		(end 90.66475 94.27525)
		(width 0.15)
		(layer "In5.Cu")
		(net 381)
	)
	(segment
		(start 104 92.97)
		(end 103.98 92.97)
		(width 0.15)
		(layer "In5.Cu")
		(net 381)
	)
	(segment
		(start 76.06 99.1)
		(end 74.725 100.435)
		(width 0.15)
		(layer "In5.Cu")
		(net 381)
	)
	(segment
		(start 91.24 93.38)
		(end 91.24 93.7)
		(width 0.15)
		(layer "In5.Cu")
		(net 381)
	)
	(segment
		(start 80.8 99.1)
		(end 76.06 99.1)
		(width 0.15)
		(layer "In5.Cu")
		(net 381)
	)
	(segment
		(start 91.52 93.1)
		(end 91.24 93.38)
		(width 0.15)
		(layer "In5.Cu")
		(net 381)
	)
	(segment
		(start 90.66475 95.08475)
		(end 90.0995 95.65)
		(width 0.15)
		(layer "In5.Cu")
		(net 381)
	)
	(segment
		(start 103.85 93.1)
		(end 91.52 93.1)
		(width 0.15)
		(layer "In5.Cu")
		(net 381)
	)
	(segment
		(start 84.25 95.65)
		(end 80.8 99.1)
		(width 0.15)
		(layer "In5.Cu")
		(net 381)
	)
	(segment
		(start 90.0995 95.65)
		(end 84.25 95.65)
		(width 0.15)
		(layer "In5.Cu")
		(net 381)
	)
	(segment
		(start 103.98 92.97)
		(end 103.85 93.1)
		(width 0.15)
		(layer "In5.Cu")
		(net 381)
	)
	(segment
		(start 105.805 95.83)
		(end 105.988 96.013)
		(width 0.15)
		(layer "F.Cu")
		(net 382)
	)
	(segment
		(start 105.988 96.013)
		(end 105.988 96.551)
		(width 0.15)
		(layer "F.Cu")
		(net 382)
	)
	(segment
		(start 103.8 94.79)
		(end 103.8 95.56)
		(width 0.15)
		(layer "F.Cu")
		(net 382)
	)
	(segment
		(start 104.625 95.83)
		(end 105.805 95.83)
		(width 0.15)
		(layer "F.Cu")
		(net 382)
	)
	(segment
		(start 103.8 95.56)
		(end 104.07 95.83)
		(width 0.15)
		(layer "F.Cu")
		(net 382)
	)
	(segment
		(start 104.07 95.83)
		(end 104.625001 95.83)
		(width 0.15)
		(layer "F.Cu")
		(net 382)
	)
	(via
		(at 103.8 94.79)
		(size 0.45)
		(drill 0.2)
		(layers "F.Cu" "B.Cu")
		(remove_unused_layers yes)
		(keep_end_layers yes)
		(zone_layer_connections)
		(net 382)
	)
	(via
		(at 75.225 101.3)
		(size 0.45)
		(drill 0.2)
		(layers "F.Cu" "B.Cu")
		(remove_unused_layers yes)
		(keep_end_layers yes)
		(zone_layer_connections)
		(net 382)
	)
	(segment
		(start 76.51 101.71)
		(end 75.635 101.71)
		(width 0.15)
		(layer "In5.Cu")
		(net 382)
	)
	(segment
		(start 76.73 101.11)
		(end 76.73 101.49)
		(width 0.15)
		(layer "In5.Cu")
		(net 382)
	)
	(segment
		(start 80.508999 100.841001)
		(end 76.998999 100.841001)
		(width 0.15)
		(layer "In5.Cu")
		(net 382)
	)
	(segment
		(start 75.635 101.71)
		(end 75.225 101.3)
		(width 0.15)
		(layer "In5.Cu")
		(net 382)
	)
	(segment
		(start 76.998999 100.841001)
		(end 76.73 101.11)
		(width 0.15)
		(layer "In5.Cu")
		(net 382)
	)
	(segment
		(start 92.47 94.79)
		(end 90.727599 96.532401)
		(width 0.15)
		(layer "In5.Cu")
		(net 382)
	)
	(segment
		(start 84.817599 96.532401)
		(end 80.508999 100.841001)
		(width 0.15)
		(layer "In5.Cu")
		(net 382)
	)
	(segment
		(start 103.8 94.79)
		(end 92.47 94.79)
		(width 0.15)
		(layer "In5.Cu")
		(net 382)
	)
	(segment
		(start 76.73 101.49)
		(end 76.51 101.71)
		(width 0.15)
		(layer "In5.Cu")
		(net 382)
	)
	(segment
		(start 90.727599 96.532401)
		(end 84.817599 96.532401)
		(width 0.15)
		(layer "In5.Cu")
		(net 382)
	)
	(via
		(at 93.725 107.355)
		(size 0.45)
		(drill 0.2)
		(layers "F.Cu" "B.Cu")
		(remove_unused_layers yes)
		(keep_end_layers yes)
		(zone_layer_connections)
		(net 383)
	)
	(segment
		(start 91.23 109.27)
		(end 91.23 108.9)
		(width 0.125)
		(layer "F.Cu")
		(net 384)
	)
	(segment
		(start 90.72 108.04)
		(end 90.035 107.355)
		(width 0.125)
		(layer "F.Cu")
		(net 384)
	)
	(segment
		(start 91.23 108.9)
		(end 90.72 108.39)
		(width 0.125)
		(layer "F.Cu")
		(net 384)
	)
	(segment
		(start 90.035 107.355)
		(end 89.725 107.355)
		(width 0.125)
		(layer "F.Cu")
		(net 384)
	)
	(segment
		(start 91.7615 109.8015)
		(end 91.23 109.27)
		(width 0.125)
		(layer "F.Cu")
		(net 384)
	)
	(segment
		(start 90.72 108.39)
		(end 90.72 108.04)
		(width 0.125)
		(layer "F.Cu")
		(net 384)
	)
	(segment
		(start 91.7615 112.0115)
		(end 91.7615 109.8015)
		(width 0.125)
		(layer "F.Cu")
		(net 384)
	)
	(segment
		(start 92.063 112.313)
		(end 91.7615 112.0115)
		(width 0.125)
		(layer "F.Cu")
		(net 384)
	)
	(segment
		(start 92.649 112.313)
		(end 92.063 112.313)
		(width 0.125)
		(layer "F.Cu")
		(net 384)
	)
	(via
		(at 92.32 112.313)
		(size 0.45)
		(drill 0.2)
		(layers "F.Cu" "B.Cu")
		(remove_unused_layers yes)
		(keep_end_layers yes)
		(zone_layer_connections)
		(net 384)
	)
	(segment
		(start 92.32 112.61)
		(end 92.32 112.313)
		(width 0.15)
		(layer "B.Cu")
		(net 384)
	)
	(segment
		(start 110.27 101.25)
		(end 110.25 101.25)
		(width 0.15)
		(layer "F.Cu")
		(net 385)
	)
	(segment
		(start 110.15 101.15)
		(end 110.15 101.25)
		(width 0.15)
		(layer "F.Cu")
		(net 385)
	)
	(segment
		(start 110.15 101.25)
		(end 109.83 101.570001)
		(width 0.15)
		(layer "F.Cu")
		(net 385)
	)
	(segment
		(start 109.83 101.570001)
		(end 109.15 101.57)
		(width 0.15)
		(layer "F.Cu")
		(net 385)
	)
	(segment
		(start 110.27 101.25)
		(end 110.15 101.25)
		(width 0.15)
		(layer "F.Cu")
		(net 385)
	)
	(segment
		(start 110.7 101.249999)
		(end 110.27 101.25)
		(width 0.15)
		(layer "F.Cu")
		(net 385)
	)
	(segment
		(start 110.15 100.58)
		(end 110.15 101.15)
		(width 0.15)
		(layer "F.Cu")
		(net 385)
	)
	(segment
		(start 110.25 101.25)
		(end 110.15 101.15)
		(width 0.15)
		(layer "F.Cu")
		(net 385)
	)
	(segment
		(start 110.9 101.45)
		(end 110.7 101.249999)
		(width 0.15)
		(layer "F.Cu")
		(net 385)
	)
	(segment
		(start 110.9 101.9)
		(end 110.9 101.45)
		(width 0.15)
		(layer "F.Cu")
		(net 385)
	)
	(segment
		(start 115.42 102.206)
		(end 115.42 101.1)
		(width 0.3)
		(layer "F.Cu")
		(net 386)
	)
	(segment
		(start 114.55 102.451)
		(end 115.175 102.451)
		(width 0.3)
		(layer "F.Cu")
		(net 386)
	)
	(segment
		(start 115.175 102.451)
		(end 115.42 102.206)
		(width 0.3)
		(layer "F.Cu")
		(net 386)
	)
	(segment
		(start 109.15 105.7)
		(end 109.15 106.07)
		(width 0.15)
		(layer "F.Cu")
		(net 387)
	)
	(segment
		(start 110.4 105.35)
		(end 110.3 105.45)
		(width 0.15)
		(layer "F.Cu")
		(net 387)
	)
	(segment
		(start 110.4 104.9)
		(end 110.4 105.35)
		(width 0.15)
		(layer "F.Cu")
		(net 387)
	)
	(segment
		(start 109.4 105.45)
		(end 109.15 105.7)
		(width 0.15)
		(layer "F.Cu")
		(net 387)
	)
	(segment
		(start 110.3 105.45)
		(end 109.4 105.45)
		(width 0.15)
		(layer "F.Cu")
		(net 387)
	)
	(segment
		(start 108.5 101.12)
		(end 109.04 100.58)
		(width 0.125)
		(layer "F.Cu")
		(net 388)
	)
	(segment
		(start 111.9 105.35)
		(end 112.05 105.5)
		(width 0.3)
		(layer "F.Cu")
		(net 388)
	)
	(segment
		(start 110.15 107.03)
		(end 110.15 107.599997)
		(width 0.15)
		(layer "F.Cu")
		(net 388)
	)
	(segment
		(start 112.15 99.62)
		(end 112.15 99.05)
		(width 0.15)
		(layer "F.Cu")
		(net 388)
	)
	(segment
		(start 112.05 105.5)
		(end 112.85 105.5)
		(width 0.3)
		(layer "F.Cu")
		(net 388)
	)
	(segment
		(start 111.9 104.9)
		(end 111.9 105.35)
		(width 0.3)
		(layer "F.Cu")
		(net 388)
	)
	(segment
		(start 109.04 100.58)
		(end 109.15 100.58)
		(width 0.125)
		(layer "F.Cu")
		(net 388)
	)
	(via
		(at 108.5 101.12)
		(size 0.45)
		(drill 0.2)
		(layers "F.Cu" "B.Cu")
		(remove_unused_layers yes)
		(keep_end_layers yes)
		(zone_layer_connections "In3.Cu")
		(net 388)
	)
	(via
		(at 110.15 107.599997)
		(size 0.45)
		(drill 0.2)
		(layers "F.Cu" "B.Cu")
		(remove_unused_layers yes)
		(keep_end_layers yes)
		(zone_layer_connections "In3.Cu")
		(net 388)
	)
	(via
		(at 84.76 71.1)
		(size 0.45)
		(drill 0.2)
		(layers "F.Cu" "B.Cu")
		(remove_unused_layers yes)
		(keep_end_layers yes)
		(zone_layer_connections)
		(net 388)
	)
	(via
		(at 113.2 105.226)
		(size 0.45)
		(drill 0.2)
		(layers "F.Cu" "B.Cu")
		(remove_unused_layers yes)
		(keep_end_layers yes)
		(zone_layer_connections "In3.Cu")
		(net 388)
	)
	(via
		(at 112.15 99.05)
		(size 0.45)
		(drill 0.2)
		(layers "F.Cu" "B.Cu")
		(remove_unused_layers yes)
		(keep_end_layers yes)
		(zone_layer_connections "In3.Cu")
		(net 388)
	)
	(via
		(at 114.2 105.226)
		(size 0.45)
		(drill 0.2)
		(layers "F.Cu" "B.Cu")
		(remove_unused_layers yes)
		(keep_end_layers yes)
		(zone_layer_connections "In3.Cu")
		(net 388)
	)
	(segment
		(start 84.74 71.12)
		(end 84.76 71.1)
		(width 0.15)
		(layer "B.Cu")
		(net 388)
	)
	(segment
		(start 84.74 72.3)
		(end 84.74 71.12)
		(width 0.15)
		(layer "B.Cu")
		(net 388)
	)
	(segment
		(start 113.6 97.6)
		(end 112.15 99.05)
		(width 0.15)
		(layer "In5.Cu")
		(net 388)
	)
	(segment
		(start 84.76 71.1)
		(end 95.36 60.5)
		(width 0.15)
		(layer "In5.Cu")
		(net 388)
	)
	(segment
		(start 95.36 60.5)
		(end 107.7 60.5)
		(width 0.15)
		(layer "In5.Cu")
		(net 388)
	)
	(segment
		(start 112.33 65.13)
		(end 112.33 84.16)
		(width 0.15)
		(layer "In5.Cu")
		(net 388)
	)
	(segment
		(start 112.33 84.16)
		(end 113.6 85.43)
		(width 0.15)
		(layer "In5.Cu")
		(net 388)
	)
	(segment
		(start 113.6 85.43)
		(end 113.6 97.6)
		(width 0.15)
		(layer "In5.Cu")
		(net 388)
	)
	(segment
		(start 107.7 60.5)
		(end 112.33 65.13)
		(width 0.15)
		(layer "In5.Cu")
		(net 388)
	)
	(segment
		(start 112 106.067704)
		(end 112 108.45)
		(width 0.15)
		(layer "F.Cu")
		(net 390)
	)
	(segment
		(start 113.37 109.82)
		(end 115.4 109.82)
		(width 0.15)
		(layer "F.Cu")
		(net 390)
	)
	(segment
		(start 112 108.45)
		(end 113.37 109.82)
		(width 0.15)
		(layer "F.Cu")
		(net 390)
	)
	(segment
		(start 111.4 105.467704)
		(end 112 106.067704)
		(width 0.15)
		(layer "F.Cu")
		(net 390)
	)
	(segment
		(start 111.4 104.9)
		(end 111.4 105.467704)
		(width 0.15)
		(layer "F.Cu")
		(net 390)
	)
	(segment
		(start 54.699 73.715)
		(end 54.699 75.099)
		(width 0.15)
		(layer "F.Cu")
		(net 392)
	)
	(segment
		(start 57.05 75.75)
		(end 57.85 76.55)
		(width 0.15)
		(layer "F.Cu")
		(net 392)
	)
	(segment
		(start 55.35 75.75)
		(end 57.05 75.75)
		(width 0.15)
		(layer "F.Cu")
		(net 392)
	)
	(segment
		(start 57.85 76.55)
		(end 57.85 77.52)
		(width 0.15)
		(layer "F.Cu")
		(net 392)
	)
	(segment
		(start 54.699 75.099)
		(end 55.35 75.75)
		(width 0.15)
		(layer "F.Cu")
		(net 392)
	)
	(segment
		(start 91.65 70.65)
		(end 55.85 70.65)
		(width 0.15)
		(layer "F.Cu")
		(net 393)
	)
	(segment
		(start 55.85 70.65)
		(end 55.6495 70.8505)
		(width 0.15)
		(layer "F.Cu")
		(net 393)
	)
	(segment
		(start 55.6495 70.8505)
		(end 55.6495 71.515)
		(width 0.15)
		(layer "F.Cu")
		(net 393)
	)
	(via
		(at 108.35 69.55)
		(size 0.45)
		(drill 0.2)
		(layers "F.Cu" "B.Cu")
		(remove_unused_layers yes)
		(keep_end_layers yes)
		(zone_layer_connections)
		(net 393)
	)
	(via
		(at 91.65 70.65)
		(size 0.45)
		(drill 0.2)
		(layers "F.Cu" "B.Cu")
		(remove_unused_layers yes)
		(keep_end_layers yes)
		(zone_layer_connections)
		(net 393)
	)
	(segment
		(start 108.4 69.6)
		(end 108.35 69.55)
		(width 0.15)
		(layer "B.Cu")
		(net 393)
	)
	(segment
		(start 109.02 69.6)
		(end 108.4 69.6)
		(width 0.15)
		(layer "B.Cu")
		(net 393)
	)
	(segment
		(start 94.325 67.975)
		(end 106.775 67.975)
		(width 0.15)
		(layer "In5.Cu")
		(net 393)
	)
	(segment
		(start 106.775 67.975)
		(end 108.35 69.55)
		(width 0.15)
		(layer "In5.Cu")
		(net 393)
	)
	(segment
		(start 91.65 70.65)
		(end 94.325 67.975)
		(width 0.15)
		(layer "In5.Cu")
		(net 393)
	)
	(via
		(at 76.225 97.84)
		(size 0.45)
		(drill 0.2)
		(layers "F.Cu" "B.Cu")
		(remove_unused_layers yes)
		(keep_end_layers yes)
		(zone_layer_connections)
		(net 394)
	)
	(via
		(at 106.2 69.2)
		(size 0.45)
		(drill 0.2)
		(layers "F.Cu" "B.Cu")
		(remove_unused_layers yes)
		(keep_end_layers yes)
		(zone_layer_connections)
		(net 394)
	)
	(segment
		(start 106.2 68.63)
		(end 106.2 69.77)
		(width 0.2)
		(layer "B.Cu")
		(net 394)
	)
	(segment
		(start 83.17 94.53)
		(end 83.17 93.31)
		(width 0.15)
		(layer "In5.Cu")
		(net 394)
	)
	(segment
		(start 82.8 92.35)
		(end 83.23 91.92)
		(width 0.15)
		(layer "In5.Cu")
		(net 394)
	)
	(segment
		(start 83.32 90.33)
		(end 83.32 88.564998)
		(width 0.15)
		(layer "In5.Cu")
		(net 394)
	)
	(segment
		(start 83.23 91.92)
		(end 83.23 91.6)
		(width 0.15)
		(layer "In5.Cu")
		(net 394)
	)
	(segment
		(start 82.8 92.94)
		(end 82.8 92.35)
		(width 0.15)
		(layer "In5.Cu")
		(net 394)
	)
	(segment
		(start 99.8 69.55)
		(end 105.85 69.55)
		(width 0.15)
		(layer "In5.Cu")
		(net 394)
	)
	(segment
		(start 90 79.35)
		(end 99.8 69.55)
		(width 0.15)
		(layer "In5.Cu")
		(net 394)
	)
	(segment
		(start 76.225 97.84)
		(end 76.635 98.25)
		(width 0.15)
		(layer "In5.Cu")
		(net 394)
	)
	(segment
		(start 90 81.884998)
		(end 90 79.35)
		(width 0.15)
		(layer "In5.Cu")
		(net 394)
	)
	(segment
		(start 83.17 93.31)
		(end 82.8 92.94)
		(width 0.15)
		(layer "In5.Cu")
		(net 394)
	)
	(segment
		(start 76.635 98.25)
		(end 79.45 98.25)
		(width 0.15)
		(layer "In5.Cu")
		(net 394)
	)
	(segment
		(start 83.23 91.6)
		(end 83.7 91.13)
		(width 0.15)
		(layer "In5.Cu")
		(net 394)
	)
	(segment
		(start 105.85 69.55)
		(end 106.2 69.2)
		(width 0.15)
		(layer "In5.Cu")
		(net 394)
	)
	(segment
		(start 83.7 91.13)
		(end 83.7 90.71)
		(width 0.15)
		(layer "In5.Cu")
		(net 394)
	)
	(segment
		(start 83.7 90.71)
		(end 83.32 90.33)
		(width 0.15)
		(layer "In5.Cu")
		(net 394)
	)
	(segment
		(start 79.45 98.25)
		(end 83.17 94.53)
		(width 0.15)
		(layer "In5.Cu")
		(net 394)
	)
	(segment
		(start 83.32 88.564998)
		(end 90 81.884998)
		(width 0.15)
		(layer "In5.Cu")
		(net 394)
	)
	(via
		(at 107.2 69.2)
		(size 0.45)
		(drill 0.2)
		(layers "F.Cu" "B.Cu")
		(remove_unused_layers yes)
		(keep_end_layers yes)
		(zone_layer_connections)
		(net 395)
	)
	(via
		(at 75.725 96.975)
		(size 0.45)
		(drill 0.2)
		(layers "F.Cu" "B.Cu")
		(remove_unused_layers yes)
		(keep_end_layers yes)
		(zone_layer_connections)
		(net 395)
	)
	(segment
		(start 107.2 68.63)
		(end 107.2 69.77)
		(width 0.2)
		(layer "B.Cu")
		(net 395)
	)
	(segment
		(start 76.388189 97.276)
		(end 76.538189 97.426)
		(width 0.15)
		(layer "In5.Cu")
		(net 395)
	)
	(segment
		(start 82.25 94.45)
		(end 82.25 91.5)
		(width 0.15)
		(layer "In5.Cu")
		(net 395)
	)
	(segment
		(start 89 78.4)
		(end 98.75 68.65)
		(width 0.15)
		(layer "In5.Cu")
		(net 395)
	)
	(segment
		(start 75.725 96.975)
		(end 76.026 97.276)
		(width 0.15)
		(layer "In5.Cu")
		(net 395)
	)
	(segment
		(start 89 81.55)
		(end 89 78.4)
		(width 0.15)
		(layer "In5.Cu")
		(net 395)
	)
	(segment
		(start 82.75 91)
		(end 82.75 87.8)
		(width 0.15)
		(layer "In5.Cu")
		(net 395)
	)
	(segment
		(start 76.538189 97.426)
		(end 79.274 97.426)
		(width 0.15)
		(layer "In5.Cu")
		(net 395)
	)
	(segment
		(start 82.25 91.5)
		(end 82.75 91)
		(width 0.15)
		(layer "In5.Cu")
		(net 395)
	)
	(segment
		(start 76.026 97.276)
		(end 76.388189 97.276)
		(width 0.15)
		(layer "In5.Cu")
		(net 395)
	)
	(segment
		(start 106.65 68.65)
		(end 107.2 69.2)
		(width 0.15)
		(layer "In5.Cu")
		(net 395)
	)
	(segment
		(start 98.75 68.65)
		(end 106.65 68.65)
		(width 0.15)
		(layer "In5.Cu")
		(net 395)
	)
	(segment
		(start 79.274 97.426)
		(end 82.25 94.45)
		(width 0.15)
		(layer "In5.Cu")
		(net 395)
	)
	(segment
		(start 82.75 87.8)
		(end 89 81.55)
		(width 0.15)
		(layer "In5.Cu")
		(net 395)
	)
	(segment
		(start 79.87 83.15)
		(end 79.25 83.15)
		(width 0.15)
		(layer "F.Cu")
		(net 396)
	)
	(segment
		(start 79.25 86.35)
		(end 79.95 86.35)
		(width 0.15)
		(layer "F.Cu")
		(net 396)
	)
	(segment
		(start 79.1 83.3)
		(end 79.1 86.2)
		(width 0.15)
		(layer "F.Cu")
		(net 396)
	)
	(segment
		(start 79.25 83.15)
		(end 79.1 83.3)
		(width 0.15)
		(layer "F.Cu")
		(net 396)
	)
	(segment
		(start 79.1 86.2)
		(end 79.25 86.35)
		(width 0.15)
		(layer "F.Cu")
		(net 396)
	)
	(segment
		(start 108.53 99.62)
		(end 109.15 99.62)
		(width 0.15)
		(layer "F.Cu")
		(net 397)
	)
	(segment
		(start 106.5 116.65)
		(end 109.3 113.85)
		(width 0.15)
		(layer "F.Cu")
		(net 397)
	)
	(segment
		(start 109.3 113.85)
		(end 109.3 111.35)
		(width 0.15)
		(layer "F.Cu")
		(net 397)
	)
	(segment
		(start 107.95 110)
		(end 107.95 100.2)
		(width 0.15)
		(layer "F.Cu")
		(net 397)
	)
	(segment
		(start 109.15 99.62)
		(end 110.15 99.62)
		(width 0.15)
		(layer "F.Cu")
		(net 397)
	)
	(segment
		(start 109.3 111.35)
		(end 107.95 110)
		(width 0.15)
		(layer "F.Cu")
		(net 397)
	)
	(segment
		(start 84.59 115)
		(end 84.59 115.94)
		(width 0.15)
		(layer "F.Cu")
		(net 397)
	)
	(segment
		(start 85.3 116.65)
		(end 106.5 116.65)
		(width 0.15)
		(layer "F.Cu")
		(net 397)
	)
	(segment
		(start 84.59 115.94)
		(end 85.3 116.65)
		(width 0.15)
		(layer "F.Cu")
		(net 397)
	)
	(segment
		(start 107.95 100.2)
		(end 108.53 99.62)
		(width 0.15)
		(layer "F.Cu")
		(net 397)
	)
	(segment
		(start 110.9 104.9)
		(end 110.9 105.45)
		(width 0.15)
		(layer "F.Cu")
		(net 398)
	)
	(segment
		(start 110.15 106.07)
		(end 111.15 106.07)
		(width 0.15)
		(layer "F.Cu")
		(net 398)
	)
	(segment
		(start 111.15 105.7)
		(end 111.15 106.07)
		(width 0.15)
		(layer "F.Cu")
		(net 398)
	)
	(segment
		(start 110.9 105.45)
		(end 111.15 105.7)
		(width 0.15)
		(layer "F.Cu")
		(net 398)
	)
	(segment
		(start 111.900001 100.83)
		(end 112.15 100.58)
		(width 0.15)
		(layer "F.Cu")
		(net 399)
	)
	(segment
		(start 111.9 101.9)
		(end 111.900001 100.83)
		(width 0.15)
		(layer "F.Cu")
		(net 399)
	)
	(segment
		(start 112.15 100.58)
		(end 113.15 100.579999)
		(width 0.15)
		(layer "F.Cu")
		(net 399)
	)
	(segment
		(start 111.15 100.58)
		(end 111.4 100.83)
		(width 0.15)
		(layer "F.Cu")
		(net 400)
	)
	(segment
		(start 111.4 100.83)
		(end 111.4 101.9)
		(width 0.15)
		(layer "F.Cu")
		(net 400)
	)
	(segment
		(start 98.3735 89.883)
		(end 98.655 90.1645)
		(width 0.2)
		(layer "F.Cu")
		(net 402)
	)
	(segment
		(start 96.629019 90.961049)
		(end 96.387881 91.202186)
		(width 0.202)
		(layer "F.Cu")
		(net 402)
	)
	(segment
		(start 98.68 90.1645)
		(end 98.68 90.164)
		(width 0.2)
		(layer "F.Cu")
		(net 402)
	)
	(segment
		(start 97.445377 90.145381)
		(end 97.444685 90.145381)
		(width 0.202)
		(layer "F.Cu")
		(net 402)
	)
	(segment
		(start 98.12128 89.883)
		(end 98.3735 89.883)
		(width 0.2)
		(layer "F.Cu")
		(net 402)
	)
	(segment
		(start 96.252512 91.337556)
		(end 95.225 92.365066)
		(width 0.202)
		(layer "F.Cu")
		(net 402)
	)
	(segment
		(start 97.444685 90.145381)
		(end 97.23641 90.353656)
		(width 0.202)
		(layer "F.Cu")
		(net 402)
	)
	(segment
		(start 97.23641 90.719912)
		(end 96.995273 90.96105)
		(width 0.202)
		(layer "F.Cu")
		(net 402)
	)
	(segment
		(start 97.4486 90.145381)
		(end 97.476092 90.117889)
		(width 0.2)
		(layer "F.Cu")
		(net 402)
	)
	(segment
		(start 96.252511 91.337555)
		(end 96.252512 91.337556)
		(width 0.202)
		(layer "F.Cu")
		(net 402)
	)
	(segment
		(start 98.655 90.1645)
		(end 98.68 90.1645)
		(width 0.2)
		(layer "F.Cu")
		(net 402)
	)
	(segment
		(start 95.225 92.365066)
		(end 95.225 92.65)
		(width 0.202)
		(layer "F.Cu")
		(net 402)
	)
	(segment
		(start 96.387881 91.202186)
		(end 96.252511 91.337555)
		(width 0.202)
		(layer "F.Cu")
		(net 402)
	)
	(segment
		(start 97.445377 90.145381)
		(end 97.4486 90.145381)
		(width 0.2)
		(layer "F.Cu")
		(net 402)
	)
	(via
		(at 98.68 90.164)
		(size 0.45)
		(drill 0.2)
		(layers "F.Cu" "B.Cu")
		(remove_unused_layers yes)
		(keep_end_layers yes)
		(zone_layer_connections)
		(net 402)
	)
	(arc
		(start 96.812145 90.96105)
		(mid 96.720581 90.923124)
		(end 96.629019 90.961049)
		(width 0.202)
		(layer "F.Cu")
		(net 402)
	)
	(arc
		(start 96.995273 90.96105)
		(mid 96.90371 90.998976)
		(end 96.812145 90.96105)
		(width 0.202)
		(layer "F.Cu")
		(net 402)
	)
	(arc
		(start 97.23641 90.536784)
		(mid 97.274336 90.628349)
		(end 97.23641 90.719912)
		(width 0.202)
		(layer "F.Cu")
		(net 402)
	)
	(arc
		(start 97.476092 90.117889)
		(mid 97.778097 89.943768)
		(end 98.12128 89.883)
		(width 0.2)
		(layer "F.Cu")
		(net 402)
	)
	(arc
		(start 97.23641 90.353656)
		(mid 97.198482 90.445221)
		(end 97.23641 90.536784)
		(width 0.202)
		(layer "F.Cu")
		(net 402)
	)
	(segment
		(start 97.195977 89.843957)
		(end 95.049934 91.99)
		(width 0.202)
		(layer "F.Cu")
		(net 403)
	)
	(segment
		(start 95.049934 91.99)
		(end 94.93 91.99)
		(width 0.202)
		(layer "F.Cu")
		(net 403)
	)
	(segment
		(start 98.3735 89.496)
		(end 98.03602 89.496)
		(width 0.202)
		(layer "F.Cu")
		(net 403)
	)
	(segment
		(start 98.655 89.2145)
		(end 98.68 89.2145)
		(width 0.2)
		(layer "F.Cu")
		(net 403)
	)
	(segment
		(start 94.93 91.99)
		(end 94.725 91.785)
		(width 0.202)
		(layer "F.Cu")
		(net 403)
	)
	(segment
		(start 98.68 89.2145)
		(end 98.68 89.214)
		(width 0.2)
		(layer "F.Cu")
		(net 403)
	)
	(segment
		(start 98.3735 89.496)
		(end 98.655 89.2145)
		(width 0.2)
		(layer "F.Cu")
		(net 403)
	)
	(via
		(at 98.68 89.214)
		(size 0.45)
		(drill 0.2)
		(layers "F.Cu" "B.Cu")
		(remove_unused_layers yes)
		(keep_end_layers yes)
		(zone_layer_connections)
		(net 403)
	)
	(arc
		(start 98.03602 89.496)
		(mid 97.581392 89.586431)
		(end 97.195977 89.843957)
		(width 0.202)
		(layer "F.Cu")
		(net 403)
	)
	(segment
		(start 105.71 86.644)
		(end 105.71 87.62)
		(width 0.2)
		(layer "B.Cu")
		(net 404)
	)
	(segment
		(start 105.71 87.62)
		(end 105.475 87.855)
		(width 0.2)
		(layer "B.Cu")
		(net 404)
	)
	(segment
		(start 100.595 90.164)
		(end 100.62 90.164)
		(width 0.202)
		(layer "B.Cu")
		(net 405)
	)
	(segment
		(start 100.645 90.164)
		(end 100.62 90.164)
		(width 0.202)
		(layer "B.Cu")
		(net 405)
	)
	(segment
		(start 99.9455 89.8835)
		(end 100.3145 89.8835)
		(width 0.202)
		(layer "B.Cu")
		(net 405)
	)
	(segment
		(start 101.6 90.164)
		(end 101.575 90.164)
		(width 0.202)
		(layer "B.Cu")
		(net 405)
	)
	(segment
		(start 100.3145 89.8835)
		(end 100.595 90.164)
		(width 0.202)
		(layer "B.Cu")
		(net 405)
	)
	(segment
		(start 101.575 90.164)
		(end 101.2945 89.8835)
		(width 0.202)
		(layer "B.Cu")
		(net 405)
	)
	(segment
		(start 99.64 90.164)
		(end 99.665 90.164)
		(width 0.202)
		(layer "B.Cu")
		(net 405)
	)
	(segment
		(start 99.665 90.164)
		(end 99.9455 89.8835)
		(width 0.202)
		(layer "B.Cu")
		(net 405)
	)
	(segment
		(start 100.9255 89.8835)
		(end 100.645 90.164)
		(width 0.202)
		(layer "B.Cu")
		(net 405)
	)
	(segment
		(start 101.2945 89.8835)
		(end 100.9255 89.8835)
		(width 0.202)
		(layer "B.Cu")
		(net 405)
	)
	(segment
		(start 101.6 89.214)
		(end 101.575 89.214)
		(width 0.202)
		(layer "B.Cu")
		(net 406)
	)
	(segment
		(start 100.3145 89.4945)
		(end 100.595 89.214)
		(width 0.202)
		(layer "B.Cu")
		(net 406)
	)
	(segment
		(start 100.9255 89.4945)
		(end 100.645 89.214)
		(width 0.202)
		(layer "B.Cu")
		(net 406)
	)
	(segment
		(start 101.575 89.214)
		(end 101.2945 89.4945)
		(width 0.202)
		(layer "B.Cu")
		(net 406)
	)
	(segment
		(start 99.665 89.214)
		(end 99.9455 89.4945)
		(width 0.202)
		(layer "B.Cu")
		(net 406)
	)
	(segment
		(start 99.9455 89.4945)
		(end 100.3145 89.4945)
		(width 0.202)
		(layer "B.Cu")
		(net 406)
	)
	(segment
		(start 100.645 89.214)
		(end 100.62 89.214)
		(width 0.202)
		(layer "B.Cu")
		(net 406)
	)
	(segment
		(start 100.595 89.214)
		(end 100.62 89.214)
		(width 0.202)
		(layer "B.Cu")
		(net 406)
	)
	(segment
		(start 101.2945 89.4945)
		(end 100.9255 89.4945)
		(width 0.202)
		(layer "B.Cu")
		(net 406)
	)
	(segment
		(start 99.64 89.214)
		(end 99.665 89.214)
		(width 0.202)
		(layer "B.Cu")
		(net 406)
	)
	(segment
		(start 102.876 89.848)
		(end 102.56 90.164)
		(width 0.202)
		(layer "B.Cu")
		(net 407)
	)
	(segment
		(start 103.369 89.848)
		(end 102.876 89.848)
		(width 0.202)
		(layer "B.Cu")
		(net 407)
	)
	(segment
		(start 103.874 90.253)
		(end 103.774 90.253)
		(width 0.202)
		(layer "B.Cu")
		(net 407)
	)
	(segment
		(start 103.774 90.253)
		(end 103.369 89.848)
		(width 0.202)
		(layer "B.Cu")
		(net 407)
	)
	(segment
		(start 103.774 89.054)
		(end 103.369 89.459)
		(width 0.202)
		(layer "B.Cu")
		(net 408)
	)
	(segment
		(start 102.805 89.459)
		(end 102.56 89.214)
		(width 0.202)
		(layer "B.Cu")
		(net 408)
	)
	(segment
		(start 103.369 89.459)
		(end 102.805 89.459)
		(width 0.202)
		(layer "B.Cu")
		(net 408)
	)
	(segment
		(start 103.874 89.054)
		(end 103.774 89.054)
		(width 0.202)
		(layer "B.Cu")
		(net 408)
	)
	(segment
		(start 90.75 53.35)
		(end 90.75 59.76)
		(width 0.15)
		(layer "F.Cu")
		(net 410)
	)
	(segment
		(start 90.75 59.76)
		(end 91.59 60.6)
		(width 0.15)
		(layer "F.Cu")
		(net 410)
	)
	(segment
		(start 91.59 60.6)
		(end 92.37 60.6)
		(width 0.15)
		(layer "F.Cu")
		(net 410)
	)
	(segment
		(start 55.05 125.1)
		(end 56.67 125.1)
		(width 0.15)
		(layer "F.Cu")
		(net 411)
	)
	(segment
		(start 56.67 122.75)
		(end 55.05 122.75)
		(width 0.15)
		(layer "F.Cu")
		(net 412)
	)
	(segment
		(start 55.050001 120.4)
		(end 56.67 120.4)
		(width 0.15)
		(layer "F.Cu")
		(net 413)
	)
	(segment
		(start 56.67 118.05)
		(end 55.05 118.05)
		(width 0.15)
		(layer "F.Cu")
		(net 414)
	)
	(segment
		(start 55.05 127.449999)
		(end 56.67 127.45)
		(width 0.15)
		(layer "F.Cu")
		(net 415)
	)
	(via
		(at 57.63 125.1)
		(size 0.45)
		(drill 0.2)
		(layers "F.Cu" "B.Cu")
		(remove_unused_layers yes)
		(keep_end_layers yes)
		(zone_layer_connections)
		(net 416)
	)
	(segment
		(start 56.899999 125.1)
		(end 57.63 125.1)
		(width 0.15)
		(layer "B.Cu")
		(net 416)
	)
	(via
		(at 57.63 122.75)
		(size 0.45)
		(drill 0.2)
		(layers "F.Cu" "B.Cu")
		(remove_unused_layers yes)
		(keep_end_layers yes)
		(zone_layer_connections)
		(net 417)
	)
	(segment
		(start 56.899999 122.75)
		(end 57.63 122.75)
		(width 0.15)
		(layer "B.Cu")
		(net 417)
	)
	(via
		(at 57.63 120.4)
		(size 0.45)
		(drill 0.2)
		(layers "F.Cu" "B.Cu")
		(remove_unused_layers yes)
		(keep_end_layers yes)
		(zone_layer_connections)
		(net 418)
	)
	(segment
		(start 57.63 120.4)
		(end 56.899999 120.4)
		(width 0.15)
		(layer "B.Cu")
		(net 418)
	)
	(via
		(at 57.63 118.05)
		(size 0.45)
		(drill 0.2)
		(layers "F.Cu" "B.Cu")
		(remove_unused_layers yes)
		(keep_end_layers yes)
		(zone_layer_connections)
		(net 419)
	)
	(segment
		(start 56.899999 118.05)
		(end 57.63 118.05)
		(width 0.15)
		(layer "B.Cu")
		(net 419)
	)
	(zone
		(net 314)
		(net_name "VCC")
		(layer "F.Cu")
		(hatch edge 0.5)
		(priority 7)
		(connect_pads yes
			(clearance 0.15)
		)
		(min_thickness 0.25)
		(filled_areas_thickness no)
		(fill yes
			(thermal_gap 0.5)
			(thermal_bridge_width 0.5)
			(smoothing fillet)
			(radius 0.2)
		)
		(polygon
			(pts
				(xy 56.270001 104.000001) (xy 51.245001 104) (xy 51.245 105.55) (xy 54.945002 105.55) (xy 55.595002 104.9)
				(xy 56.270001 104.9)
			)
		)
	)
	(zone
		(net 314)
		(net_name "VCC")
		(layer "F.Cu")
		(hatch edge 0.5)
		(priority 7)
		(connect_pads yes
			(clearance 0.15)
		)
		(min_thickness 0.25)
		(filled_areas_thickness no)
		(fill yes
			(thermal_gap 0.5)
			(thermal_bridge_width 0.5)
			(smoothing fillet)
			(radius 0.2)
		)
		(polygon
			(pts
				(xy 56.270001 111.7) (xy 51.245001 111.699999) (xy 51.245 113.249999) (xy 54.945002 113.249999)
				(xy 55.595002 112.599999) (xy 56.270001 112.599999)
			)
		)
	)
	(zone
		(net 24)
		(net_name "XFI_PVDD")
		(layer "F.Cu")
		(hatch edge 0.5)
		(priority 34)
		(connect_pads yes
			(clearance 0.15)
		)
		(min_thickness 0.15)
		(filled_areas_thickness no)
		(fill yes
			(thermal_gap 0.5)
			(thermal_bridge_width 0.5)
			(smoothing fillet)
			(radius 0.2)
		)
		(polygon
			(pts
				(xy 70.4 105) (xy 71.7 105) (xy 71.7 103.65) (xy 79.6 103.65) (xy 79.6 102.4) (xy 70.4 102.4)
			)
		)
	)
	(zone
		(net 314)
		(net_name "VCC")
		(layer "F.Cu")
		(hatch edge 0.5)
		(priority 7)
		(connect_pads yes
			(clearance 0.15)
		)
		(min_thickness 0.25)
		(filled_areas_thickness no)
		(fill yes
			(thermal_gap 0.5)
			(thermal_bridge_width 0.5)
			(smoothing fillet)
			(radius 0.2)
		)
		(polygon
			(pts
				(xy 56.270002 88.599999) (xy 51.245002 88.599998) (xy 51.245001 90.149998) (xy 54.945003 90.149998)
				(xy 55.595003 89.499998) (xy 56.270002 89.499998)
			)
		)
	)
	(zone
		(net 28)
		(net_name "GND")
		(layer "F.Cu")
		(hatch edge 0.5)
		(priority 8)
		(connect_pads yes
			(clearance 0.15)
		)
		(min_thickness 0.25)
		(filled_areas_thickness no)
		(fill yes
			(thermal_gap 0.5)
			(thermal_bridge_width 0.5)
			(smoothing fillet)
			(radius 0.2)
		)
		(polygon
			(pts
				(xy 56.220001 102.975) (xy 55.420001 102.975) (xy 54.695001 102.25) (xy 51.245001 102.250001) (xy 51.245001 103.8)
				(xy 55.295001 103.8) (xy 55.695001 103.4) (xy 56.220001 103.4)
			)
		)
	)
	(zone
		(net 28)
		(net_name "GND")
		(layer "F.Cu")
		(hatch edge 0.5)
		(priority 8)
		(connect_pads yes
			(clearance 0.15)
		)
		(min_thickness 0.25)
		(filled_areas_thickness no)
		(fill yes
			(thermal_gap 0.5)
			(thermal_bridge_width 0.5)
			(smoothing fillet)
			(radius 0.2)
		)
		(polygon
			(pts
				(xy 71.425001 80.159997) (xy 71.425001 79.359997) (xy 72.150001 78.634997) (xy 72.15 75.184997)
				(xy 70.600001 75.184997) (xy 70.600001 79.234997) (xy 71.000001 79.634997) (xy 71.000001 80.159997)
			)
		)
	)
	(zone
		(net 310)
		(net_name "/Power/+1V88_OUT")
		(layer "F.Cu")
		(hatch edge 0.5)
		(priority 37)
		(connect_pads yes
			(clearance 0.15)
		)
		(min_thickness 0.25)
		(filled_areas_thickness no)
		(fill yes
			(thermal_gap 0.5)
			(thermal_bridge_width 0.5)
			(smoothing fillet)
			(radius 0.2)
		)
		(polygon
			(pts
				(xy 63.12 98.850002) (xy 60.72 98.850002) (xy 60.72 105.900003) (xy 63.12 105.900002)
			)
		)
	)
	(zone
		(net 28)
		(net_name "GND")
		(layer "F.Cu")
		(hatch edge 0.5)
		(priority 8)
		(connect_pads yes
			(clearance 0.15)
		)
		(min_thickness 0.25)
		(filled_areas_thickness no)
		(fill yes
			(thermal_gap 0.5)
			(thermal_bridge_width 0.5)
			(smoothing fillet)
			(radius 0.2)
		)
		(polygon
			(pts
				(xy 56.220002 87.574998) (xy 55.420002 87.574998) (xy 54.695002 86.849998) (xy 51.245002 86.849999)
				(xy 51.245002 88.399998) (xy 55.295002 88.399998) (xy 55.695002 87.999998) (xy 56.220002 87.999998)
			)
		)
	)
	(zone
		(net 28)
		(net_name "GND")
		(layer "F.Cu")
		(hatch edge 0.5)
		(priority 17)
		(connect_pads yes
			(clearance 0.15)
		)
		(min_thickness 0.25)
		(filled_areas_thickness no)
		(fill yes
			(thermal_gap 0.5)
			(thermal_bridge_width 0.5)
			(smoothing fillet)
			(radius 0.2)
		)
		(polygon
			(pts
				(xy 58.99 98.859988) (xy 58.99 101.510001) (xy 60.55 101.510001) (xy 60.55 98.859989)
			)
		)
	)
	(zone
		(net 334)
		(net_name "/Power/VCCD_SW")
		(layer "F.Cu")
		(hatch edge 0.5)
		(priority 6)
		(connect_pads yes
			(clearance 0.15)
		)
		(min_thickness 0.25)
		(filled_areas_thickness no)
		(fill yes
			(thermal_gap 0.5)
			(thermal_bridge_width 0.5)
			(smoothing fillet)
			(radius 0.2)
		)
		(polygon
			(pts
				(xy 55.75 88.149999) (xy 55.75 88.449999) (xy 56.675 88.45) (xy 57.65 89.425) (xy 57.649999 90.199998)
				(xy 59.149999 90.199999) (xy 59.149999 86.699999) (xy 57.649998 86.700001) (xy 57.65 87.524999)
				(xy 57.025 88.149999)
			)
		)
	)
	(zone
		(net 303)
		(net_name "/Power/+VCCD_OUT")
		(layer "F.Cu")
		(hatch edge 0.5)
		(priority 37)
		(connect_pads yes
			(clearance 0.15)
		)
		(min_thickness 0.25)
		(filled_areas_thickness no)
		(fill yes
			(thermal_gap 0.5)
			(thermal_bridge_width 0.5)
			(smoothing fillet)
			(radius 0.2)
		)
		(polygon
			(pts
				(xy 63.12 83.450002) (xy 60.72 83.450002) (xy 60.72 90.500002) (xy 63.12 90.500002)
			)
		)
	)
	(zone
		(net 28)
		(net_name "GND")
		(layer "F.Cu")
		(hatch edge 0.5)
		(priority 17)
		(connect_pads yes
			(clearance 0.15)
		)
		(min_thickness 0.25)
		(filled_areas_thickness no)
		(fill yes
			(thermal_gap 0.5)
			(thermal_bridge_width 0.5)
			(smoothing fillet)
			(radius 0.2)
		)
		(polygon
			(pts
				(xy 59.02 83.449988) (xy 59.02 86.100001) (xy 60.58 86.100001) (xy 60.58 83.449989)
			)
		)
	)
	(zone
		(net 43)
		(net_name "Net-(C37-Pad2)")
		(layer "F.Cu")
		(hatch edge 0.5)
		(priority 48)
		(connect_pads yes
			(clearance 0.15)
		)
		(min_thickness 0.15)
		(filled_areas_thickness no)
		(fill yes
			(thermal_gap 0.5)
			(thermal_bridge_width 0.5)
			(smoothing fillet)
			(radius 0.2)
		)
		(polygon
			(pts
				(xy 86.05 58.002) (xy 87.85 58.002) (xy 87.85 50.352) (xy 77.95 50.352) (xy 77.95 56.802) (xy 79.2 56.802)
				(xy 79.2 54.302) (xy 86.6 54.302) (xy 86.6 56.804) (xy 86.05 57.302)
			)
		)
	)
	(zone
		(net 351)
		(net_name "/Power/+5V_USB")
		(layer "F.Cu")
		(hatch edge 0.5)
		(priority 20)
		(connect_pads yes
			(clearance 0.15)
		)
		(min_thickness 0.25)
		(filled_areas_thickness no)
		(fill yes
			(thermal_gap 0.5)
			(thermal_bridge_width 0.5)
			(smoothing fillet)
			(radius 0.2)
		)
		(polygon
			(pts
				(xy 80.14 55.619999) (xy 80.86 55.619999) (xy 80.86 58.25) (xy 84.91 58.25) (xy 84.91 55.639999)
				(xy 85.66 55.639999) (xy 85.66 63.05) (xy 84.8 63.05) (xy 84.8 65.599999) (xy 80.14 65.599999)
			)
		)
	)
	(zone
		(net 314)
		(net_name "VCC")
		(layer "F.Cu")
		(hatch edge 0.5)
		(priority 7)
		(connect_pads yes
			(clearance 0.15)
		)
		(min_thickness 0.25)
		(filled_areas_thickness no)
		(fill yes
			(thermal_gap 0.5)
			(thermal_bridge_width 0.5)
			(smoothing fillet)
			(radius 0.2)
		)
		(polygon
			(pts
				(xy 70.4 80.209996) (xy 70.400001 75.184997) (xy 68.850001 75.184996) (xy 68.850001 78.884998) (xy 69.500001 79.534998)
				(xy 69.500001 80.209997)
			)
		)
	)
	(zone
		(net 28)
		(net_name "GND")
		(layer "F.Cu")
		(hatch edge 0.5)
		(priority 43)
		(connect_pads yes
			(clearance 0.15)
		)
		(min_thickness 0.25)
		(filled_areas_thickness no)
		(fill yes
			(thermal_gap 0.5)
			(thermal_bridge_width 0.5)
			(smoothing fillet)
			(radius 0.2)
		)
		(polygon
			(pts
				(xy 66.9 94.049999) (xy 67.9 94.049999) (xy 67.9 90.049999) (xy 66.9 90.049999)
			)
		)
	)
	(zone
		(net 314)
		(net_name "VCC")
		(layer "F.Cu")
		(hatch edge 0.5)
		(priority 7)
		(connect_pads yes
			(clearance 0.15)
		)
		(min_thickness 0.25)
		(filled_areas_thickness no)
		(fill yes
			(thermal_gap 0.5)
			(thermal_bridge_width 0.5)
			(smoothing fillet)
			(radius 0.2)
		)
		(polygon
			(pts
				(xy 56.27 96.3) (xy 51.245 96.299999) (xy 51.244999 97.849999) (xy 54.945001 97.849999) (xy 55.595001 97.199999)
				(xy 56.27 97.199999)
			)
		)
	)
	(zone
		(net 28)
		(net_name "GND")
		(layer "F.Cu")
		(hatch edge 0.5)
		(priority 22)
		(connect_pads yes
			(clearance 0.15)
		)
		(min_thickness 0.25)
		(filled_areas_thickness no)
		(fill yes
			(thermal_gap 0.5)
			(thermal_bridge_width 0.5)
			(smoothing fillet)
			(radius 0.2)
		)
		(polygon
			(pts
				(xy 67.4 116.2) (xy 67.4 113.9) (xy 68 113.9) (xy 68.6 114.5) (xy 73.5 114.5) (xy 73.5 116.2)
			)
		)
	)
	(zone
		(net 6)
		(net_name "DVDD")
		(layer "F.Cu")
		(hatch edge 0.5)
		(priority 39)
		(connect_pads yes
			(clearance 0.15)
		)
		(min_thickness 0.15)
		(filled_areas_thickness no)
		(fill yes
			(thermal_gap 0.5)
			(thermal_bridge_width 0.5)
			(smoothing fillet)
			(radius 0.2)
		)
		(polygon
			(pts
				(xy 63.4 91.15) (xy 63.4 92.4) (xy 64.6 92.4) (xy 64.6 94.05) (xy 66.5 94.05) (xy 66.5 90.05) (xy 63.7 90.05)
				(xy 63.7 91.15)
			)
		)
	)
	(zone
		(net 7)
		(net_name "+3V3")
		(layer "F.Cu")
		(hatch edge 0.5)
		(priority 1)
		(connect_pads yes
			(clearance 0.15)
		)
		(min_thickness 0.25)
		(filled_areas_thickness no)
		(fill yes
			(thermal_gap 0.15)
			(thermal_bridge_width 0.25)
			(smoothing fillet)
			(radius 0.2)
		)
		(polygon
			(pts
				(xy 97.8 102.55) (xy 97.8 97.45) (xy 96.35 97.45) (xy 95.6 96.7) (xy 94.45 96.7) (xy 94.45 97.4)
				(xy 95.35 97.4) (xy 95.75 97.8) (xy 95.75 102.55)
			)
		)
	)
	(zone
		(net 28)
		(net_name "GND")
		(layer "F.Cu")
		(hatch edge 0.5)
		(priority 8)
		(connect_pads yes
			(clearance 0.15)
		)
		(min_thickness 0.25)
		(filled_areas_thickness no)
		(fill yes
			(thermal_gap 0.5)
			(thermal_bridge_width 0.5)
			(smoothing fillet)
			(radius 0.2)
		)
		(polygon
			(pts
				(xy 56.22 95.274999) (xy 55.42 95.274999) (xy 54.695 94.549999) (xy 51.245 94.55) (xy 51.245 96.099999)
				(xy 55.295 96.099999) (xy 55.695 95.699999) (xy 56.22 95.699999)
			)
		)
	)
	(zone
		(net 28)
		(net_name "GND")
		(layer "F.Cu")
		(hatch edge 0.5)
		(priority 43)
		(connect_pads yes
			(clearance 0.15)
		)
		(min_thickness 0.25)
		(filled_areas_thickness no)
		(fill yes
			(thermal_gap 0.5)
			(thermal_bridge_width 0.5)
			(smoothing fillet)
			(radius 0.2)
		)
		(polygon
			(pts
				(xy 66.9 89.75) (xy 67.9 89.75) (xy 67.9 81.45) (xy 66.9 81.45)
			)
		)
	)
	(zone
		(net 1)
		(net_name "VCCA")
		(layer "F.Cu")
		(hatch edge 0.5)
		(priority 3)
		(connect_pads yes
			(clearance 0.15)
		)
		(min_thickness 0.25)
		(filled_areas_thickness no)
		(fill yes
			(thermal_gap 0.15)
			(thermal_bridge_width 0.25)
			(smoothing fillet)
			(radius 0.2)
		)
		(polygon
			(pts
				(xy 100.55 102.55) (xy 102.5 102.55) (xy 102.5 92.55) (xy 100.55 92.55)
			)
		)
	)
	(zone
		(net 388)
		(net_name "/Fan controller/+5V")
		(layer "F.Cu")
		(hatch edge 0.5)
		(priority 59)
		(connect_pads yes
			(clearance 0.15)
		)
		(min_thickness 0.25)
		(filled_areas_thickness no)
		(fill yes
			(thermal_gap 0.5)
			(thermal_bridge_width 0.5)
			(smoothing fillet)
			(radius 0.2)
		)
		(polygon
			(pts
				(xy 116.85 107.1) (xy 116.85 107.9) (xy 112.65 107.9) (xy 112.65 103.65) (xy 115.2 103.65) (xy 115.2 107.1)
			)
		)
	)
	(zone
		(net 337)
		(net_name "/Power/1V0_SW")
		(layer "F.Cu")
		(hatch edge 0.5)
		(priority 6)
		(connect_pads yes
			(clearance 0.15)
		)
		(min_thickness 0.25)
		(filled_areas_thickness no)
		(fill yes
			(thermal_gap 0.5)
			(thermal_bridge_width 0.5)
			(smoothing fillet)
			(radius 0.2)
		)
		(polygon
			(pts
				(xy 55.749999 111.25) (xy 55.749999 111.55) (xy 56.674999 111.550001) (xy 57.649999 112.525001)
				(xy 57.649998 113.299999) (xy 59.149998 113.3) (xy 59.149998 109.8) (xy 57.649997 109.800002) (xy 57.649999 110.625)
				(xy 57.024999 111.25)
			)
		)
	)
	(zone
		(net 350)
		(net_name "/Power/+12V_IN")
		(layer "F.Cu")
		(hatch edge 0.5)
		(priority 41)
		(connect_pads yes
			(clearance 0.15)
		)
		(min_thickness 0.25)
		(filled_areas_thickness no)
		(fill yes
			(thermal_gap 0.5)
			(thermal_bridge_width 0.5)
			(smoothing fillet)
			(radius 0.2)
		)
		(polygon
			(pts
				(xy 68.06 65.77) (xy 68.06 63.17) (xy 67.56 62.67) (xy 67.56 57.97) (xy 65.66 57.97) (xy 65.66 59.17)
				(xy 64.91 59.17) (xy 64.91 65.77)
			)
		)
	)
	(zone
		(net 5)
		(net_name "P0_AVDDL")
		(layer "F.Cu")
		(hatch edge 0.5)
		(priority 23)
		(connect_pads yes
			(clearance 0.15)
		)
		(min_thickness 0.25)
		(filled_areas_thickness no)
		(fill yes
			(thermal_gap 0.5)
			(thermal_bridge_width 0.5)
			(smoothing fillet)
			(radius 0.2)
		)
		(polygon
			(pts
				(xy 67.4 109.7) (xy 68.15 109.7) (xy 68.75 110.3) (xy 73.5 110.3) (xy 73.5 108.5) (xy 67.4 108.5)
			)
		)
	)
	(zone
		(net 28)
		(net_name "GND")
		(layer "F.Cu")
		(hatch edge 0.5)
		(priority 2)
		(connect_pads yes
			(clearance 0.15)
		)
		(min_thickness 0.25)
		(filled_areas_thickness no)
		(fill yes
			(thermal_gap 0.15)
			(thermal_bridge_width 0.25)
			(smoothing fillet)
			(radius 0.2)
		)
		(polygon
			(pts
				(xy 100.35 102.55) (xy 100.35 96.95) (xy 99.85 96.45) (xy 96.7 96.45) (xy 96.05 95.8) (xy 94.9 95.8)
				(xy 94.9 96.4) (xy 95.55 96.4) (xy 96.4 97.25) (xy 98 97.25) (xy 98 102.55)
			)
		)
	)
	(zone
		(net 28)
		(net_name "GND")
		(layer "F.Cu")
		(hatch edge 0.5)
		(priority 17)
		(connect_pads yes
			(clearance 0.15)
		)
		(min_thickness 0.25)
		(filled_areas_thickness no)
		(fill yes
			(thermal_gap 0.5)
			(thermal_bridge_width 0.5)
			(smoothing fillet)
			(radius 0.2)
		)
		(polygon
			(pts
				(xy 72.899988 83.78) (xy 75.550001 83.78) (xy 75.560001 82.44) (xy 72.909989 82.44)
			)
		)
	)
	(zone
		(net 28)
		(net_name "GND")
		(layer "F.Cu")
		(hatch edge 0.5)
		(priority 17)
		(connect_pads yes
			(clearance 0.15)
		)
		(min_thickness 0.25)
		(filled_areas_thickness no)
		(fill yes
			(thermal_gap 0.5)
			(thermal_bridge_width 0.5)
			(smoothing fillet)
			(radius 0.2)
		)
		(polygon
			(pts
				(xy 59.01 91.149988) (xy 59.01 93.800001) (xy 60.57 93.800001) (xy 60.57 91.149989)
			)
		)
	)
	(zone
		(net 312)
		(net_name "/Power/+1V0_OUT")
		(layer "F.Cu")
		(hatch edge 0.5)
		(priority 37)
		(connect_pads yes
			(clearance 0.15)
		)
		(min_thickness 0.25)
		(filled_areas_thickness no)
		(fill yes
			(thermal_gap 0.5)
			(thermal_bridge_width 0.5)
			(smoothing fillet)
			(radius 0.2)
		)
		(polygon
			(pts
				(xy 63.12 106.550001) (xy 60.72 106.550001) (xy 60.72 113.600001) (xy 63.12 113.600001)
			)
		)
	)
	(zone
		(net 335)
		(net_name "/Power/1V88_SW")
		(layer "F.Cu")
		(hatch edge 0.5)
		(priority 6)
		(connect_pads yes
			(clearance 0.15)
		)
		(min_thickness 0.25)
		(filled_areas_thickness no)
		(fill yes
			(thermal_gap 0.5)
			(thermal_bridge_width 0.5)
			(smoothing fillet)
			(radius 0.2)
		)
		(polygon
			(pts
				(xy 55.749999 103.550001) (xy 55.749999 103.850001) (xy 56.674999 103.850002) (xy 57.649999 104.825002)
				(xy 57.649998 105.6) (xy 59.149998 105.600001) (xy 59.149998 102.100001) (xy 57.649997 102.100003)
				(xy 57.649999 102.925001) (xy 57.024999 103.550001)
			)
		)
	)
	(zone
		(net 28)
		(net_name "GND")
		(layer "F.Cu")
		(hatch edge 0.5)
		(priority 22)
		(connect_pads yes
			(clearance 0.15)
		)
		(min_thickness 0.25)
		(filled_areas_thickness no)
		(fill yes
			(thermal_gap 0.5)
			(thermal_bridge_width 0.5)
			(smoothing fillet)
			(radius 0.2)
		)
		(polygon
			(pts
				(xy 67.4 112.25) (xy 67.4 109.95) (xy 68 109.95) (xy 68.6 110.55) (xy 73.5 110.55) (xy 73.5 112.25)
			)
		)
	)
	(zone
		(net 14)
		(net_name "P1_AVDDL")
		(layer "F.Cu")
		(hatch edge 0.5)
		(priority 23)
		(connect_pads yes
			(clearance 0.15)
		)
		(min_thickness 0.25)
		(filled_areas_thickness no)
		(fill yes
			(thermal_gap 0.5)
			(thermal_bridge_width 0.5)
			(smoothing fillet)
			(radius 0.2)
		)
		(polygon
			(pts
				(xy 67.4 113.65) (xy 68.15 113.65) (xy 68.75 114.25) (xy 73.5 114.25) (xy 73.5 112.45) (xy 67.4 112.45)
			)
		)
	)
	(zone
		(net 314)
		(net_name "VCC")
		(layer "F.Cu")
		(hatch edge 0.5)
		(priority 47)
		(connect_pads yes
			(clearance 0.15)
		)
		(min_thickness 0.25)
		(filled_areas_thickness no)
		(fill yes
			(thermal_gap 0.5)
			(thermal_bridge_width 0.5)
			(smoothing fillet)
			(radius 0.2)
		)
		(polygon
			(pts
				(xy 87.66 66.9) (xy 87.66 69.75) (xy 64.91 69.75) (xy 64.91 66.9)
			)
		)
	)
	(zone
		(net 12)
		(net_name "XFI_VDD")
		(layer "F.Cu")
		(hatch edge 0.5)
		(priority 34)
		(connect_pads yes
			(clearance 0.15)
		)
		(min_thickness 0.15)
		(filled_areas_thickness no)
		(fill yes
			(thermal_gap 0.5)
			(thermal_bridge_width 0.5)
			(smoothing fillet)
			(radius 0.2)
		)
		(polygon
			(pts
				(xy 70.4 99.65) (xy 71.7 99.65) (xy 71.7 100.9) (xy 73.2 100.9) (xy 73.2 99.65) (xy 82.6 99.65)
				(xy 82.6 103.65) (xy 79.85 103.65) (xy 79.85 102.25) (xy 70.4 102.25)
			)
		)
	)
	(zone
		(net 28)
		(net_name "GND")
		(layer "F.Cu")
		(hatch edge 0.5)
		(priority 8)
		(connect_pads yes
			(clearance 0.15)
		)
		(min_thickness 0.25)
		(filled_areas_thickness no)
		(fill yes
			(thermal_gap 0.5)
			(thermal_bridge_width 0.5)
			(smoothing fillet)
			(radius 0.2)
		)
		(polygon
			(pts
				(xy 56.220001 110.674999) (xy 55.420001 110.674999) (xy 54.695001 109.949999) (xy 51.245001 109.95)
				(xy 51.245001 111.499999) (xy 55.295001 111.499999) (xy 55.695001 111.099999) (xy 56.220001 111.099999)
			)
		)
	)
	(zone
		(net 333)
		(net_name "/Power/3V3_SW")
		(layer "F.Cu")
		(hatch edge 0.5)
		(priority 6)
		(connect_pads yes
			(clearance 0.15)
		)
		(min_thickness 0.25)
		(filled_areas_thickness no)
		(fill yes
			(thermal_gap 0.5)
			(thermal_bridge_width 0.5)
			(smoothing fillet)
			(radius 0.2)
		)
		(polygon
			(pts
				(xy 70.850001 79.689995) (xy 70.550001 79.689995) (xy 70.549999 80.614995) (xy 69.574999 81.589995)
				(xy 68.950001 81.589994) (xy 68.95 82.589994) (xy 72.45 82.589994) (xy 72.449998 81.589992) (xy 71.475 81.589994)
				(xy 70.850001 80.964995)
			)
		)
	)
	(zone
		(net 28)
		(net_name "GND")
		(layer "F.Cu")
		(hatch edge 0.5)
		(priority 49)
		(connect_pads yes
			(clearance 0.15)
		)
		(min_thickness 0.15)
		(filled_areas_thickness no)
		(fill yes
			(thermal_gap 0.5)
			(thermal_bridge_width 0.5)
			(smoothing fillet)
			(radius 0.2)
		)
		(polygon
			(pts
				(xy 86.05 58.202) (xy 87.85 58.202) (xy 87.85 58.952) (xy 86.05 58.952)
			)
		)
	)
	(zone
		(net 311)
		(net_name "/Power/+DVDD_OUT")
		(layer "F.Cu")
		(hatch edge 0.5)
		(priority 37)
		(connect_pads yes
			(clearance 0.15)
		)
		(min_thickness 0.25)
		(filled_areas_thickness no)
		(fill yes
			(thermal_gap 0.5)
			(thermal_bridge_width 0.5)
			(smoothing fillet)
			(radius 0.2)
		)
		(polygon
			(pts
				(xy 63.119999 91.15) (xy 60.719999 91.15) (xy 60.719999 98.2) (xy 63.119999 98.2)
			)
		)
	)
	(zone
		(net 336)
		(net_name "/Power/DVDD_SW")
		(layer "F.Cu")
		(hatch edge 0.5)
		(priority 6)
		(connect_pads yes
			(clearance 0.15)
		)
		(min_thickness 0.25)
		(filled_areas_thickness no)
		(fill yes
			(thermal_gap 0.5)
			(thermal_bridge_width 0.5)
			(smoothing fillet)
			(radius 0.2)
		)
		(polygon
			(pts
				(xy 55.749998 95.85) (xy 55.749998 96.15) (xy 56.674998 96.150001) (xy 57.649998 97.125001) (xy 57.649997 97.899999)
				(xy 59.149997 97.9) (xy 59.149997 94.4) (xy 57.649996 94.400002) (xy 57.649998 95.225) (xy 57.024998 95.85)
			)
		)
	)
	(zone
		(net 28)
		(net_name "GND")
		(layer "F.Cu")
		(hatch edge 0.5)
		(priority 17)
		(connect_pads yes
			(clearance 0.15)
		)
		(min_thickness 0.25)
		(filled_areas_thickness no)
		(fill yes
			(thermal_gap 0.5)
			(thermal_bridge_width 0.5)
			(smoothing fillet)
			(radius 0.2)
		)
		(polygon
			(pts
				(xy 59 106.549988) (xy 59 109.200001) (xy 60.56 109.200001) (xy 60.56 106.549989)
			)
		)
	)
	(zone
		(net 389)
		(net_name "/Fan controller/V_{FAN}")
		(layer "F.Cu")
		(hatch edge 0.5)
		(priority 50)
		(connect_pads yes
			(clearance 0.15)
		)
		(min_thickness 0.25)
		(filled_areas_thickness no)
		(fill yes
			(thermal_gap 0.5)
			(thermal_bridge_width 0.5)
			(smoothing fillet)
			(radius 0.2)
		)
		(polygon
			(pts
				(xy 110.39 115.94) (xy 120 115.85) (xy 120 106.15) (xy 117.05 106.15) (xy 117.05 113.95) (xy 110.39 114.04)
			)
		)
	)
	(zone
		(net 28)
		(net_name "GND")
		(layer "F.Cu")
		(hatch edge 0.5)
		(priority 5)
		(connect_pads yes
			(clearance 0.15)
		)
		(min_thickness 0.25)
		(filled_areas_thickness no)
		(fill yes
			(thermal_gap 0.15)
			(thermal_bridge_width 0.25)
			(smoothing fillet)
			(radius 0.2)
		)
		(polygon
			(pts
				(xy 77.35 88.400001) (xy 77.35 80.250001) (xy 78.6 80.250001) (xy 78.6 88.400001)
			)
		)
	)
	(zone
		(net 255)
		(net_name "/Power/+3V3_OUT")
		(layer "F.Cu")
		(hatch edge 0.5)
		(priority 37)
		(connect_pads yes
			(clearance 0.15)
		)
		(min_thickness 0.25)
		(filled_areas_thickness no)
		(fill yes
			(thermal_gap 0.5)
			(thermal_bridge_width 0.5)
			(smoothing fillet)
			(radius 0.2)
		)
		(polygon
			(pts
				(xy 75.549999 86.379998) (xy 75.549999 83.979998) (xy 68.799999 83.979998) (xy 68.799999 86.379998)
			)
		)
	)
	(zone
		(net 9)
		(net_name "VCCD")
		(layer "F.Cu")
		(hatch edge 0.5)
		(priority 28)
		(connect_pads yes
			(clearance 0.15)
		)
		(min_thickness 0.15)
		(filled_areas_thickness no)
		(fill yes
			(thermal_gap 0.5)
			(thermal_bridge_width 0.5)
			(smoothing fillet)
			(radius 0.2)
		)
		(polygon
			(pts
				(xy 63.35 84.7) (xy 64.5 84.7) (xy 64.5 86.15) (xy 63.7 86.15) (xy 63.7 89.75) (xy 66.5 89.75) (xy 66.5 81.45)
				(xy 63.35 81.45)
			)
		)
	)
	(zone
		(net 28)
		(net_name "GND")
		(layer "F.Cu")
		(hatch edge 0.5)
		(priority 42)
		(connect_pads yes
			(clearance 0.15)
		)
		(min_thickness 0.25)
		(filled_areas_thickness no)
		(fill yes
			(thermal_gap 0.5)
			(thermal_bridge_width 0.5)
			(smoothing fillet)
			(radius 0.2)
		)
		(polygon
			(pts
				(xy 68.21 57.97) (xy 68.21 60.67) (xy 68.61 61.07) (xy 68.61 63.12) (xy 70.46 63.12) (xy 70.46 61.07)
				(xy 70.01 60.62) (xy 70.01 57.97)
			)
		)
	)
	(zone
		(net 155)
		(net_name "Net-(U9H-SVR_IND)")
		(layer "F.Cu")
		(hatch edge 0.5)
		(priority 4)
		(connect_pads yes
			(clearance 0.15)
		)
		(min_thickness 0.25)
		(filled_areas_thickness no)
		(fill yes
			(thermal_gap 0.15)
			(thermal_bridge_width 0.25)
			(smoothing fillet)
			(radius 0.3)
		)
		(polygon
			(pts
				(xy 94.4 95.6) (xy 96.75 95.6) (xy 96.85 95.7) (xy 96.95 95.8) (xy 96.95 96.15) (xy 98.45 96.15)
				(xy 98.449999 92.65) (xy 96.950011 92.65) (xy 96.949999 93.25) (xy 95.3 94.9) (xy 94.4 94.9)
			)
		)
	)
	(zone
		(net 302)
		(net_name "+1V0")
		(layer "F.Cu")
		(hatch edge 0.5)
		(priority 33)
		(connect_pads yes
			(clearance 0.15)
		)
		(min_thickness 0.25)
		(filled_areas_thickness no)
		(fill yes
			(thermal_gap 0.5)
			(thermal_bridge_width 0.5)
			(smoothing fillet)
			(radius 0.2)
		)
		(polygon
			(pts
				(xy 67.2 116.2) (xy 67.2 103.7) (xy 68.45 103.7) (xy 68.45 105) (xy 69.8 105) (xy 69.8 99.65) (xy 68.45 99.65)
				(xy 68.45 100.95) (xy 67.35 100.95) (xy 67.35 100.45) (xy 64.65 100.45) (xy 64.65 101.7) (xy 63.5 101.7)
				(xy 63.5 107.8) (xy 64.65 107.8) (xy 64.65 116.2)
			)
		)
	)
	(zone
		(net 28)
		(net_name "GND")
		(layer "F.Cu")
		(hatch edge 0.5)
		(priority 40)
		(connect_pads yes
			(clearance 0.15)
		)
		(min_thickness 0.15)
		(filled_areas_thickness no)
		(fill yes
			(thermal_gap 0.5)
			(thermal_bridge_width 0.5)
			(smoothing fillet)
			(radius 0.2)
		)
		(polygon
			(pts
				(xy 69.2 99.45) (xy 71.9 99.45) (xy 71.9 100.7) (xy 73 100.7) (xy 73 98.45) (xy 69.2 98.45)
			)
		)
	)
	(zone
		(net 10)
		(net_name "AVDDH")
		(layer "F.Cu")
		(hatch edge 0.5)
		(priority 40)
		(connect_pads yes
			(clearance 0.15)
		)
		(min_thickness 0.15)
		(filled_areas_thickness no)
		(fill yes
			(thermal_gap 0.5)
			(thermal_bridge_width 0.5)
			(smoothing fillet)
			(radius 0.2)
		)
		(polygon
			(pts
				(xy 69.2 98.25) (xy 73 98.25) (xy 73 97.15) (xy 69.2 97.15)
			)
		)
	)
	(zone
		(net 7)
		(net_name "+3V3")
		(layer "F.Cu")
		(hatch edge 0.5)
		(priority 46)
		(connect_pads yes
			(clearance 0.15)
		)
		(min_thickness 0.25)
		(filled_areas_thickness no)
		(fill yes
			(thermal_gap 0.5)
			(thermal_bridge_width 0.5)
			(smoothing fillet)
			(radius 0.2)
		)
		(polygon
			(pts
				(xy 77.05 86.65) (xy 77.05 88.4) (xy 74.3 88.4) (xy 74.3 86.65) (xy 75.8 86.65) (xy 75.8 80.25)
				(xy 77.05 80.25)
			)
		)
	)
	(zone
		(net 18)
		(net_name "+1V88")
		(layer "F.Cu")
		(hatch edge 0.5)
		(priority 21)
		(connect_pads yes
			(clearance 0.15)
		)
		(min_thickness 0.25)
		(filled_areas_thickness no)
		(fill yes
			(thermal_gap 0.5)
			(thermal_bridge_width 0.5)
			(smoothing fillet)
			(radius 0.2)
		)
		(polygon
			(pts
				(xy 69 99.45) (xy 69 94.7) (xy 63.5 94.7) (xy 63.5 100.1) (xy 67.05 100.1) (xy 67.7 99.45)
			)
		)
	)
	(zone
		(net 300)
		(net_name "/2xRJ45/P1_CT")
		(layer "B.Cu")
		(hatch edge 0.5)
		(priority 52)
		(connect_pads yes
			(clearance 0.15)
		)
		(min_thickness 0.25)
		(filled_areas_thickness no)
		(fill yes
			(thermal_gap 0.5)
			(thermal_bridge_width 0.5)
			(smoothing fillet)
			(radius 0.2)
		)
		(polygon
			(pts
				(xy 101.349979 129.05) (xy 101.349979 131.6) (xy 100.299979 131.6) (xy 100.299979 133.95) (xy 91.649979 133.95)
				(xy 91.649979 131.6) (xy 90.599979 131.6) (xy 90.599979 129.05) (xy 88.099979 129.05) (xy 88.099979 135.85)
				(xy 103.849979 135.85) (xy 103.849979 129.05)
			)
		)
	)
	(zone
		(net 9)
		(net_name "VCCD")
		(layer "B.Cu")
		(hatch edge 0.5)
		(priority 5)
		(connect_pads yes
			(clearance 0.15)
		)
		(min_thickness 0.25)
		(filled_areas_thickness no)
		(fill yes
			(thermal_gap 0.15)
			(thermal_bridge_width 0.25)
			(smoothing fillet)
			(radius 0.2)
		)
		(polygon
			(pts
				(xy 84.85 98.25) (xy 89.6 98.25) (xy 89.6 97.45) (xy 84.85 97.45)
			)
		)
	)
	(zone
		(net 9)
		(net_name "VCCD")
		(layer "B.Cu")
		(hatch edge 0.5)
		(priority 5)
		(connect_pads yes
			(clearance 0.15)
		)
		(min_thickness 0.25)
		(filled_areas_thickness no)
		(fill yes
			(thermal_gap 0.15)
			(thermal_bridge_width 0.25)
			(smoothing fillet)
			(radius 0.2)
		)
		(polygon
			(pts
				(xy 84.85 101.9) (xy 86.6 101.9) (xy 86.6 101.1) (xy 84.85 101.1)
			)
		)
	)
	(zone
		(net 28)
		(net_name "GND")
		(layer "B.Cu")
		(hatch edge 0.5)
		(priority 19)
		(connect_pads yes
			(clearance 0.15)
		)
		(min_thickness 0.25)
		(filled_areas_thickness no)
		(fill yes
			(thermal_gap 0.5)
			(thermal_bridge_width 0.5)
			(smoothing fillet)
			(radius 0.2)
		)
		(polygon
			(pts
				(xy 107.955 92.505) (xy 105.315 92.505) (xy 105.315 96.22) (xy 107.955 96.22)
			)
		)
	)
	(zone
		(net 1)
		(net_name "VCCA")
		(layer "B.Cu")
		(hatch edge 0.5)
		(priority 5)
		(connect_pads yes
			(clearance 0.15)
		)
		(min_thickness 0.25)
		(filled_areas_thickness no)
		(fill yes
			(thermal_gap 0.15)
			(thermal_bridge_width 0.25)
			(smoothing fillet)
			(radius 0.2)
		)
		(polygon
			(pts
				(xy 84.85 94.6) (xy 89.6 94.6) (xy 89.6 93.8) (xy 84.85 93.8)
			)
		)
	)
	(zone
		(net 28)
		(net_name "GND")
		(layer "B.Cu")
		(hatch edge 0.5)
		(priority 56)
		(connect_pads yes
			(clearance 0.15)
		)
		(min_thickness 0.25)
		(filled_areas_thickness no)
		(fill yes
			(thermal_gap 0.5)
			(thermal_bridge_width 0.5)
			(smoothing fillet)
			(radius 0.2)
		)
		(polygon
			(pts
				(xy 77.1 101.7) (xy 77.75 101.7) (xy 77.75 100) (xy 77.1 100)
			)
		)
	)
	(zone
		(net 28)
		(net_name "GND")
		(layer "B.Cu")
		(hatch edge 0.5)
		(priority 13)
		(connect_pads yes
			(clearance 0.15)
		)
		(min_thickness 0.25)
		(filled_areas_thickness no)
		(fill yes
			(thermal_gap 0.5)
			(thermal_bridge_width 0.5)
			(smoothing fillet)
			(radius 0.2)
		)
		(polygon
			(pts
				(xy 83.96 105.91) (xy 80.84 105.91) (xy 80.84 106.92) (xy 79.92 106.92) (xy 79.92 107.76) (xy 79.17 107.76)
				(xy 79.17 107.04) (xy 78.94 106.81) (xy 78.94 105.91) (xy 74.95 105.91) (xy 74.95 107.1) (xy 78.01 107.1)
				(xy 78.01 107.74) (xy 73.25 107.74) (xy 73.25 106.26) (xy 74.5 106.26) (xy 74.5 105.86) (xy 74.5 105.23)
				(xy 83.96 105.23)
			)
		)
	)
	(zone
		(net 28)
		(net_name "GND")
		(layer "B.Cu")
		(hatch edge 0.5)
		(priority 14)
		(connect_pads yes
			(clearance 0.15)
		)
		(min_thickness 0.25)
		(filled_areas_thickness no)
		(fill yes
			(thermal_gap 0.5)
			(thermal_bridge_width 0.5)
			(smoothing fillet)
			(radius 0.2)
		)
		(polygon
			(pts
				(xy 81.11 107.76) (xy 81.11 107.05) (xy 84.955 107.05) (xy 84.955 107.76)
			)
		)
	)
	(zone
		(net 6)
		(net_name "DVDD")
		(layer "B.Cu")
		(hatch edge 0.5)
		(priority 16)
		(connect_pads yes
			(clearance 0.15)
		)
		(min_thickness 0.25)
		(filled_areas_thickness no)
		(fill yes
			(thermal_gap 0.5)
			(thermal_bridge_width 0.5)
			(smoothing fillet)
			(radius 0.2)
		)
		(polygon
			(pts
				(xy 82.62 104.99) (xy 77.99 104.99) (xy 77.99 104.28) (xy 82.62 104.28)
			)
		)
	)
	(zone
		(net 10)
		(net_name "AVDDH")
		(layer "B.Cu")
		(hatch edge 0.5)
		(priority 12)
		(connect_pads yes
			(clearance 0.15)
		)
		(min_thickness 0.25)
		(filled_areas_thickness no)
		(fill yes
			(thermal_gap 0.5)
			(thermal_bridge_width 0.5)
			(smoothing fillet)
			(radius 0.2)
		)
		(polygon
			(pts
				(xy 78.74 106.94) (xy 77 106.94) (xy 77 106.12) (xy 78.74 106.12)
			)
		)
	)
	(zone
		(net 28)
		(net_name "GND")
		(layer "B.Cu")
		(hatch edge 0.5)
		(priority 5)
		(connect_pads yes
			(clearance 0.15)
		)
		(min_thickness 0.25)
		(filled_areas_thickness no)
		(fill yes
			(thermal_gap 0.15)
			(thermal_bridge_width 0.25)
			(smoothing fillet)
			(radius 0.2)
		)
		(polygon
			(pts
				(xy 84.85 100.95) (xy 91.6 100.95) (xy 91.6 100.2) (xy 84.85 100.2)
			)
		)
	)
	(zone
		(net 9)
		(net_name "VCCD")
		(layer "B.Cu")
		(hatch edge 0.5)
		(priority 5)
		(connect_pads yes
			(clearance 0.15)
		)
		(min_thickness 0.25)
		(filled_areas_thickness no)
		(fill yes
			(thermal_gap 0.15)
			(thermal_bridge_width 0.25)
			(smoothing fillet)
			(radius 0.2)
		)
		(polygon
			(pts
				(xy 85.85 96.45) (xy 90.6 96.45) (xy 90.6 95.65) (xy 85.85 95.65)
			)
		)
	)
	(zone
		(net 5)
		(net_name "P0_AVDDL")
		(layer "B.Cu")
		(hatch edge 0.5)
		(priority 9)
		(connect_pads yes
			(clearance 0.15)
		)
		(min_thickness 0.25)
		(filled_areas_thickness no)
		(fill yes
			(thermal_gap 0.5)
			(thermal_bridge_width 0.5)
			(smoothing fillet)
			(radius 0.2)
		)
		(polygon
			(pts
				(xy 75.47 108.69) (xy 75.47 107.93) (xy 79.73 107.93) (xy 79.73 108.69)
			)
		)
	)
	(zone
		(net 28)
		(net_name "GND")
		(layer "B.Cu")
		(hatch edge 0.5)
		(priority 44)
		(connect_pads yes
			(clearance 0.15)
		)
		(min_thickness 0.25)
		(filled_areas_thickness no)
		(fill yes
			(thermal_gap 0.5)
			(thermal_bridge_width 0.5)
		)
		(polygon
			(pts
				(xy 63.9 105.75) (xy 66.65 105.75) (xy 66.65 104.55) (xy 72.9 104.55) (xy 72.9 98.65) (xy 63.9 98.65)
			)
		)
	)
	(zone
		(net 6)
		(net_name "DVDD")
		(layer "B.Cu")
		(hatch edge 0.5)
		(priority 45)
		(connect_pads yes
			(clearance 0.15)
		)
		(min_thickness 0.25)
		(filled_areas_thickness no)
		(fill yes
			(thermal_gap 0.5)
			(thermal_bridge_width 0.5)
			(smoothing fillet)
			(radius 0.2)
		)
		(polygon
			(pts
				(xy 63.9 96.6) (xy 66.6 96.6) (xy 66.6 90.1) (xy 63.9 90.1)
			)
		)
	)
	(zone
		(net 18)
		(net_name "+1V88")
		(layer "B.Cu")
		(hatch edge 0.5)
		(priority 55)
		(connect_pads yes
			(clearance 0.15)
		)
		(min_thickness 0.25)
		(filled_areas_thickness no)
		(fill yes
			(thermal_gap 0.5)
			(thermal_bridge_width 0.5)
			(smoothing fillet)
			(radius 0.2)
		)
		(polygon
			(pts
				(xy 83.35 127.7) (xy 87.4 127.7) (xy 87.4 127.6) (xy 84.9 125.1) (xy 83.35 125.1)
			)
		)
	)
	(zone
		(net 299)
		(net_name "/2xRJ45/P0_CT")
		(layer "B.Cu")
		(hatch edge 0.5)
		(priority 52)
		(connect_pads yes
			(clearance 0.15)
		)
		(min_thickness 0.25)
		(filled_areas_thickness no)
		(fill yes
			(thermal_gap 0.5)
			(thermal_bridge_width 0.5)
			(smoothing fillet)
			(radius 0.2)
		)
		(polygon
			(pts
				(xy 68.600021 129.05) (xy 68.600021 131.6) (xy 69.650021 131.6) (xy 69.650021 133.95) (xy 78.300021 133.95)
				(xy 78.300021 131.6) (xy 79.350021 131.6) (xy 79.350021 129.05) (xy 81.850021 129.05) (xy 81.850021 135.85)
				(xy 66.100021 135.85) (xy 66.100021 129.05)
			)
		)
	)
	(zone
		(net 28)
		(net_name "GND")
		(layer "B.Cu")
		(hatch edge 0.5)
		(priority 53)
		(connect_pads yes
			(clearance 0.15)
		)
		(min_thickness 0.25)
		(filled_areas_thickness no)
		(fill yes
			(thermal_gap 0.5)
			(thermal_bridge_width 0.5)
			(smoothing fillet)
			(radius 0.2)
		)
		(polygon
			(pts
				(xy 83.2 128.85) (xy 83.2 125.1) (xy 79.35 125.1) (xy 79.35 128.85)
			)
		)
	)
	(zone
		(net 28)
		(net_name "GND")
		(layer "B.Cu")
		(hatch edge 0.5)
		(priority 19)
		(connect_pads yes
			(clearance 0.15)
		)
		(min_thickness 0.25)
		(filled_areas_thickness no)
		(fill yes
			(thermal_gap 0.5)
			(thermal_bridge_width 0.5)
			(smoothing fillet)
			(radius 0.2)
		)
		(polygon
			(pts
				(xy 96.695 114.280001) (xy 96.695 111.640001) (xy 92.98 111.640001) (xy 92.98 114.280001)
			)
		)
	)
	(zone
		(net 28)
		(net_name "GND")
		(layer "B.Cu")
		(hatch edge 0.5)
		(priority 53)
		(connect_pads yes
			(clearance 0.15)
		)
		(min_thickness 0.25)
		(filled_areas_thickness no)
		(fill yes
			(thermal_gap 0.5)
			(thermal_bridge_width 0.5)
			(smoothing fillet)
			(radius 0.2)
		)
		(polygon
			(pts
				(xy 87.9 135.85) (xy 87.9 129.05) (xy 82.05 129.05) (xy 82.05 135.85)
			)
		)
	)
	(zone
		(net 10)
		(net_name "AVDDH")
		(layer "B.Cu")
		(hatch edge 0.5)
		(priority 15)
		(connect_pads yes
			(clearance 0.15)
		)
		(min_thickness 0.25)
		(filled_areas_thickness no)
		(fill yes
			(thermal_gap 0.5)
			(thermal_bridge_width 0.5)
			(smoothing fillet)
			(radius 0.2)
		)
		(polygon
			(pts
				(xy 82.85 106.07) (xy 82.85 106.92) (xy 82.84 106.93) (xy 81.18 106.93) (xy 80.95 107.16) (xy 80.95 107.76)
				(xy 80.1 107.76) (xy 80.1 106.97) (xy 80.71 106.97) (xy 81 106.68) (xy 81 106.07)
			)
		)
	)
	(zone
		(net 28)
		(net_name "GND")
		(layer "B.Cu")
		(hatch edge 0.5)
		(priority 17)
		(connect_pads yes
			(clearance 0.15)
		)
		(min_thickness 0.25)
		(filled_areas_thickness no)
		(fill yes
			(thermal_gap 0.5)
			(thermal_bridge_width 0.5)
			(smoothing fillet)
			(radius 0.2)
		)
		(polygon
			(pts
				(xy 82.95 104.12) (xy 76.5 104.12) (xy 76.5 103.41) (xy 82.95 103.41)
			)
		)
	)
	(zone
		(net 28)
		(net_name "GND")
		(layer "B.Cu")
		(hatch edge 0.5)
		(priority 53)
		(connect_pads yes
			(clearance 0.15)
		)
		(min_thickness 0.25)
		(filled_areas_thickness no)
		(fill yes
			(thermal_gap 0.5)
			(thermal_bridge_width 0.5)
			(smoothing fillet)
			(radius 0.2)
		)
		(polygon
			(pts
				(xy 106.15 135.85) (xy 106.15 129.05) (xy 104.05 129.05) (xy 104.05 135.85)
			)
		)
	)
	(zone
		(net 28)
		(net_name "GND")
		(layer "B.Cu")
		(hatch edge 0.5)
		(priority 53)
		(connect_pads yes
			(clearance 0.15)
		)
		(min_thickness 0.25)
		(filled_areas_thickness no)
		(fill yes
			(thermal_gap 0.5)
			(thermal_bridge_width 0.5)
			(smoothing fillet)
			(radius 0.2)
		)
		(polygon
			(pts
				(xy 65.9 135.85) (xy 65.9 129.05) (xy 63.8 129.05) (xy 63.8 135.85)
			)
		)
	)
	(zone
		(net 12)
		(net_name "XFI_VDD")
		(layer "B.Cu")
		(hatch edge 0.5)
		(priority 18)
		(connect_pads yes
			(clearance 0.15)
		)
		(min_thickness 0.25)
		(filled_areas_thickness no)
		(fill yes
			(thermal_gap 0.5)
			(thermal_bridge_width 0.5)
			(smoothing fillet)
			(radius 0.2)
		)
		(polygon
			(pts
				(xy 82.56 102.42) (xy 79.89 102.42) (xy 79.89 103.25) (xy 82.56 103.25)
			)
		)
	)
	(zone
		(net 18)
		(net_name "+1V88")
		(layer "B.Cu")
		(hatch edge 0.5)
		(priority 56)
		(connect_pads yes
			(clearance 0.15)
		)
		(min_thickness 0.25)
		(filled_areas_thickness no)
		(fill yes
			(thermal_gap 0.5)
			(thermal_bridge_width 0.5)
			(smoothing fillet)
			(radius 0.2)
		)
		(polygon
			(pts
				(xy 76.15 101.7) (xy 76.8 101.7) (xy 76.8 100) (xy 76.15 100)
			)
		)
	)
	(zone
		(net 28)
		(net_name "GND")
		(layer "B.Cu")
		(hatch edge 0.5)
		(priority 5)
		(connect_pads yes
			(clearance 0.15)
		)
		(min_thickness 0.25)
		(filled_areas_thickness no)
		(fill yes
			(thermal_gap 0.15)
			(thermal_bridge_width 0.25)
			(smoothing fillet)
			(radius 0.2)
		)
		(polygon
			(pts
				(xy 84.85 97.3) (xy 90.7 97.3) (xy 90.7 96.6) (xy 84.85 96.6)
			)
		)
	)
	(zone
		(net 1)
		(net_name "VCCA")
		(layer "B.Cu")
		(hatch edge 0.5)
		(priority 5)
		(connect_pads yes
			(clearance 0.15)
		)
		(min_thickness 0.25)
		(filled_areas_thickness no)
		(fill yes
			(thermal_gap 0.15)
			(thermal_bridge_width 0.25)
			(smoothing fillet)
			(radius 0.2)
		)
		(polygon
			(pts
				(xy 86.85 101.9) (xy 90.65 101.9) (xy 90.65 101.1) (xy 86.85 101.1)
			)
		)
	)
	(zone
		(net 18)
		(net_name "+1V88")
		(layer "B.Cu")
		(hatch edge 0.5)
		(priority 57)
		(connect_pads yes
			(clearance 0.15)
		)
		(min_thickness 0.25)
		(filled_areas_thickness no)
		(fill yes
			(thermal_gap 0.5)
			(thermal_bridge_width 0.5)
			(smoothing fillet)
			(radius 0.2)
		)
		(polygon
			(pts
				(xy 67.45 98.25) (xy 68.95 98.25) (xy 68.95 94.75) (xy 67.45 94.75)
			)
		)
	)
	(zone
		(net 302)
		(net_name "+1V0")
		(layer "B.Cu")
		(hatch edge 0.5)
		(priority 11)
		(connect_pads yes
			(clearance 0.15)
		)
		(min_thickness 0.25)
		(filled_areas_thickness no)
		(fill yes
			(thermal_gap 0.5)
			(thermal_bridge_width 0.5)
			(smoothing fillet)
			(radius 0.2)
		)
		(polygon
			(pts
				(xy 72.9 104.8) (xy 72.9 107.75) (xy 70.65 107.75) (xy 66.5 111.9) (xy 63.66 111.9) (xy 63.66 106)
				(xy 66.9 106) (xy 66.9 104.8)
			)
		)
	)
	(zone
		(net 9)
		(net_name "VCCD")
		(layer "B.Cu")
		(hatch edge 0.5)
		(priority 5)
		(connect_pads yes
			(clearance 0.15)
		)
		(min_thickness 0.25)
		(filled_areas_thickness no)
		(fill yes
			(thermal_gap 0.15)
			(thermal_bridge_width 0.25)
			(smoothing fillet)
			(radius 0.2)
		)
		(polygon
			(pts
				(xy 84.85 100.1) (xy 87.65 100.1) (xy 87.65 99.3) (xy 84.85 99.3)
			)
		)
	)
	(zone
		(net 7)
		(net_name "+3V3")
		(layer "B.Cu")
		(hatch edge 0.5)
		(priority 5)
		(connect_pads yes
			(clearance 0.15)
		)
		(min_thickness 0.25)
		(filled_areas_thickness no)
		(fill yes
			(thermal_gap 0.15)
			(thermal_bridge_width 0.25)
			(smoothing fillet)
			(radius 0.2)
		)
		(polygon
			(pts
				(xy 90.85 101.9) (xy 92.6 101.9) (xy 92.6 101.1) (xy 90.85 101.1)
			)
		)
	)
	(zone
		(net 7)
		(net_name "+3V3")
		(layer "B.Cu")
		(hatch edge 0.5)
		(priority 58)
		(connect_pads
			(clearance 0.15)
		)
		(min_thickness 0.25)
		(filled_areas_thickness no)
		(fill yes
			(thermal_gap 0.2)
			(thermal_bridge_width 0.3)
			(smoothing fillet)
			(radius 0.2)
		)
		(polygon
			(pts
				(xy 96.6 97.75) (xy 97.8 97.75) (xy 97.8 102.25) (xy 97.25 102.25) (xy 97.25 103.45) (xy 96.6 103.45)
			)
		)
	)
	(zone
		(net 301)
		(net_name "+1V88_CT")
		(layer "B.Cu")
		(hatch edge 0.5)
		(priority 54)
		(connect_pads yes
			(clearance 0.15)
		)
		(min_thickness 0.25)
		(filled_areas_thickness no)
		(fill yes
			(thermal_gap 0.5)
			(thermal_bridge_width 0.5)
			(smoothing fillet)
			(radius 0.2)
		)
		(polygon
			(pts
				(xy 82.05 130.8) (xy 87.9 130.8) (xy 87.9 127.9) (xy 83.35 127.9) (xy 83.35 129.05) (xy 82.05 129.05)
			)
		)
	)
	(zone
		(net 28)
		(net_name "GND")
		(layer "B.Cu")
		(hatch edge 0.5)
		(priority 5)
		(connect_pads yes
			(clearance 0.15)
		)
		(min_thickness 0.25)
		(filled_areas_thickness no)
		(fill yes
			(thermal_gap 0.15)
			(thermal_bridge_width 0.25)
			(smoothing fillet)
			(radius 0.2)
		)
		(polygon
			(pts
				(xy 84.85 103.25) (xy 91.65 103.25) (xy 91.65 103.8) (xy 92.6 103.8) (xy 92.6 102) (xy 84.85 102)
			)
		)
	)
	(zone
		(net 14)
		(net_name "P1_AVDDL")
		(layer "B.Cu")
		(hatch edge 0.5)
		(priority 10)
		(connect_pads yes
			(clearance 0.15)
		)
		(min_thickness 0.25)
		(filled_areas_thickness no)
		(fill yes
			(thermal_gap 0.5)
			(thermal_bridge_width 0.5)
			(smoothing fillet)
			(radius 0.2)
		)
		(polygon
			(pts
				(xy 81 107.93) (xy 81 108.69) (xy 85.65 108.69) (xy 85.65 107.93)
			)
		)
	)
	(zone
		(net 1)
		(net_name "VCCA")
		(layer "B.Cu")
		(hatch edge 0.5)
		(priority 5)
		(connect_pads yes
			(clearance 0.15)
		)
		(min_thickness 0.25)
		(filled_areas_thickness no)
		(fill yes
			(thermal_gap 0.15)
			(thermal_bridge_width 0.25)
			(smoothing fillet)
			(radius 0.2)
		)
		(polygon
			(pts
				(xy 87.85 100.1) (xy 90.65 100.1) (xy 90.65 99.3) (xy 87.85 99.3)
			)
		)
	)
	(zone
		(net 28)
		(net_name "GND")
		(layer "B.Cu")
		(hatch edge 0.5)
		(priority 5)
		(connect_pads yes
			(clearance 0.15)
		)
		(min_thickness 0.25)
		(filled_areas_thickness no)
		(fill yes
			(thermal_gap 0.15)
			(thermal_bridge_width 0.25)
			(smoothing fillet)
			(radius 0.2)
		)
		(polygon
			(pts
				(xy 81.8 95.5) (xy 90.8 95.5) (xy 90.8 96.35) (xy 91.6 96.35) (xy 91.6 94.75) (xy 81.8 94.75)
			)
		)
	)
	(zone
		(net 28)
		(net_name "GND")
		(layer "B.Cu")
		(hatch edge 0.5)
		(priority 5)
		(connect_pads yes
			(clearance 0.15)
		)
		(min_thickness 0.25)
		(filled_areas_thickness no)
		(fill yes
			(thermal_gap 0.15)
			(thermal_bridge_width 0.25)
			(smoothing fillet)
			(radius 0.2)
		)
		(polygon
			(pts
				(xy 84.85 99.15) (xy 90.7 99.15) (xy 90.7 98.45) (xy 84.85 98.45)
			)
		)
	)
	(zone
		(net 27)
		(net_name "PLL_VDD")
		(layer "B.Cu")
		(hatch edge 0.5)
		(priority 35)
		(connect_pads yes
			(clearance 0.125)
		)
		(min_thickness 0.125)
		(filled_areas_thickness no)
		(fill yes
			(thermal_gap 0.5)
			(thermal_bridge_width 0.5)
		)
		(polygon
			(pts
				(xy 76.4 104.2) (xy 73.85 104.2) (xy 73.25 104.8) (xy 73.25 106) (xy 74.35 106) (xy 74.35 105.65)
				(xy 75.2 105.65) (xy 75.2 104.95) (xy 76.4 104.95)
			)
		)
	)
	(zone
		(net 0)
		(net_name "")
		(layer "In1.Cu")
		(hatch edge 0.5)
		(connect_pads
			(clearance 0)
		)
		(min_thickness 0.25)
		(filled_areas_thickness no)
		(keepout
			(tracks not_allowed)
			(vias not_allowed)
			(pads not_allowed)
			(copperpour not_allowed)
			(footprints allowed)
		)
		(placement
			(enabled no)
			(sheetname "")
		)
		(fill
			(thermal_gap 0.5)
			(thermal_bridge_width 0.5)
		)
		(polygon
			(pts
				(xy 103.56 57.185) (xy 104.44 57.185) (xy 104.44 58.165) (xy 103.56 58.165)
			)
		)
	)
	(zone
		(net 0)
		(net_name "")
		(layer "In1.Cu")
		(hatch edge 0.5)
		(connect_pads
			(clearance 0)
		)
		(min_thickness 0.25)
		(filled_areas_thickness no)
		(keepout
			(tracks not_allowed)
			(vias not_allowed)
			(pads not_allowed)
			(copperpour not_allowed)
			(footprints allowed)
		)
		(placement
			(enabled no)
			(sheetname "")
		)
		(fill
			(thermal_gap 0.5)
			(thermal_bridge_width 0.5)
		)
		(polygon
			(pts
				(xy 103.06 54.995) (xy 103.94 54.995) (xy 103.94 55.975) (xy 103.06 55.975)
			)
		)
	)
	(zone
		(net 0)
		(net_name "")
		(layer "In1.Cu")
		(hatch edge 0.5)
		(connect_pads
			(clearance 0)
		)
		(min_thickness 0.25)
		(filled_areas_thickness no)
		(keepout
			(tracks not_allowed)
			(vias not_allowed)
			(pads not_allowed)
			(copperpour not_allowed)
			(footprints allowed)
		)
		(placement
			(enabled no)
			(sheetname "")
		)
		(fill
			(thermal_gap 0.5)
			(thermal_bridge_width 0.5)
		)
		(polygon
			(pts
				(xy 95.56 55.005) (xy 96.44 55.005) (xy 96.44 55.985) (xy 95.56 55.985)
			)
		)
	)
	(zone
		(net 0)
		(net_name "")
		(layer "In1.Cu")
		(hatch edge 0.5)
		(connect_pads
			(clearance 0)
		)
		(min_thickness 0.25)
		(filled_areas_thickness no)
		(keepout
			(tracks not_allowed)
			(vias not_allowed)
			(pads not_allowed)
			(copperpour not_allowed)
			(footprints allowed)
		)
		(placement
			(enabled no)
			(sheetname "")
		)
		(fill
			(thermal_gap 0.5)
			(thermal_bridge_width 0.5)
		)
		(polygon
			(pts
				(xy 101.56 55.005) (xy 102.44 55.005) (xy 102.44 55.985) (xy 101.56 55.985)
			)
		)
	)
	(zone
		(net 0)
		(net_name "")
		(layer "In1.Cu")
		(hatch edge 0.5)
		(connect_pads
			(clearance 0)
		)
		(min_thickness 0.25)
		(filled_areas_thickness no)
		(keepout
			(tracks not_allowed)
			(vias not_allowed)
			(pads not_allowed)
			(copperpour not_allowed)
			(footprints allowed)
		)
		(placement
			(enabled no)
			(sheetname "")
		)
		(fill
			(thermal_gap 0.5)
			(thermal_bridge_width 0.5)
		)
		(polygon
			(pts
				(xy 95.6 64.435) (xy 97.39 64.435) (xy 97.39 66.135) (xy 95.6 66.135)
			)
		)
	)
	(zone
		(net 0)
		(net_name "")
		(layer "In1.Cu")
		(hatch edge 0.5)
		(connect_pads
			(clearance 0)
		)
		(min_thickness 0.25)
		(filled_areas_thickness no)
		(keepout
			(tracks not_allowed)
			(vias not_allowed)
			(pads not_allowed)
			(copperpour not_allowed)
			(footprints allowed)
		)
		(placement
			(enabled no)
			(sheetname "")
		)
		(fill
			(thermal_gap 0.5)
			(thermal_bridge_width 0.5)
		)
		(polygon
			(pts
				(xy 102.060792 57.185) (xy 102.940792 57.185) (xy 102.940792 58.165) (xy 102.060792 58.165)
			)
		)
	)
	(zone
		(net 0)
		(net_name "")
		(layer "In1.Cu")
		(hatch edge 0.5)
		(connect_pads
			(clearance 0)
		)
		(min_thickness 0.25)
		(filled_areas_thickness no)
		(keepout
			(tracks not_allowed)
			(vias not_allowed)
			(pads not_allowed)
			(copperpour not_allowed)
			(footprints allowed)
		)
		(placement
			(enabled no)
			(sheetname "")
		)
		(fill
			(thermal_gap 0.5)
			(thermal_bridge_width 0.5)
		)
		(polygon
			(pts
				(xy 97.1 61.935) (xy 98.89 61.935) (xy 98.89 63.635) (xy 97.1 63.635)
			)
		)
	)
	(zone
		(net 0)
		(net_name "")
		(layer "In1.Cu")
		(hatch edge 0.5)
		(connect_pads
			(clearance 0)
		)
		(min_thickness 0.25)
		(filled_areas_thickness no)
		(keepout
			(tracks not_allowed)
			(vias not_allowed)
			(pads not_allowed)
			(copperpour not_allowed)
			(footprints allowed)
		)
		(placement
			(enabled no)
			(sheetname "")
		)
		(fill
			(thermal_gap 0.5)
			(thermal_bridge_width 0.5)
		)
		(polygon
			(pts
				(xy 97.06 55.005) (xy 97.94 55.005) (xy 97.94 55.985) (xy 97.06 55.985)
			)
		)
	)
	(zone
		(net 0)
		(net_name "")
		(layer "In1.Cu")
		(hatch edge 0.5)
		(connect_pads
			(clearance 0)
		)
		(min_thickness 0.25)
		(filled_areas_thickness no)
		(keepout
			(tracks not_allowed)
			(vias not_allowed)
			(pads not_allowed)
			(copperpour not_allowed)
			(footprints allowed)
		)
		(placement
			(enabled no)
			(sheetname "")
		)
		(fill
			(thermal_gap 0.5)
			(thermal_bridge_width 0.5)
		)
		(polygon
			(pts
				(xy 101.61 64.435) (xy 103.4 64.435) (xy 103.4 66.135) (xy 101.61 66.135)
			)
		)
	)
	(zone
		(net 0)
		(net_name "")
		(layer "In1.Cu")
		(hatch edge 0.5)
		(connect_pads
			(clearance 0)
		)
		(min_thickness 0.25)
		(filled_areas_thickness no)
		(keepout
			(tracks not_allowed)
			(vias not_allowed)
			(pads not_allowed)
			(copperpour not_allowed)
			(footprints allowed)
		)
		(placement
			(enabled no)
			(sheetname "")
		)
		(fill
			(thermal_gap 0.5)
			(thermal_bridge_width 0.5)
		)
		(polygon
			(pts
				(xy 97.56 57.185) (xy 98.44 57.185) (xy 98.44 58.165) (xy 97.56 58.165)
			)
		)
	)
	(zone
		(net 0)
		(net_name "")
		(layer "In1.Cu")
		(hatch edge 0.5)
		(connect_pads
			(clearance 0)
		)
		(min_thickness 0.25)
		(filled_areas_thickness no)
		(keepout
			(tracks not_allowed)
			(vias not_allowed)
			(pads not_allowed)
			(copperpour not_allowed)
			(footprints allowed)
		)
		(placement
			(enabled no)
			(sheetname "")
		)
		(fill
			(thermal_gap 0.5)
			(thermal_bridge_width 0.5)
		)
		(polygon
			(pts
				(xy 99.06 57.185) (xy 99.94 57.185) (xy 99.94 58.165) (xy 99.06 58.165)
			)
		)
	)
	(zone
		(net 0)
		(net_name "")
		(layer "In1.Cu")
		(hatch edge 0.5)
		(connect_pads
			(clearance 0)
		)
		(min_thickness 0.25)
		(filled_areas_thickness no)
		(keepout
			(tracks not_allowed)
			(vias not_allowed)
			(pads not_allowed)
			(copperpour not_allowed)
			(footprints allowed)
		)
		(placement
			(enabled no)
			(sheetname "")
		)
		(fill
			(thermal_gap 0.5)
			(thermal_bridge_width 0.5)
		)
		(polygon
			(pts
				(xy 96.06 57.185347) (xy 96.94 57.185347) (xy 96.94 58.165347) (xy 96.06 58.165347)
			)
		)
	)
	(zone
		(net 0)
		(net_name "")
		(layer "In1.Cu")
		(hatch edge 0.5)
		(connect_pads
			(clearance 0)
		)
		(min_thickness 0.25)
		(filled_areas_thickness no)
		(keepout
			(tracks not_allowed)
			(vias not_allowed)
			(pads not_allowed)
			(copperpour not_allowed)
			(footprints allowed)
		)
		(placement
			(enabled no)
			(sheetname "")
		)
		(fill
			(thermal_gap 0.5)
			(thermal_bridge_width 0.5)
		)
		(polygon
			(pts
				(xy 103.11 61.945) (xy 104.9 61.945) (xy 104.9 63.645) (xy 103.11 63.645)
			)
		)
	)
	(zone
		(net 28)
		(net_name "GND")
		(layers "In1.Cu" "In4.Cu" "In6.Cu")
		(name "INNER_GND")
		(hatch edge 0.5)
		(connect_pads yes
			(clearance 0.2)
		)
		(min_thickness 0.15)
		(filled_areas_thickness no)
		(fill yes
			(thermal_gap 0.2)
			(thermal_bridge_width 0.3)
		)
		(polygon
			(pts
				(xy 50 150) (xy 120 150) (xy 120 50) (xy 50 50)
			)
		)
	)
	(zone
		(net 10)
		(net_name "AVDDH")
		(layer "In2.Cu")
		(hatch edge 0.5)
		(priority 27)
		(connect_pads yes
			(clearance 0.2)
		)
		(min_thickness 0.15)
		(filled_areas_thickness no)
		(fill yes
			(thermal_gap 0.5)
			(thermal_bridge_width 0.5)
			(smoothing fillet)
			(radius 0.2)
		)
		(polygon
			(pts
				(xy 73.75 106.24) (xy 82.6 106.24) (xy 82.6 108.2) (xy 69.85 108.2) (xy 69.85 96.65) (xy 73.75 96.65)
			)
		)
	)
	(zone
		(net 18)
		(net_name "+1V88")
		(layer "In2.Cu")
		(name "INNER_GND")
		(hatch edge 0.5)
		(priority 29)
		(connect_pads yes
			(clearance 0.2)
		)
		(min_thickness 0.15)
		(filled_areas_thickness no)
		(fill yes
			(thermal_gap 0.2)
			(thermal_bridge_width 0.3)
			(smoothing fillet)
			(radius 0.2)
		)
		(polygon
			(pts
				(xy 83.75 106.1) (xy 74.05 106.1) (xy 74.05 96.35) (xy 69.6 96.35) (xy 69.6 98.25) (xy 67.36 98.25)
				(xy 67.36 93.55) (xy 77.35 93.55) (xy 77.35 102.55) (xy 82.5 102.55) (xy 83.75 103.8)
			)
		)
	)
	(zone
		(net 28)
		(net_name "GND")
		(layer "In2.Cu")
		(hatch edge 0.5)
		(priority 51)
		(connect_pads
			(clearance 0.15)
		)
		(min_thickness 0.25)
		(filled_areas_thickness no)
		(fill yes
			(thermal_gap 0.5)
			(thermal_bridge_width 0.5)
		)
		(polygon
			(pts
				(xy 94.84 53.665) (xy 105.42 53.665) (xy 105.42 66.695) (xy 104.92 67.195) (xy 95.47 67.195) (xy 94.84 66.565)
			)
		)
	)
	(zone
		(net 7)
		(net_name "+3V3")
		(layer "In2.Cu")
		(hatch edge 0.5)
		(priority 1)
		(connect_pads yes
			(clearance 0.2)
		)
		(min_thickness 0.2)
		(filled_areas_thickness no)
		(fill yes
			(thermal_gap 0.5)
			(thermal_bridge_width 0.5)
			(smoothing fillet)
			(radius 0.2)
		)
		(polygon
			(pts
				(xy 50 150) (xy 120 150) (xy 120 50) (xy 50 50)
			)
		)
	)
	(zone
		(net 1)
		(net_name "VCCA")
		(layer "In2.Cu")
		(hatch edge 0.5)
		(priority 36)
		(connect_pads yes
			(clearance 0.2)
		)
		(min_thickness 0.125)
		(filled_areas_thickness no)
		(fill yes
			(thermal_gap 0.5)
			(thermal_bridge_width 0.5)
			(smoothing fillet)
			(radius 0.2)
		)
		(polygon
			(pts
				(xy 84.9 94.65) (xy 89.41 94.65) (xy 90.07 93.99) (xy 90.6 93.99) (xy 90.6 98.23) (xy 88.52 98.23)
				(xy 86.975 99.775) (xy 86.975 101.53) (xy 90.45 101.53) (xy 91.06 100.92) (xy 91.41 100.92) (xy 92.29 101.8)
				(xy 97.95 101.8) (xy 97.95 102.45) (xy 102.5 102.45) (xy 102.5 96.25) (xy 96.65 90.4) (xy 84.9 90.4)
			)
		)
	)
	(zone
		(net 23)
		(net_name "XGB_AVDDH")
		(layer "In3.Cu")
		(hatch edge 0.5)
		(priority 61)
		(connect_pads yes
			(clearance 0.15)
		)
		(min_thickness 0.15)
		(filled_areas_thickness no)
		(fill yes
			(thermal_gap 0.5)
			(thermal_bridge_width 0.5)
			(smoothing fillet)
			(radius 0.2)
		)
		(polygon
			(pts
				(xy 69.5 94.45) (xy 72.01 94.45) (xy 72 99.6) (xy 71.65 99.86) (xy 71.65 103) (xy 74.61 105.96)
				(xy 79.1 105.96) (xy 79.1 107.83) (xy 70.2 107.83) (xy 70.2 95.65) (xy 69.5 95.65)
			)
		)
	)
	(zone
		(net 12)
		(net_name "XFI_VDD")
		(layer "In3.Cu")
		(hatch edge 0.5)
		(priority 26)
		(connect_pads yes
			(clearance 0.15)
		)
		(min_thickness 0.25)
		(filled_areas_thickness no)
		(fill yes
			(thermal_gap 0.5)
			(thermal_bridge_width 0.5)
		)
		(polygon
			(pts
				(xy 71.9 99.85) (xy 71.9 103.75) (xy 81.84 103.75) (xy 82.47 103.12) (xy 82.47 102.81) (xy 79.51 99.85)
			)
		)
	)
	(zone
		(net 28)
		(net_name "GND")
		(layer "In3.Cu")
		(hatch edge 0.5)
		(priority 31)
		(connect_pads
			(clearance 0.5)
		)
		(min_thickness 0.25)
		(filled_areas_thickness no)
		(fill yes
			(thermal_gap 0.5)
			(thermal_bridge_width 0.5)
		)
		(polygon
			(pts
				(xy 50 118.45) (xy 63.95 118.45) (xy 63.95 128.05) (xy 64 128.1) (xy 108.05 128.1) (xy 108.05 108.2)
				(xy 120 108.2) (xy 120 150) (xy 50 150)
			)
		)
	)
	(zone
		(net 388)
		(net_name "/Fan controller/+5V")
		(layer "In3.Cu")
		(hatch edge 0.5)
		(priority 5)
		(connect_pads yes
			(clearance 0.15)
		)
		(min_thickness 0.25)
		(filled_areas_thickness no)
		(fill yes
			(thermal_gap 0.5)
			(thermal_bridge_width 0.5)
			(smoothing fillet)
			(radius 0.2)
		)
		(polygon
			(pts
				(xy 108.193586 107.9) (xy 108.193586 98.8) (xy 114.493586 98.8) (xy 114.493586 107.9)
			)
		)
	)
	(zone
		(net 314)
		(net_name "VCC")
		(layer "In3.Cu")
		(hatch edge 0.5)
		(priority 4)
		(connect_pads
			(clearance 0.15)
		)
		(min_thickness 0.2)
		(filled_areas_thickness no)
		(fill yes
			(thermal_gap 0.5)
			(thermal_bridge_width 0.5)
		)
		(polygon
			(pts
				(xy 120 107.9) (xy 108.193586 107.9) (xy 108.2 80.85) (xy 87.075 80.85) (xy 63.95 80.85) (xy 63.95 118)
				(xy 50 118) (xy 50 50) (xy 120 50)
			)
		)
	)
	(zone
		(net 6)
		(net_name "DVDD")
		(layer "In3.Cu")
		(name "INNER_GND")
		(hatch edge 0.5)
		(priority 32)
		(connect_pads yes
			(clearance 0.15)
		)
		(min_thickness 0.15)
		(filled_areas_thickness no)
		(fill yes
			(thermal_gap 0.2)
			(thermal_bridge_width 0.3)
			(smoothing fillet)
			(radius 0.2)
		)
		(polygon
			(pts
				(xy 64.5 90.05) (xy 64.5 94.05) (xy 72 94.05) (xy 72 99.6) (xy 79.58 99.6) (xy 82.7 102.72) (xy 82.7 103.2)
				(xy 81.85 104.05) (xy 71.9 104.05) (xy 71.9 107.05) (xy 84.55 107.05) (xy 84.55 90.05)
			)
		)
	)
	(zone
		(net 14)
		(net_name "P1_AVDDL")
		(layer "In3.Cu")
		(hatch edge 0.5)
		(priority 25)
		(connect_pads yes
			(clearance 0.15)
		)
		(min_thickness 0.25)
		(filled_areas_thickness no)
		(fill yes
			(thermal_gap 0.5)
			(thermal_bridge_width 0.5)
			(smoothing fillet)
			(radius 0.2)
		)
		(polygon
			(pts
				(xy 70.2 114.16) (xy 73.45 114.16) (xy 73.45 113.74) (xy 74.84 112.35) (xy 84.55 112.35) (xy 84.55 107.25)
				(xy 80.3 107.25) (xy 80.3 109.795042) (xy 79.43 110.69) (xy 70.2 110.69)
			)
		)
	)
	(zone
		(net 5)
		(net_name "P0_AVDDL")
		(layer "In3.Cu")
		(hatch edge 0.5)
		(priority 26)
		(connect_pads yes
			(clearance 0.15)
		)
		(min_thickness 0.25)
		(filled_areas_thickness no)
		(fill yes
			(thermal_gap 0.5)
			(thermal_bridge_width 0.5)
			(smoothing fillet)
			(radius 0.2)
		)
		(polygon
			(pts
				(xy 70.2 110.599998) (xy 79.305151 110.598519) (xy 80.15 109.754519) (xy 80.15 107.25) (xy 70.2 107.25)
			)
		)
	)
	(zone
		(net 9)
		(net_name "VCCD")
		(layer "In3.Cu")
		(hatch edge 0.5)
		(priority 30)
		(connect_pads
			(clearance 0.15)
		)
		(min_thickness 0.2)
		(filled_areas_thickness no)
		(fill yes
			(thermal_gap 0.5)
			(thermal_bridge_width 0.5)
			(smoothing fillet)
			(radius 0.2)
		)
		(polygon
			(pts
				(xy 64.5 89.7) (xy 84.9 89.7) (xy 84.9 102.41) (xy 92.2 102.41) (xy 92.2 81.35) (xy 64.5 81.35)
			)
		)
	)
	(zone
		(net 18)
		(net_name "+1V88")
		(layer "In3.Cu")
		(hatch edge 0.5)
		(priority 1)
		(connect_pads yes
			(clearance 0.15)
		)
		(min_thickness 0.21)
		(filled_areas_thickness no)
		(fill yes
			(thermal_gap 0.5)
			(thermal_bridge_width 0.5)
			(smoothing fillet)
			(radius 0.2)
		)
		(polygon
			(pts
				(xy 64.5 94.45) (xy 64.5 127.75) (xy 107.75 127.75) (xy 107.75 81.35) (xy 92.5 81.35) (xy 92.5 102.45)
				(xy 84.9 102.45) (xy 84.9 112.65) (xy 70 112.65) (xy 70 94.45)
			)
		)
	)
	(zone
		(net 28)
		(net_name "GND")
		(layer "In5.Cu")
		(hatch edge 0.5)
		(priority 38)
		(connect_pads
			(clearance 0.15)
		)
		(min_thickness 0.25)
		(filled_areas_thickness no)
		(fill yes
			(thermal_gap 0.5)
			(thermal_bridge_width 0.5)
		)
		(polygon
			(pts
				(xy 97.89 87.87) (xy 101.81 87.87) (xy 102.29 87.39) (xy 106.12 87.39) (xy 107.07 88.34) (xy 107.07 90.35)
				(xy 105.57 91.85) (xy 98.52 91.85) (xy 97.89 91.22)
			)
		)
	)
	(zone
		(net 0)
		(net_name "")
		(layer "In6.Cu")
		(hatch edge 0.5)
		(connect_pads
			(clearance 0)
		)
		(min_thickness 0.25)
		(filled_areas_thickness no)
		(keepout
			(tracks allowed)
			(vias allowed)
			(pads allowed)
			(copperpour not_allowed)
			(footprints allowed)
		)
		(placement
			(enabled no)
			(sheetname "")
		)
		(fill
			(thermal_gap 0.5)
			(thermal_bridge_width 0.5)
		)
		(polygon
			(pts
				(xy 100.32 88.908677) (xy 100.92 88.908677) (xy 100.92 90.473677) (xy 100.32 90.473677)
			)
		)
	)
	(zone
		(net 0)
		(net_name "")
		(layer "In6.Cu")
		(hatch edge 0.5)
		(connect_pads
			(clearance 0)
		)
		(min_thickness 0.25)
		(filled_areas_thickness no)
		(keepout
			(tracks allowed)
			(vias allowed)
			(pads allowed)
			(copperpour not_allowed)
			(footprints allowed)
		)
		(placement
			(enabled no)
			(sheetname "")
		)
		(fill
			(thermal_gap 0.5)
			(thermal_bridge_width 0.5)
		)
		(polygon
			(pts
				(xy 98.385 88.908677) (xy 99.935 88.908677) (xy 99.935 90.473677) (xy 98.385 90.473677)
			)
		)
	)
	(zone
		(net 0)
		(net_name "")
		(layer "In6.Cu")
		(hatch edge 0.5)
		(connect_pads
			(clearance 0)
		)
		(min_thickness 0.25)
		(filled_areas_thickness no)
		(keepout
			(tracks allowed)
			(vias allowed)
			(pads allowed)
			(copperpour not_allowed)
			(footprints allowed)
		)
		(placement
			(enabled no)
			(sheetname "")
		)
		(fill
			(thermal_gap 0.5)
			(thermal_bridge_width 0.5)
		)
		(polygon
			(pts
				(xy 101.34 88.908677) (xy 102.89 88.908677) (xy 102.89 90.473677) (xy 101.34 90.473677)
			)
		)
	)
)
